G04 ================== begin FILE IDENTIFICATION RECORD ==================*
G04 Layout Name:  15126-1b.brd*
G04 Film Name:    L2GND*
G04 File Format:  Gerber RS274X*
G04 File Origin:  Cadence Allegro 16.6-2015-S079*
G04 Origin Date:  Fri Feb 10 17:22:00 2017*
G04 *
G04 Layer:  VIA CLASS/L2GND*
G04 Layer:  PIN/L2GND*
G04 Layer:  ETCH/L2GND*
G04 Layer:  DRAWING FORMAT/LAYER_PCB_STORY*
G04 Layer:  DRAWING FORMAT/LAYER_L2GND*
G04 *
G04 Offset:    (0.00 0.00)*
G04 Mirror:    No*
G04 Mode:      Positive*
G04 Rotation:  0*
G04 FullContactRelief:  No*
G04 UndefLineWidth:     6.00*
G04 ================== end FILE IDENTIFICATION RECORD ====================*
%FSLAX35Y35*MOIN*%
%IR0*IPPOS*OFA0.00000B0.00000*MIA0B0*SFA1.00000B1.00000*%
%ADD12C,.02*%
%ADD40C,.03*%
%ADD28C,.031*%
%ADD10C,.022*%
%ADD23C,.05*%
%ADD21C,.06*%
%ADD29C,.052*%
%ADD13C,.034*%
%ADD17C,.071*%
%ADD16C,.044*%
%ADD37C,.045*%
%ADD26C,.054*%
%ADD22C,.018*%
%ADD38C,.055*%
%ADD25C,.064*%
%ADD20C,.028*%
%ADD14C,.046*%
%ADD32C,.047*%
%ADD24C,.056*%
%ADD19C,.039*%
%ADD18C,.057*%
%ADD34O,.041X.06*%
%AMMACRO36*
4,1,48,.0225,.036,
.026668,.035635,
.030708,.034553,
.0345,.032785,
.037927,.030385,
.040885,.027427,
.043285,.024,
.045053,.020208,
.046135,.016168,
.0465,.012,
.046135,.007832,
.045053,.003792,
.043285,0.0,
.040885,-.003427,
.037927,-.006385,
.0345,-.008785,
.030708,-.010553,
.026668,-.011635,
.0225,-.012,
.0015,-.012,
.001135,-.016168,
.000053,-.020208,
-.001715,-.024,
-.004115,-.027427,
-.007073,-.030385,
-.0105,-.032785,
-.014292,-.034553,
-.018332,-.035635,
-.0225,-.036,
-.026668,-.035635,
-.030708,-.034553,
-.0345,-.032785,
-.037927,-.030385,
-.040885,-.027427,
-.043285,-.024,
-.045053,-.020208,
-.046135,-.016168,
-.0465,-.012,
-.0465,.012,
-.046135,.016168,
-.045053,.020208,
-.043285,.024,
-.040885,.027427,
-.037927,.030385,
-.0345,.032785,
-.030708,.034553,
-.026668,.035635,
-.0225,.036,
.0225,.036,
0.0*
%
%ADD36MACRO36*%
%ADD30O,.07X.046*%
%ADD15C,.14*%
%ADD39O,.094X.048*%
%ADD11C,.238*%
%ADD31O,.098X.046*%
%ADD27C,.276*%
%ADD33O,.099X.048*%
%ADD41C,.01*%
%ADD42C,.025*%
%ADD43C,.016*%
%ADD44C,.006*%
%ADD45C,.008*%
%ADD46C,.00352*%
%ADD109R,.05948X.06858*%
%ADD112O,.07202X.12102*%
%ADD72C,.03004*%
%ADD94C,.04004*%
%ADD76C,.03204*%
%ADD111C,.06104*%
%ADD69C,.07004*%
%ADD96C,.08004*%
%ADD84C,.02604*%
%ADD80C,.06204*%
%ADD66C,.04404*%
%ADD87C,.07204*%
%ADD78C,.02704*%
%ADD108C,.05504*%
%ADD90C,.06404*%
%ADD49C,.02804*%
%ADD107C,.06504*%
%ADD93C,.04704*%
%ADD71C,.07404*%
%ADD48C,.05604*%
%ADD110C,.05506*%
%ADD105C,.05704*%
%ADD95C,.09304*%
%ADD79C,.07504*%
%ADD68C,.08404*%
%ADD63C,.04804*%
%ADD70C,.07604*%
%ADD106C,.06804*%
%ADD75C,.05904*%
%ADD65C,.08604*%
%ADD81C,.07804*%
%ADD58C,.06943*%
%ADD61C,.11211*%
%ADD91R,.02002X.05502*%
%ADD73C,.12104*%
%ADD64C,.11204*%
%ADD53R,.02202X.07102*%
%ADD62C,.261*%
%ADD83R,.02004X.05502*%
%ADD67C,.15004*%
%ADD52R,.02204X.07102*%
%ADD51O,.15402X.21902*%
%ADD47C,.11404*%
%ADD55R,.09004X.02004*%
%ADD89R,.02004X.05504*%
%ADD74R,.05504X.02004*%
%ADD60C,.11209*%
%ADD85R,.06104X.0317*%
%ADD50O,.15404X.21904*%
%ADD54C,.15504*%
%ADD86R,.06104X.03172*%
%ADD57C,.15506*%
%ADD92C,.28404*%
%ADD56R,.05152X.04702*%
%ADD101R,.05152X.09402*%
%ADD88R,.05152X.04704*%
%ADD82R,.05154X.04702*%
%ADD77C,.17804*%
%ADD59R,.05504X.05504*%
%ADD103R,.05152X.09404*%
%ADD102R,.05154X.09402*%
%ADD100R,.05152X.07902*%
%ADD104R,.05154X.09404*%
%ADD99R,.05154X.07902*%
%ADD97R,.05152X.07904*%
%ADD98R,.05154X.07904*%
G75*
%LPD*%
G75*
G36*
G01X1973300Y-60000D02*
X-19810D01*
Y-34500D01*
X1973300D01*
Y-60000D01*
G37*
G36*
G01X308012Y508085D02*
Y498881D01*
X319462Y487431D01*
Y462720D01*
X337008Y445174D01*
Y415467D01*
X338518Y413958D01*
Y384032D01*
X338382Y383986D01*
G03X337438Y382727I456J-1326D01*
G03X337999Y381536I1400J-68D01*
G02X338032Y380941I-250J-312D01*
G01X336490Y379400D01*
Y378496D01*
G02X335950Y378122I-400J0D01*
G03Y375496I-492J-1313D01*
G02X336490Y375122I140J-374D01*
G01Y370697D01*
G02X335950Y370323I-400J0D01*
G03Y367697I-492J-1313D01*
G02X336490Y367323I140J-374D01*
G01Y366796D01*
G02X335950Y366422I-400J0D01*
G03Y363796I-492J-1313D01*
G02X336490Y363422I140J-374D01*
G01Y363326D01*
X340030Y359787D01*
Y353496D01*
X341240Y352285D01*
Y350935D01*
X341454Y350722D01*
X341303Y350571D01*
X341297Y350566D01*
G03X340876Y349916I921J-1058D01*
G03X343163Y348473I1342J-408D01*
G02X343715Y348460I269J-295D01*
G01X344242Y347933D01*
X344222Y347828D01*
G03X344213Y347343I1376J-268D01*
G03X346967Y347256I1385J217D01*
G03X347000Y347551I-1369J303D01*
G02X347400Y347948I400J-3D01*
G01X350555D01*
G02X350955Y347551I0J-400D01*
G03X353759I1402J9D01*
G02X354159Y347948I400J-3D01*
G01X357315D01*
G02X357715Y347551I0J-400D01*
G03X360519I1402J9D01*
G02X360919Y347948I400J-3D01*
G01X364075D01*
G02X364475Y347551I0J-400D01*
G03X367279I1402J9D01*
G02X367656Y347948I400J-2D01*
G01X368165Y348457D01*
X368321Y348465D01*
G03X369263Y348107I936J1044D01*
G03X370656Y349412I-6J1402D01*
G01X370669Y349598D01*
X374605D01*
X374618Y349412D01*
G03X376326Y348141I1399J97D01*
G03X377033Y350475I-309J1368D01*
G01X377500Y350942D01*
G02X378141Y350837I283J-283D01*
G03X380735Y351040I1256J623D01*
G03X378412Y352457I-1338J420D01*
G02X377744Y352754I-268J297D01*
G01Y353935D01*
X378232Y354424D01*
X378427Y354345D01*
X378454Y354321D01*
G03X380412Y356327I943J1039D01*
G01X380277Y356469D01*
X380957Y357148D01*
X381375D01*
X381407Y357010D01*
G03X384147I1370J299D01*
G01X384179Y357148D01*
X385009D01*
G02X385263Y356440I-1J-400D01*
G03X387051I894J-1080D01*
G02X387305Y357148I255J308D01*
G01X388135D01*
X388167Y357010D01*
G03X390907I1370J299D01*
G01X390939Y357148D01*
X391768D01*
G02X392022Y356440I-1J-400D01*
G03X393810I894J-1080D01*
G02X394064Y357148I255J308D01*
G01X394894D01*
X394926Y357010D01*
G03X397616Y356837I1370J299D01*
G01X397658Y356948D01*
X398322D01*
G02X398622Y356285I-1J-400D01*
G03X399016Y354123I1054J-925D01*
G03X401043Y355047I660J1237D01*
G02X401711Y355223I385J-107D01*
G01X401837Y355097D01*
G02X402088Y354424I-40J-398D01*
G03X404024Y354423I967J-1015D01*
G02X404314Y355098I290J275D01*
G01X404715D01*
X407644Y358027D01*
Y384817D01*
X409095Y386269D01*
G02X409757Y386113I283J-283D01*
G03X410998Y385161I1329J447D01*
G03X412213Y385727I88J1399D01*
G03X411447Y387915I-1127J833D01*
G02X411189Y388474I103J386D01*
G03X411327Y389079I-1263J606D01*
G03X412467Y390219I-241J1381D01*
G03X413455Y390628I-2J1402D01*
G01X417230Y394403D01*
Y407935D01*
X419844Y410549D01*
Y440837D01*
X418296Y442384D01*
Y469947D01*
X442620Y494271D01*
Y499415D01*
X449382Y506176D01*
Y513367D01*
X448378Y514370D01*
Y518362D01*
X449382Y519365D01*
Y529232D01*
X447888Y530725D01*
Y586991D01*
X448013Y587020D01*
G03X448044Y589762I-278J1374D01*
G01X447888Y589797D01*
Y605966D01*
X447214Y606641D01*
Y607920D01*
X447888Y608595D01*
Y611253D01*
X448019Y611280D01*
G03X448048Y614032I-253J1379D01*
G01X447888Y614065D01*
Y621400D01*
X448388Y621900D01*
X449800D01*
X450700Y622800D01*
Y624350D01*
X450924Y624574D01*
X451663D01*
G02X452015Y623984I0J-400D01*
G03X454485I1235J-664D01*
G02X454837Y624574I352J190D01*
G01X455323D01*
G02X455675Y623984I0J-400D01*
G03X458145I1235J-664D01*
G02X458497Y624574I352J190D01*
G01X726329D01*
G02X726700Y624024I0J-400D01*
G03X729300I1300J-524D01*
G02X729671Y624574I371J150D01*
G01X731378D01*
G02X731671Y623902I0J-400D01*
G03X733729I1029J-952D01*
G02X734022Y624574I293J272D01*
G01X1044829D01*
G02X1045200Y624024I0J-400D01*
G03X1045109Y623326I1300J-524D01*
G02X1044712Y622876I-397J-50D01*
G01X958910D01*
X955722Y619689D01*
G02X955040Y619971I-282J283D01*
G01Y621184D01*
X952836D01*
Y614082D01*
X954870D01*
Y612421D01*
G02X954352Y612039I-400J0D01*
G03Y609361I-416J-1339D01*
G02X954870Y608979I118J-382D01*
G01Y602910D01*
X955708Y602072D01*
X956182D01*
Y596974D01*
X954998D01*
Y595170D01*
G03X955992Y593829I1402J0D01*
G03X957162Y592361I1291J-172D01*
G03X957736Y591324I1398J96D01*
G02X957765Y590699I-236J-324D01*
G03X957730Y588626I925J-1052D01*
G02X957222Y588009I-274J-292D01*
G03X955879Y588176I-823J-1134D01*
G02X955332Y588584I-149J371D01*
G03X954418Y587397I-1396J130D01*
G02X954956Y587022I138J-375D01*
G01Y583384D01*
X952836D01*
Y576282D01*
X954956D01*
Y574592D01*
G02X954418Y574217I-400J0D01*
G03X954768Y571771I-482J-1317D01*
G01X954793Y571790D01*
X955014Y571865D01*
X955117Y571680D01*
X955123Y571667D01*
X955125Y571664D01*
X955131Y571651D01*
G03X955468Y571199I1269J594D01*
G02Y570602I-266J-298D01*
G03X954998Y569556I931J-1047D01*
G01Y568027D01*
G03X956295Y566630I1401J1D01*
G03X956579Y565926I1297J114D01*
G02X956268Y565274I-311J-252D01*
G01X956182D01*
Y559174D01*
X955585D01*
X954942Y558530D01*
Y552611D01*
G02X954407Y552234I-400J0D01*
G03Y549594I-471J-1320D01*
G02X954942Y549217I135J-377D01*
G01Y545584D01*
X952836D01*
Y538482D01*
X954942D01*
Y536797D01*
G02X954407Y536420I-400J0D01*
G03Y533780I-471J-1320D01*
G02X954942Y533403I135J-377D01*
G01Y527274D01*
X955740Y526476D01*
X956182D01*
Y521374D01*
X954998D01*
Y519627D01*
G03X955905Y518316I1402J1D01*
G03Y517798I1378J-259D01*
G03X954998Y516487I495J-1312D01*
G01Y514789D01*
G02X954451Y514418I-400J1D01*
G03X954796Y512007I-515J-1304D01*
G01X955015Y511875D01*
X955004Y511750D01*
G03X954998Y511629I1396J-130D01*
G01Y510707D01*
X957620Y508085D01*
Y498881D01*
X969958Y486544D01*
Y461626D01*
X984498Y447085D01*
Y444361D01*
G02X983767Y444138I-400J1D01*
G03Y434208I-7389J-4965D01*
G02X984498Y433985I331J-224D01*
G01Y423703D01*
X986616Y421585D01*
Y415467D01*
X987644Y414439D01*
Y398731D01*
X987864Y398511D01*
Y393398D01*
X988485D01*
X988598Y393285D01*
Y384415D01*
X988230Y384047D01*
X988170Y384035D01*
G03X987282Y381878I276J-1375D01*
G01X987374Y381741D01*
X986998Y381365D01*
Y380560D01*
G03X987350Y379634I1401J3D01*
G03Y377886I1096J-874D01*
G03X986998Y376960I1049J-929D01*
G01Y376660D01*
G03X987350Y375734I1401J3D01*
G03X987051Y374728I1096J-873D01*
G01X987053Y374706D01*
X987054Y374686D01*
Y374478D01*
X986998D01*
Y372585D01*
X987486Y372099D01*
X987410Y371904D01*
X987387Y371878D01*
G03X987798Y369715I1059J-919D01*
G01Y368304D01*
G03Y365816I648J-1244D01*
G01Y364404D01*
G03Y361916I648J-1244D01*
G01Y359924D01*
X988585Y359636D01*
G02Y358884I-139J-376D01*
G01X987798Y358596D01*
Y356897D01*
X988888Y355807D01*
Y354245D01*
X990848Y352285D01*
Y350935D01*
X991062Y350722D01*
X990913Y350573D01*
X990907Y350568D01*
G03X992771Y348473I919J-1059D01*
G02X993323Y348460I269J-295D01*
G01X993850Y347933D01*
X993830Y347828D01*
G03X996608Y347561I1376J-268D01*
G02X996960Y347959I400J1D01*
G03X998187Y349473I-169J1391D01*
G02X998985I399J36D01*
G03X1000211Y347959I1396J-123D01*
G02X1000563Y347561I-48J-397D01*
G03X1003367I1402J-1D01*
G02X1003719Y347959I400J1D01*
G03X1004946Y349473I-169J1391D01*
G02X1005744I399J36D01*
G03X1006971Y347959I1396J-123D01*
G02X1007323Y347561I-48J-397D01*
G03X1010127I1402J-1D01*
G02X1010479Y347959I400J1D01*
G03X1011302Y348360I-169J1391D01*
G03X1012908I803J1149D01*
G03X1013731Y347959I992J990D01*
G02X1014083Y347561I-48J-397D01*
G03X1016887Y347551I1402J-1D01*
G02X1017264Y347948I400J-2D01*
G01X1017846Y348530D01*
X1017986Y348417D01*
G03X1020264Y349412I879J1092D01*
G01X1020277Y349598D01*
X1020503D01*
G03X1021647Y350192I-1J1401D01*
G03X1022843I598J1268D01*
G03X1023987Y349598I1145J807D01*
G01X1024213D01*
X1024226Y349412D01*
G03X1026751Y350344I1399J97D01*
G01X1026648Y350482D01*
X1027108Y350942D01*
G02X1027749Y350837I283J-283D01*
G03X1028030Y352467I1256J623D01*
G02X1027352Y352754I-278J287D01*
G01Y353935D01*
X1027758Y354342D01*
G02X1028038Y354345I142J-141D01*
G03X1030043Y356302I968J1014D01*
G01X1030021Y356326D01*
X1029957Y356474D01*
X1030001Y356600D01*
X1030019Y356625D01*
G03X1030229Y357029I-1122J840D01*
G01X1030282Y357191D01*
X1030450Y357165D01*
G03X1030661Y357148I218J1384D01*
G01X1030983D01*
X1031019Y356993D01*
G03X1033751I1366J316D01*
G01X1033787Y357148D01*
X1034109D01*
G03X1035396Y359103I-1J1401D01*
G02X1036134I369J157D01*
G03X1037421Y357148I1288J-554D01*
G01X1037743D01*
X1037779Y356993D01*
G03X1040511I1366J316D01*
G01X1040547Y357148D01*
X1040868D01*
G03X1042155Y359103I-1J1401D01*
G02X1042893I369J157D01*
G03X1044180Y357148I1288J-554D01*
G01X1044502D01*
X1044538Y356993D01*
G03X1047270I1366J316D01*
G01X1047306Y357148D01*
X1047628D01*
G03X1048878Y357918I-1J1401D01*
G03X1049335Y357859I406J1342D01*
G01X1049422Y357862D01*
X1052035Y355248D01*
X1053765D01*
X1057252Y358735D01*
Y384817D01*
X1058703Y386269D01*
G02X1059365Y386113I283J-283D01*
G03X1061055Y387915I1329J447D01*
G02X1060797Y388474I103J386D01*
G03X1060935Y389079I-1263J606D01*
G03X1062075Y390219I-241J1381D01*
G03X1063063Y390628I-2J1402D01*
G01X1066838Y394403D01*
Y407935D01*
X1068001Y409098D01*
X1068215D01*
X1069452Y410335D01*
Y439015D01*
X1068302Y440165D01*
Y457035D01*
X1069452Y458185D01*
Y471636D01*
X1092250Y494435D01*
Y499437D01*
X1098990Y506176D01*
Y510908D01*
G03X1097409Y512298I-1402J0D01*
G02X1097138Y513250I-65J496D01*
G03X1097842Y515096I-577J1277D01*
G02X1098149Y515777I458J203D01*
G01X1098152Y515778D01*
X1098990Y516047D01*
Y530610D01*
X1097969Y530759D01*
G02X1097646Y531004I47J398D01*
G01X1097461Y531128D01*
X1097430Y531126D01*
G02X1097156Y532080I-79J494D01*
G03X1097791Y533653I-472J1105D01*
G02X1097980Y534166I369J155D01*
G03X1097889Y536352I-542J1072D01*
G02X1097710Y536495I150J371D01*
G01X1097546Y536580D01*
X1097497Y536574D01*
G02X1096981Y536750I-123J485D01*
G03X1096844Y536901I-1104J-864D01*
G02X1096834Y537180I138J145D01*
G03X1096959Y537339I-1036J943D01*
G02X1097430Y537556I415J-280D01*
G03X1098990Y538947I158J1393D01*
G01Y549253D01*
X1098035Y549451D01*
G02X1097769Y549648I84J391D01*
G03X1097194Y550117I-875J-486D01*
G02X1097138Y551050I150J477D01*
G03X1097842Y552896I-577J1277D01*
G02X1098149Y553577I458J203D01*
G01X1098152Y553578D01*
X1098990Y553847D01*
Y567534D01*
G03X1098043Y568859I-1402J-1D01*
G02X1097521Y568949I-210J341D01*
G02X1097414Y569916I-169J471D01*
G03X1098990Y571307I174J1391D01*
G01Y572971D01*
G03X1097430Y574362I-1402J-2D01*
G02X1096981Y574550I-56J497D01*
G03X1096844Y574701I-1104J-864D01*
G02X1096834Y574980I138J145D01*
G03X1096959Y575139I-1036J943D01*
G02X1097430Y575356I415J-280D01*
G03X1098990Y576747I158J1393D01*
G01Y586508D01*
G03X1098487Y587583I-1402J-1D01*
G03X1097891Y589684I-1144J811D01*
G03X1097842Y590696I-1330J443D01*
G02X1098149Y591377I458J203D01*
G01X1098152Y591378D01*
X1098990Y591647D01*
Y605333D01*
G03X1097414Y606724I-1402J0D01*
G02Y607716I-62J496D01*
G03X1098990Y609107I174J1391D01*
G01Y610771D01*
G03X1098504Y611830I-1402J-2D01*
G03Y613488I-1130J829D01*
G03X1098990Y614547I-916J1061D01*
G01Y619999D01*
X1096473Y622515D01*
X1095737Y622219D01*
X1095736D01*
G02X1095621Y622188I-187J464D01*
G01X1095291Y622141D01*
X1095224Y622262D01*
G03X1095141Y622394I-1226J-679D01*
G02X1095055Y622607I409J289D01*
G01X1094877Y623580D01*
X1077479D01*
X1077329Y622553D01*
G02X1077263Y622375I-398J46D01*
G03X1077195Y622265I1157J-791D01*
G01X1077116Y622123D01*
X1076812Y622218D01*
G02X1076535Y622553I120J382D01*
G01X1076385Y623580D01*
X1063479D01*
X1063329Y622553D01*
G02X1063263Y622375I-398J46D01*
G03X1063148Y622173I1157J-792D01*
G03X1062919Y622200I-278J-1374D01*
G02X1062536Y622545I13J400D01*
G01X1062535Y622547D01*
X1062385Y623580D01*
X1049979D01*
X1049829Y622553D01*
G02X1049763Y622375I-398J46D01*
G03X1049656Y622190I1157J-792D01*
G03X1049444Y622200I-172J-1391D01*
G02X1049090Y622393I-11J400D01*
G01X1048798Y622876D01*
X1048288D01*
G02X1047891Y623326I0J400D01*
G03X1047800Y624024I-1391J174D01*
G02X1048171Y624574I371J150D01*
G01X1550312D01*
G02X1550649Y623959I0J-400D01*
G03X1552841Y622233I1182J-753D01*
G03X1553393Y622746I-643J1246D01*
G02X1553723Y622603I23J-399D01*
G03X1555889Y622617I1077J897D01*
G02X1556511I311J-252D01*
G03X1558611Y622529I1089J883D01*
G02X1559189I289J-277D01*
G03X1560661Y622177I1010J972D01*
G03X1561793Y622642I87J1399D01*
G02X1562404Y622626I299J-266D01*
G03X1564645Y622691I1096J874D01*
G02X1565315Y622665I327J-231D01*
G03X1567673Y622584I1205J717D01*
G02X1568333Y622580I329J-228D01*
G03X1570748Y623994I1162J784D01*
G02X1571105Y624574I357J180D01*
G01X1967224D01*
G02X1974574Y617224I0J-7350D01*
G01Y598567D01*
G02X1973913Y598264I-400J0D01*
G03Y596136I-913J-1064D01*
G02X1974574Y595833I261J-303D01*
G01Y566366D01*
G02X1973869Y566107I-400J0D01*
G03Y564293I-1069J-907D01*
G02X1974574Y564034I305J-259D01*
G01Y537966D01*
G02X1973869Y537707I-400J0D01*
G03Y535893I-1069J-907D01*
G02X1974574Y535634I305J-259D01*
G01Y441748D01*
G02X1967225Y434399I-7349J0D01*
G01X1922314D01*
G02X1921956Y434977I0J400D01*
G03X1919533Y436377I-1256J623D01*
G02X1918867I-333J222D01*
G03X1916533I-1167J-777D01*
G02X1915867I-333J222D01*
G03X1913444Y434977I-1167J-777D01*
G02X1913424Y434585I-358J-178D01*
G01X1683585D01*
X1680100Y431100D01*
Y306399D01*
G02X1679567Y306022I-400J0D01*
G03X1678129Y303689I-467J-1322D01*
G02Y303111I-277J-289D01*
G03Y301089I971J-1011D01*
G02Y300511I-277J-289D01*
G03X1678090Y298527I971J-1011D01*
G02Y297973I-288J-277D01*
G03Y296027I1010J-973D01*
G02Y295473I-288J-277D01*
G03Y293527I1010J-973D01*
G02Y292973I-288J-277D01*
G03Y291027I1010J-973D01*
G02Y290473I-288J-277D01*
G03X1678271Y288369I1010J-973D01*
G02Y287724I-236J-323D01*
G03X1678090Y285620I829J-1131D01*
G02Y285066I-288J-277D01*
G03Y283120I1010J-973D01*
G02Y282566I-288J-277D01*
G03X1678158Y280555I1010J-972D01*
G02Y279962I-269J-297D01*
G03X1678099Y277942I942J-1038D01*
G02Y277382I-285J-280D01*
G03X1678090Y275427I1001J-982D01*
G02Y274873I-288J-277D01*
G03X1678129Y272889I1010J-973D01*
G02Y272311I-277J-289D01*
G03X1679567Y269978I971J-1011D01*
G02X1680100Y269601I133J-377D01*
G01Y268600D01*
X1683264Y265436D01*
X1870745D01*
G02X1871095Y264843I0J-400D01*
G03X1873551I1228J-676D01*
G02X1873901Y265436I350J193D01*
G01X1882941D01*
G02X1885824Y262553I0J-2883D01*
G01Y248376D01*
X1889250Y244950D01*
X1892200D01*
X1892214Y244964D01*
X1912372D01*
G02X1912722Y244371I-1J-400D01*
G03X1915352I1315J-725D01*
G02X1915702Y244964I351J193D01*
G01X1946598D01*
Y236102D01*
X1954390D01*
G03X1959543Y236615I2500J1024D01*
G02X1960225Y236815I393J-76D01*
G03X1959666Y239000I1665J1590D01*
G02X1958972Y238849I-386J104D01*
G03X1957693Y239706I-2081J-1723D01*
G01X1957552Y239750D01*
Y244964D01*
X1965840D01*
Y239440D01*
X1974344D01*
G02X1974574Y237617I-7120J-1824D01*
G01Y210008D01*
X1965840D01*
Y204006D01*
X1974574D01*
Y148894D01*
G02X1973986Y148541I-400J0D01*
G03Y146065I-658J-1238D01*
G02X1974574Y145712I188J-353D01*
G01Y144490D01*
G02X1973914Y144186I-400J0D01*
G03Y142054I-910J-1066D01*
G02X1974574Y141750I260J-304D01*
G01Y69598D01*
X1974577D01*
Y66929D01*
G02X1974565Y66704I-2136J1D01*
G01Y58935D01*
X1972600Y56970D01*
X1905350D01*
X1903062Y54682D01*
X1902906Y54721D01*
X1902884Y54731D01*
X1902876Y54734D01*
X1902866Y54738D01*
G03X1902523Y54714I-146J-372D01*
G02X1899640Y54576I-1578J2786D01*
G03X1899085Y54132I-163J-365D01*
G02Y52876I-3140J-628D01*
G03X1899111Y52637I392J-78D01*
G02X1898988Y52161I-367J-159D01*
G03X1897805Y48998I1957J-2535D01*
G02X1897250Y48554I-392J-79D01*
G03Y42706I-1305J-2924D01*
G02X1897805Y42262I163J-365D01*
G03Y41006I3140J-628D01*
G02X1897250Y40562I-392J-79D01*
G03Y34714I-1305J-2924D01*
G02X1897805Y34270I163J-365D01*
G03Y33014I3140J-628D01*
G02X1897250Y32570I-392J-79D01*
G03Y26722I-1305J-2924D01*
G02X1897805Y26278I163J-365D01*
G03X1897829Y24913I3140J-628D01*
G02X1897269Y24459I-389J-92D01*
G03Y18849I-1324J-2805D01*
G02X1897829Y18395I171J-362D01*
G03X1897805Y17030I3116J-737D01*
G02X1897250Y16586I-392J-79D01*
G03Y10738I-1305J-2924D01*
G02X1897805Y10294I163J-365D01*
G03Y9038I3140J-628D01*
G02X1897250Y8594I-392J-79D01*
G03Y2746I-1305J-2924D01*
G02X1897805Y2302I163J-365D01*
G03Y1046I3140J-628D01*
G02X1897250Y602I-392J-79D01*
G03Y-5246I-1305J-2924D01*
G02X1897805Y-5690I163J-365D01*
G03X1902416Y-9162I3140J-628D01*
G02X1903000Y-9517I184J-355D01*
G01Y-11300D01*
X1905400Y-13700D01*
X1972600D01*
X1974500Y-15600D01*
Y-19700D01*
X1972390Y-21810D01*
X1920310D01*
X1920300Y-21821D01*
X1904929D01*
X1904926Y-21818D01*
X1894747D01*
G02X1894378Y-21266I1J400D01*
G03X1891784I-1297J531D01*
G02X1891415Y-21818I-370J-152D01*
G01X1105042D01*
G02X1104667Y-21281I1J400D01*
G03X1102033I-1317J481D01*
G02X1101658Y-21818I-376J-137D01*
G01X1100392D01*
G02X1100017Y-21281I1J400D01*
G03X1097383I-1317J481D01*
G02X1097008Y-21818I-376J-137D01*
G01X1096713D01*
G02X1096369Y-21215I1J400D01*
G03X1095978Y-19361I-1207J714D01*
G01X1095894Y-19301D01*
Y-19045D01*
X1096079Y-18848D01*
X1096152Y-18840D01*
G03X1096980Y-18440I-162J1392D01*
G01X1098354Y-17067D01*
Y-8408D01*
X1097659Y-7714D01*
X1097304Y-7678D01*
G02X1097303Y-6682I50J498D01*
G01X1097656Y-6645D01*
X1098202Y-6100D01*
Y213D01*
X1098574Y585D01*
Y9909D01*
G03X1098830Y12087I-740J1191D01*
G02X1098845Y12664I284J281D01*
G03X1098574Y14929I-945J1036D01*
G01Y16306D01*
X1098191Y16606D01*
G02Y17394I309J394D01*
G01X1098574Y17694D01*
Y26909D01*
G03Y29291I-740J1191D01*
G01Y30671D01*
G03Y33129I-674J1229D01*
G01Y34467D01*
X1098680Y34523D01*
G03Y36999I-658J1238D01*
G01X1098574Y37055D01*
Y45640D01*
X1098693Y45693D01*
G03Y48257I-568J1282D01*
G01X1098574Y48310D01*
Y49674D01*
X1098690Y49728D01*
G03Y52272I-590J1272D01*
G01X1098574Y52326D01*
Y66722D01*
X1098707Y66770D01*
G03X1099124Y69174I-472J1320D01*
G02X1099129Y69797I254J309D01*
G03X1099170Y71962I-870J1099D01*
G02X1099159Y72559I260J303D01*
G03X1098703Y74900I-952J1030D01*
G01X1098574Y74949D01*
Y83933D01*
X1098705Y83981D01*
G03Y86611I-487J1315D01*
G01X1098574Y86659D01*
Y88517D01*
X1098715Y88561D01*
G03Y91239I-415J1339D01*
G01X1098574Y91283D01*
Y99639D01*
X1064800Y133413D01*
Y141617D01*
X1063902Y142515D01*
Y160369D01*
X1064618Y161085D01*
Y196061D01*
X1063056Y197622D01*
Y238255D01*
X1062082Y239229D01*
Y242685D01*
X1059590Y245178D01*
X1058328D01*
G03X1056300I-1014J-969D01*
G01X1050989D01*
G02X1050611Y245707I0J400D01*
G03X1047957I-1327J453D01*
G02X1047579Y245178I-378J-129D01*
G01X1046918D01*
G03X1044890I-1014J-969D01*
G01X1044229D01*
G02X1043851Y245707I0J400D01*
G03X1041197I-1327J453D01*
G02X1040819Y245178I-378J-129D01*
G01X1040159D01*
G03X1038131I-1014J-969D01*
G01X1037470D01*
G02X1037092Y245707I0J400D01*
G03X1034438I-1327J453D01*
G02X1034060Y245178I-378J-129D01*
G01X1033399D01*
G03X1031371I-1014J-969D01*
G01X1030710D01*
G02X1030332Y245707I0J400D01*
G03X1029779Y247329I-1327J453D01*
G03X1027604Y246202I-774J-1169D01*
G02X1026921Y245942I-400J23D01*
G01X1026093Y246770D01*
X1023507D01*
G03X1020983I-1262J-610D01*
G01X1020403D01*
G02X1020062Y247379I0J400D01*
G03X1017668I-1197J730D01*
G02X1017327Y246770I-341J-209D01*
G01X1016747D01*
G03X1015745Y247538I-1263J-610D01*
G03X1014253Y246830I-260J-1378D01*
G01X1013987D01*
X1013355Y247461D01*
X1013405Y247584D01*
G03X1011108Y249095I-1300J526D01*
G03X1010727Y248366I997J-985D01*
G01X1010697Y248202D01*
X1006753D01*
X1006723Y248365D01*
G03X1003967I-1378J-256D01*
G01X1003937Y248202D01*
X999994D01*
X999964Y248365D01*
G03X997208I-1378J-256D01*
G01X997178Y248202D01*
X993234D01*
X993204Y248365D01*
G03X990485Y247701I-1378J-256D01*
G01X990520Y247586D01*
X988698Y245765D01*
Y232355D01*
G02X988344Y231958I-400J0D01*
G03Y229162I102J-1398D01*
G02X988698Y228765I-46J-397D01*
G01Y228265D01*
X986152Y225719D01*
X985964Y225787D01*
X985938Y225807D01*
G03X984744Y223344I-872J-1098D01*
G01X984898Y223308D01*
Y222210D01*
X984744Y222174D01*
G03Y219444I322J-1365D01*
G01X984898Y219408D01*
Y218310D01*
X984744Y218274D01*
G03Y215544I322J-1365D01*
G01X984898Y215508D01*
Y214385D01*
X986598Y212685D01*
Y201185D01*
X988092Y199691D01*
Y192349D01*
X985800Y190057D01*
Y180778D01*
X985180Y180157D01*
Y167795D01*
G02X984422Y167616I-400J0D01*
G03Y159550I-8043J-4033D01*
G02X985180Y159372I358J-179D01*
G01Y142596D01*
X979048Y136465D01*
Y133415D01*
X969148Y123515D01*
Y115965D01*
X954424Y101240D01*
Y98140D01*
X954364Y98081D01*
Y90578D01*
X954382Y90486D01*
G02Y90342I-496J-72D01*
G01X954364Y90250D01*
Y89515D01*
G02X953958Y89116I-400J1D01*
G03Y86312I-22J-1402D01*
G02X954364Y85913I6J-400D01*
G01Y82384D01*
X952836D01*
Y75282D01*
X954364D01*
Y73701D01*
G02X953958Y73302I-400J1D01*
G03Y70498I-22J-1402D01*
G02X954364Y70099I6J-400D01*
G01Y68069D01*
X954413Y67899D01*
X954415Y67893D01*
G02Y67605I-479J-144D01*
G01X954413Y67599D01*
X954364Y67429D01*
Y52934D01*
X954413Y52764D01*
X954415Y52758D01*
G02Y52470I-479J-144D01*
G01X954413Y52464D01*
X954364Y52294D01*
Y51722D01*
X953960Y51318D01*
X953882Y51315D01*
G03X953958Y48512I54J-1401D01*
G02X954364Y48113I6J-400D01*
G01Y44584D01*
X952836D01*
Y37482D01*
X954364D01*
Y35901D01*
G02X953958Y35502I-400J1D01*
G03Y32698I-22J-1402D01*
G02X954364Y32299I6J-400D01*
G01Y30269D01*
X954413Y30099D01*
X954415Y30093D01*
G02Y29805I-479J-144D01*
G01X954413Y29799D01*
X954364Y29629D01*
Y15134D01*
X954413Y14964D01*
X954415Y14958D01*
G02Y14670I-479J-144D01*
G01X954413Y14664D01*
X954364Y14494D01*
Y13915D01*
G02X953958Y13516I-400J1D01*
G03Y10712I-22J-1402D01*
G02X954364Y10313I6J-400D01*
G01Y6784D01*
X952836D01*
Y-318D01*
X954364D01*
Y-1899D01*
G02X953958Y-2298I-400J1D01*
G03Y-5102I-22J-1402D01*
G02X954364Y-5501I6J-400D01*
G01Y-7531D01*
X954413Y-7701D01*
X954415Y-7707D01*
G02Y-7995I-479J-144D01*
G01X954413Y-8001D01*
X954364Y-8171D01*
Y-17207D01*
X957659Y-20502D01*
X1051411D01*
X1051467Y-20609D01*
G03X1053953I1243J649D01*
G01X1054009Y-20502D01*
X1054344D01*
G03X1056896I1276J582D01*
G01X1093749D01*
X1093771Y-20677D01*
G03X1093955Y-21215I1391J175D01*
G02X1093611Y-21818I-345J-203D01*
G01X658438D01*
G02X658075Y-21250I0J400D01*
G03X655539I-1268J598D01*
G02X655176Y-21818I-363J-168D01*
G01X69236D01*
G02X68865Y-21269I0J400D01*
G03X67065Y-19435I-1301J524D01*
G02X66532Y-19149I-143J374D01*
G03X64216Y-18423I-1368J-307D01*
G02X63622Y-18362I-270J295D01*
G03X63434Y-20217I-1136J-822D01*
G02X64028Y-20278I270J-295D01*
G03X65663Y-20766I1136J822D01*
G02X66196Y-21052I143J-374D01*
G03X66263Y-21269I1369J304D01*
G02X65892Y-21818I-371J-149D01*
G01X52233D01*
G02X51867Y-21256I0J400D01*
G03X49305I-1281J569D01*
G02X48939Y-21818I-366J-162D01*
G01X39768D01*
G02X39426Y-21211I0J400D01*
G03X37028I-1199J726D01*
G02X36686Y-21818I-342J-207D01*
G01X-14469D01*
G02X-21818Y-14469I0J7349D01*
G01Y617225D01*
G02X-14469Y624574I7349J0D01*
G01X385284D01*
G02X385658Y624033I0J-400D01*
G03X385605Y623218I1312J-495D01*
G02X385216Y622727I-389J-91D01*
G01X309153D01*
X306114Y619689D01*
G02X305432Y619971I-282J283D01*
G01Y621184D01*
X303228D01*
Y614082D01*
X305498D01*
Y612329D01*
G02X304935Y611964I-400J0D01*
G03Y609436I-607J-1264D01*
G02X305498Y609071I163J-365D01*
G01Y590343D01*
G02X304935Y589978I-400J0D01*
G03Y587450I-607J-1264D01*
G02X305498Y587085I163J-365D01*
G01Y583384D01*
X303228D01*
Y576282D01*
X305498D01*
Y574529D01*
G02X304935Y574164I-400J0D01*
G03Y571636I-607J-1264D01*
G02X305498Y571271I163J-365D01*
G01Y552543D01*
G02X304935Y552178I-400J0D01*
G03Y549650I-607J-1264D01*
G02X305498Y549285I163J-365D01*
G01Y545584D01*
X303228D01*
Y538482D01*
X305498D01*
Y536729D01*
G02X304935Y536364I-400J0D01*
G03Y533836I-607J-1264D01*
G02X305498Y533471I163J-365D01*
G01Y514743D01*
G02X304935Y514378I-400J0D01*
G03Y511850I-607J-1264D01*
G02X305498Y511485I163J-365D01*
G01Y510599D01*
X308012Y508085D01*
G37*
G36*
G01X-20621Y661811D02*
G02X-19685Y662747I936J0D01*
G01X1972600D01*
Y637600D01*
X-20412D01*
G02X-20621Y638189I726J589D01*
G01Y661811D01*
G37*
G36*
G01X344642Y348950D02*
X343488Y350104D01*
X343473Y350133D01*
G03X342848Y350761I-1255J-624D01*
G01X342820Y350776D01*
X342242Y351351D01*
Y352700D01*
X341144Y353798D01*
X341032Y353911D01*
Y355708D01*
G02X341593Y356054I399J-20D01*
G03Y358564I625J1255D01*
G02X341032Y358910I-162J366D01*
G01Y359608D01*
G02X341593Y359954I399J-20D01*
G03X343266Y362140I625J1255D01*
G03X340884Y361640I-1048J-931D01*
G03X340821Y361332I1333J-433D01*
G02X340148Y361085I-398J43D01*
G01X339722Y361511D01*
G02X339749Y362094I287J279D01*
G03X339927Y364043I-911J1066D01*
G03X338092Y364347I-1089J-883D01*
G02X337492Y364693I-200J347D01*
G01Y369426D01*
G02X338092Y369772I400J-1D01*
G03Y372146I746J1187D01*
G02X337492Y372492I-200J347D01*
G01Y373327D01*
G02X338092Y373673I400J-1D01*
G03Y376047I746J1187D01*
G02X337492Y376393I-200J347D01*
G01Y377227D01*
G02X338092Y377573I400J-1D01*
G03X338777Y377359I747J1187D01*
G03X339358Y380062I62J1401D01*
G02X339223Y380716I148J372D01*
G01X339519Y381012D01*
Y381321D01*
G03X339520Y383998I-681J1339D01*
G01Y414373D01*
X338720Y415172D01*
X338010Y415882D01*
Y445589D01*
X320464Y463135D01*
Y487846D01*
X309014Y499296D01*
Y508500D01*
X306500Y511014D01*
Y511512D01*
G02X307181Y511796I400J0D01*
G03Y513792I985J998D01*
G02X306500Y514076I-281J284D01*
G01Y516430D01*
G02X307072Y516791I400J0D01*
G03Y519323I603J1266D01*
G02X306500Y519684I-172J361D01*
G01Y520372D01*
X308776D01*
Y527586D01*
G03X307051Y529670I-578J1277D01*
G02X306500Y530040I-151J370D01*
G01Y531667D01*
G02X307142Y531985I400J0D01*
G03Y534215I850J1115D01*
G02X306500Y534533I-242J318D01*
G01Y535330D01*
G02X307072Y535691I400J0D01*
G03Y538223I603J1266D01*
G02X306500Y538584I-172J361D01*
G01Y546573D01*
G02X307072Y546934I400J0D01*
G03Y549466I603J1266D01*
G02X306500Y549827I-172J361D01*
G01Y550656D01*
G02X307166Y550954I400J0D01*
G03Y553046I934J1046D01*
G02X306500Y553344I-266J298D01*
G01Y554286D01*
G02X306905Y554685I400J-1D01*
G03Y557029I770J1172D01*
G02X306500Y557428I-5J400D01*
G01Y558172D01*
X308776D01*
Y565274D01*
X308762D01*
Y565573D01*
X308840Y565633D01*
G03X306988Y567729I-856J1110D01*
G02X306500Y568119I-88J390D01*
G01Y569467D01*
G02X307142Y569785I400J0D01*
G03Y572015I850J1115D01*
G02X306500Y572333I-242J318D01*
G01Y573130D01*
G02X307072Y573491I400J0D01*
G03Y576023I603J1266D01*
G02X306500Y576384I-172J361D01*
G01Y586802D01*
G02X307106Y587144I400J-1D01*
G03X307285Y587050I740J1191D01*
G03X308808Y589356I563J1284D01*
G02X308818Y589947I274J291D01*
G03X308717Y592134I-926J1053D01*
G02X308571Y592578I235J323D01*
G03X306905Y594829I-896J1079D01*
G02X306500Y595228I-5J400D01*
G01Y595972D01*
X308776D01*
Y603074D01*
X306500D01*
Y605929D01*
G02X307179Y606215I400J0D01*
G03Y608225I978J1005D01*
G02X306500Y608511I-279J286D01*
G01Y609973D01*
G02X307072Y610334I400J0D01*
G03Y612866I603J1266D01*
G02X306500Y613227I-172J361D01*
G01Y618658D01*
X308843Y621001D01*
X309568Y621726D01*
X443616D01*
X443765Y621875D01*
X446290D01*
X446886Y621278D01*
Y613751D01*
G03Y611567I880J-1092D01*
G01Y609010D01*
X446212Y608335D01*
Y606226D01*
X446886Y605552D01*
Y589510D01*
G03Y587278I849J-1116D01*
G01Y569615D01*
X446879Y569588D01*
G03Y568812I1347J-388D01*
G01X446886Y568785D01*
Y530310D01*
X447680Y529517D01*
X448380Y528817D01*
Y519780D01*
X448006Y519406D01*
X447376Y518777D01*
Y515787D01*
X447366Y515755D01*
G03Y514845I1326J-455D01*
G01X447376Y514813D01*
Y514156D01*
X447246Y514108D01*
G03X447674Y511393I489J-1314D01*
G03X447926Y511405I60J1401D01*
G02X448380Y511009I54J-396D01*
G01Y506591D01*
X444176Y502387D01*
X441618Y499830D01*
Y494686D01*
X417294Y470362D01*
Y441969D01*
X418106Y441158D01*
X418842Y440422D01*
Y410964D01*
X416228Y408350D01*
Y394818D01*
X412747Y391337D01*
G02X412159Y391363I-282J283D01*
G03X410183Y389387I-1073J-903D01*
G02X410209Y388799I-257J-306D01*
G01X408405Y386995D01*
G03X408387Y386977I982J-1000D01*
G01X407901Y386491D01*
X406642Y385232D01*
Y358442D01*
X404300Y356100D01*
X402250D01*
X400657Y357693D01*
G02X400647Y358249I283J283D01*
G03X399652Y360662I-971J1011D01*
G03X398297Y359008I24J-1402D01*
G03X398470Y358546I1379J253D01*
G02X398121Y357950I-349J-196D01*
G01X397543D01*
G03X395174Y358150I-1247J-641D01*
G01X394572D01*
G02X394205Y358708I0J400D01*
G03X391627I-1289J552D01*
G02X391260Y358150I-367J-158D01*
G01X390659D01*
G03X388415I-1122J-841D01*
G01X387813D01*
G02X387446Y358708I0J400D01*
G03X384868I-1289J552D01*
G02X384501Y358150I-367J-158D01*
G01X383899D01*
G03X381655I-1122J-841D01*
G01X381053D01*
G02X380686Y358708I0J400D01*
G03X378717Y360486I-1289J552D01*
G03X379328Y357860I680J-1226D01*
G02X379580Y357188I-40J-398D01*
G01X379128Y356737D01*
X379073Y356724D01*
G03X378033Y355683I324J-1364D01*
G01X378020Y355628D01*
X377459Y355067D01*
G03X377441Y355049I840J-858D01*
G01X377305Y354913D01*
X376742Y354350D01*
Y351600D01*
X376054Y350913D01*
X375975Y350910D01*
G03X375485Y350806I41J-1401D01*
G03X375136Y350600I531J-1298D01*
G01X374379D01*
G02X373993Y351102I1J400D01*
G03X371281I-1356J358D01*
G02X370895Y350600I-387J-102D01*
G01X370138D01*
G03X368972Y350882I-881J-1091D01*
G03X367861Y349634I285J-1373D01*
G01X367854Y349562D01*
X367420Y349128D01*
G03X367403Y349111I841J-858D01*
G01X367242Y348950D01*
X366060D01*
X366048Y348951D01*
G03X365706I-171J-1391D01*
G01X365694Y348950D01*
X364292D01*
G02X363894Y349385I0J400D01*
G03X361100I-1397J124D01*
G02X360702Y348950I-398J-35D01*
G01X359300D01*
X359288Y348951D01*
G03X358946I-171J-1391D01*
G01X358934Y348950D01*
X357532D01*
G02X357134Y349385I0J400D01*
G03X356638Y350583I-1397J123D01*
G03X354836I-901J-1074D01*
G03X354340Y349385I901J-1075D01*
G02X353942Y348950I-398J-35D01*
G01X352540D01*
X352528Y348951D01*
G03X352186I-171J-1391D01*
G01X352174Y348950D01*
X350773D01*
G02X350375Y349385I0J400D01*
G03X349879Y350583I-1397J123D01*
G03X348077I-901J-1074D01*
G03X347581Y349385I901J-1075D01*
G02X347183Y348950I-398J-35D01*
G01X345781D01*
X345769Y348951D01*
G03X345427I-171J-1391D01*
G01X345415Y348950D01*
X344642D01*
G37*
G36*
G01X388335Y623218D02*
G03X388282Y624033I-1365J320D01*
G02X388656Y624574I374J141D01*
G01X443350D01*
Y622876D01*
X443201Y622727D01*
X388724D01*
G02X388335Y623218I0J400D01*
G37*
G36*
G01X958074Y-19500D02*
X957685Y-19111D01*
G02X957948Y-18428I283J283D01*
G01X958384D01*
Y-11326D01*
X956182D01*
Y-16662D01*
G02X955499Y-16925I-400J20D01*
G01X955366Y-16792D01*
Y-8310D01*
X955374Y-8282D01*
G03Y-7420I-1438J431D01*
G01X955366Y-7392D01*
Y-4158D01*
X955374Y-4130D01*
G03Y-3270I-1438J430D01*
G01X955366Y-3242D01*
Y14355D01*
X955374Y14383D01*
G03Y15245I-1438J431D01*
G01X955366Y15273D01*
Y29490D01*
X955374Y29518D01*
G03Y30380I-1438J431D01*
G01X955366Y30408D01*
Y33642D01*
X955374Y33670D01*
G03Y34530I-1438J430D01*
G01X955366Y34558D01*
Y49456D01*
X955374Y49484D01*
G03Y50344I-1438J430D01*
G01X955366Y50372D01*
Y52155D01*
X955374Y52183D01*
G03Y53045I-1438J431D01*
G01X955366Y53073D01*
Y67290D01*
X955374Y67318D01*
G03Y68180I-1438J431D01*
G01X955366Y68208D01*
Y71442D01*
X955374Y71470D01*
G03Y72330I-1438J430D01*
G01X955366Y72358D01*
Y87256D01*
X955374Y87284D01*
G03Y88144I-1438J430D01*
G01X955366Y88172D01*
Y90153D01*
X955369Y90169D01*
G03Y90659I-1483J245D01*
G01X955366Y90675D01*
Y97662D01*
X955426Y97720D01*
Y100825D01*
X970150Y115550D01*
Y123100D01*
X980050Y133000D01*
Y136050D01*
X983835Y139835D01*
X986182Y142181D01*
Y159373D01*
G03X986181Y159406I-1401J-26D01*
G01Y167760D01*
G03X986182Y167795I-1400J58D01*
G01Y179742D01*
X986802Y180363D01*
Y189642D01*
X989094Y191934D01*
Y200187D01*
X988804Y200477D01*
X988723D01*
X987600Y201600D01*
Y201792D01*
G02X987881Y201975I200J0D01*
G03X988433Y201856I565J1283D01*
G03X989757Y203754I13J1402D01*
G03X988084Y204613I-1312J-496D01*
G02X987600Y205003I-84J391D01*
G01Y205413D01*
G02X988084Y205803I400J-1D01*
G03Y208513I362J1355D01*
G02X987600Y208903I-84J391D01*
G01Y209313D01*
G02X988084Y209703I400J-1D01*
G03Y212413I362J1355D01*
G02X987600Y212803I-84J391D01*
G01Y213100D01*
X985900Y214800D01*
Y215782D01*
G03Y218036I-834J1127D01*
G01Y219682D01*
G03Y221936I-834J1127D01*
G01Y223582D01*
G03X986459Y224548I-834J1127D01*
G01X986467Y224617D01*
X989700Y227850D01*
Y229931D01*
X989718Y229971D01*
G03Y231149I-1272J589D01*
G01X989700Y231189D01*
Y233831D01*
X989718Y233871D01*
G03Y235049I-1272J589D01*
G01X989700Y235089D01*
Y237731D01*
X989718Y237771D01*
G03Y238949I-1272J589D01*
G01X989700Y238989D01*
Y241631D01*
X989718Y241671D01*
G03Y242849I-1272J589D01*
G01X989700Y242889D01*
Y245350D01*
X990618Y246268D01*
X991198Y246848D01*
X991320Y246801D01*
G03X992350Y246808I506J1308D01*
G03X992893Y247200I-525J1300D01*
G01X993522D01*
G02X993895Y246658I-1J-400D01*
G03X996517I1311J-498D01*
G02X996890Y247200I374J142D01*
G01X997519D01*
G03X999653I1067J909D01*
G01X1000281D01*
G02X1000654Y246658I-1J-400D01*
G03X1003276I1311J-498D01*
G02X1003649Y247200I374J142D01*
G01X1004278D01*
G03X1006412I1067J909D01*
G01X1007041D01*
G02X1007414Y246658I-1J-400D01*
G03X1010036I1311J-498D01*
G02X1010409Y247200I374J142D01*
G01X1011038D01*
G03X1012521Y246770I1067J909D01*
G01X1012606Y246794D01*
X1012859Y246541D01*
X1013572Y245828D01*
X1014116D01*
X1014153Y245722D01*
G03X1016796Y245664I1332J438D01*
G01X1016838Y245768D01*
X1017327D01*
G03X1017362Y245769I-23J1401D01*
G01X1020368D01*
G03X1020403Y245768I58J1400D01*
G01X1020892D01*
X1020934Y245664D01*
G03X1023556I1311J496D01*
G01X1023598Y245768D01*
X1024266D01*
G02X1024552Y245112I-20J-399D01*
G03X1024672Y243181I1073J-903D01*
G03X1027012Y244005I953J1028D01*
G01X1027037Y244176D01*
X1030973D01*
X1030998Y244005D01*
G03X1033772I1387J204D01*
G01X1033797Y244176D01*
X1037733D01*
X1037758Y244005D01*
G03X1040532I1387J204D01*
G01X1040557Y244176D01*
X1044492D01*
X1044517Y244005D01*
G03X1047291I1387J204D01*
G01X1047316Y244176D01*
X1055902D01*
X1055927Y244005D01*
G03X1058703Y244021I1387J204D01*
G01X1058726Y244176D01*
X1059175D01*
X1060539Y242812D01*
X1061080Y242270D01*
Y238814D01*
X1062054Y237840D01*
Y197207D01*
X1062871Y196391D01*
X1063616Y195646D01*
Y161500D01*
X1062900Y160784D01*
Y142100D01*
X1063798Y141202D01*
Y132998D01*
X1097572Y99224D01*
Y91098D01*
G03Y88702I728J-1198D01*
G01Y86540D01*
G03Y84052I646J-1244D01*
G01Y74839D01*
G03X1097296Y72523I635J-1250D01*
G02X1097307Y71926I-260J-303D01*
G03X1097223Y69951I952J-1030D01*
G03X1097572Y69674I1035J946D01*
G01Y69325D01*
G03Y66855I663J-1235D01*
G01Y55856D01*
G03Y53910I1009J-973D01*
G01Y52305D01*
X1097463Y52249D01*
G03X1096746Y51363I637J-1249D01*
G03Y50637I1354J-363D01*
G03X1097463Y49751I1354J363D01*
G01X1097572Y49695D01*
Y48269D01*
X1097492Y48226D01*
G03X1097466Y45738I633J-1251D01*
G01X1097572Y45681D01*
Y37095D01*
X1097453Y37042D01*
G03Y34480I569J-1281D01*
G01X1097572Y34427D01*
Y33271D01*
X1097438Y33224D01*
G03Y30576I462J-1324D01*
G01X1097572Y30529D01*
Y29485D01*
X1097430Y29442D01*
G03Y26758I404J-1342D01*
G01X1097572Y26715D01*
Y18181D01*
G03Y15819I928J-1181D01*
G01Y15071D01*
X1097438Y15024D01*
G03X1096532Y13395I462J-1324D01*
G03X1096856Y12764I1369J304D01*
G02X1096821Y12210I-305J-259D01*
G03X1097426Y9654I1013J-1110D01*
G01X1097572Y9613D01*
Y1000D01*
X1097200Y628D01*
Y-5685D01*
X1097199Y-5686D01*
G03X1097139Y-8667I154J-1494D01*
G01X1097205Y-8676D01*
X1097352Y-8823D01*
Y-16652D01*
X1096272Y-17731D01*
G02X1096076Y-17838I-282J283D01*
G02X1096016Y-17847I-89J390D01*
G01X1096007D01*
G02X1095590Y-17448I-17J399D01*
G01Y-11326D01*
X1095338D01*
Y-11028D01*
X1095415Y-10968D01*
G03X1093561I-927J1182D01*
G01X1093638Y-11028D01*
Y-11326D01*
X1093386D01*
Y-18428D01*
X1094637D01*
G02X1094892Y-18545I-29J-399D01*
G01Y-19111D01*
X1094873Y-19130D01*
G03X1094181Y-19500I289J-1372D01*
G01X1087362D01*
X1087314Y-19370D01*
G03X1087150Y-19057I-1314J-489D01*
G02X1087458Y-18428I328J229D01*
G01X1088896D01*
Y-11326D01*
X1088474D01*
Y-11018D01*
X1088550Y-10968D01*
G03X1087040I-755J1182D01*
G01X1087116Y-11018D01*
Y-11326D01*
X1086694D01*
Y-18102D01*
G02X1086228Y-18477I-400J20D01*
G03X1084686Y-19370I-228J-1383D01*
G01X1084637Y-19500D01*
X1073854D01*
X1073804Y-19374D01*
G03X1073633Y-19064I-1303J-517D01*
G02X1073937Y-18428I323J236D01*
G01X1075510D01*
Y-11326D01*
X1075088D01*
Y-11018D01*
X1075164Y-10968D01*
G03X1073654I-755J1182D01*
G01X1073730Y-11018D01*
Y-11326D01*
X1073308D01*
Y-18153D01*
G02X1072817Y-18523I-400J20D01*
G03X1072550Y-18488I-315J-1366D01*
G02X1072164Y-18108I14J400D01*
G01Y-11326D01*
X1069962D01*
Y-18428D01*
X1071063D01*
G02X1071367Y-19064I-19J-400D01*
G03X1071196Y-19374I1132J-827D01*
G01X1071146Y-19500D01*
X1060476D01*
G03X1059168Y-18493I-1345J-394D01*
G02X1058778Y-18113I10J400D01*
G01Y-11326D01*
X1056576D01*
Y-18226D01*
G02X1056052Y-18586I-400J20D01*
G03X1055630Y-18518I-431J-1334D01*
G02X1055432Y-18318I2J200D01*
G01Y-11326D01*
X1055163D01*
Y-11033D01*
X1055234Y-10973D01*
G03X1053426I-904J1072D01*
G01X1053497Y-11033D01*
Y-11326D01*
X1053228D01*
Y-18162D01*
G02X1052802Y-18561I-400J0D01*
G03X1051433Y-19382I-92J-1399D01*
G01X1051379Y-19500D01*
X958074D01*
G37*
G36*
G01X994250Y348950D02*
X993096Y350104D01*
X993081Y350133D01*
G03X992450Y350764I-1255J-624D01*
G01X992421Y350779D01*
X991850Y351350D01*
Y352700D01*
X989890Y354660D01*
Y356222D01*
X988800Y357312D01*
Y357896D01*
X988931Y357944D01*
G03Y360576I-485J1316D01*
G01X988800Y360624D01*
Y361796D01*
X988931Y361844D01*
G03Y364476I-485J1316D01*
G01X988800Y364524D01*
Y365593D01*
X988935Y365640D01*
G03Y368480I-489J1420D01*
G01X988800Y368527D01*
Y369595D01*
X988931Y369643D01*
G03X989690Y371605I-485J1315D01*
G03X988713Y372335I-1244J-646D01*
G01X988653Y372347D01*
X988000Y373000D01*
Y373277D01*
G02X988231Y373475I200J0D01*
G03X989840Y375013I215J1385D01*
G03X988410Y376262I-1394J-153D01*
G02X988000Y376661I-10J400D01*
G01Y376959D01*
G02X988410Y377358I400J-1D01*
G03Y380162I36J1402D01*
G02X988000Y380561I-10J400D01*
G01Y380950D01*
X988222Y381172D01*
X988315Y381164D01*
G03X989550Y383678I131J1496D01*
G01X989420Y383820D01*
X989600Y384000D01*
Y393700D01*
X988900Y394400D01*
X988866D01*
Y398926D01*
X988646Y399146D01*
Y414854D01*
X987618Y415882D01*
Y422000D01*
X985500Y424118D01*
Y447500D01*
X970959Y462041D01*
Y486959D01*
X958622Y499296D01*
Y508500D01*
X956000Y511122D01*
Y511628D01*
G02X956701Y511892I400J0D01*
G03Y513696I1073J902D01*
G02X956000Y513960I-301J264D01*
G01Y516487D01*
G02X956588Y516839I400J-1D01*
G03Y519275I695J1218D01*
G02X956000Y519627I-188J353D01*
G01Y520372D01*
X958384D01*
Y527586D01*
G03X956755Y527935I-578J1277D01*
G02X956410Y527477I-395J-61D01*
G01X956155D01*
X955943Y527689D01*
Y531809D01*
G02X956622Y532095I400J0D01*
G03Y534105I978J1005D01*
G02X955943Y534391I-279J286D01*
G01Y535420D01*
G02X956552Y535761I400J0D01*
G03Y538153I731J1196D01*
G02X955943Y538494I-209J341D01*
G01Y546663D01*
G02X956552Y547004I400J0D01*
G03Y549396I731J1196D01*
G02X955943Y549737I-209J341D01*
G01Y550816D01*
G02X956644Y551078I400J-1D01*
G03Y552922I1057J922D01*
G02X955943Y553184I-301J263D01*
G01Y554320D01*
G02X956552Y554661I400J0D01*
G03Y557053I731J1196D01*
G02X955943Y557394I-209J341D01*
G01Y558115D01*
X956000Y558172D01*
X956381D01*
X958384D01*
Y565274D01*
X958370D01*
Y565573D01*
X958448Y565633D01*
G03X956519Y567645I-855J1111D01*
G02X956000Y568027I-119J382D01*
G01Y569556D01*
G02X956666Y569854I400J0D01*
G03Y571946I934J1046D01*
G02X956025Y572108I-266J299D01*
G01X955957Y572231D01*
Y573211D01*
G02X956563Y573554I400J0D01*
G03Y575960I720J1203D01*
G02X955957Y576303I-206J343D01*
G01Y586891D01*
X956005Y586939D01*
G02X956634Y587198I394J-64D01*
G03X958416Y589356I823J1135D01*
G02X958426Y589947I274J291D01*
G03X958325Y592134I-926J1053D01*
G02X958179Y592578I235J323D01*
G03X956432Y594772I-896J1079D01*
G02X956000Y595170I-32J398D01*
G01Y595972D01*
X958384D01*
Y603074D01*
X956122D01*
X955872Y603325D01*
Y610108D01*
G02X956496Y610439I400J0D01*
G03Y612761I787J1161D01*
G02X955872Y613092I-224J331D01*
G01Y618422D01*
X959325Y621875D01*
X1048233D01*
G03X1049471Y621199I1200J725D01*
G02X1049882Y620799I11J-400D01*
G01Y613679D01*
G03X1052046Y611595I1101J-1022D01*
G03X1052086Y613679I-1062J1063D01*
G01Y621184D01*
X1050892D01*
G02X1050590Y621810I28J400D01*
G03X1050820Y622406I-1158J789D01*
G01X1050844Y622578D01*
X1061519D01*
X1061544Y622406D01*
G03X1062883Y621199I1388J194D01*
G02X1063268Y620800I-15J-400D01*
G01Y613679D01*
G03X1065472Y613677I1101J-1022D01*
G01Y621184D01*
X1064392D01*
G02X1064090Y621810I28J400D01*
G03X1064320Y622406I-1158J789D01*
G01X1064344Y622578D01*
X1075520D01*
X1075544Y622406D01*
G03X1076513Y621262I1388J194D01*
G01X1076654Y621218D01*
Y614082D01*
Y613678D01*
G03X1078856I1101J-1021D01*
G01Y614082D01*
Y621184D01*
X1078392D01*
G02X1078090Y621810I28J400D01*
G03X1078320Y622406I-1158J789D01*
G01X1078344Y622578D01*
X1094042D01*
X1094072Y622414D01*
G03X1094324Y621815I1478J269D01*
G02X1094017Y621184I-327J-231D01*
G01X1093386D01*
Y614082D01*
X1095590D01*
Y621172D01*
X1095762Y621196D01*
G03X1096110Y621290I-215J1486D01*
G01X1096233Y621339D01*
X1097988Y619584D01*
Y614548D01*
G02X1097543Y614151I-400J1D01*
G03Y611167I-169J-1492D01*
G02X1097988Y610770I45J-398D01*
G01Y609107D01*
G02X1097538Y608710I-400J0D01*
G03Y605730I-186J-1490D01*
G02X1097988Y605333I50J-397D01*
G01Y592377D01*
X1097848Y592332D01*
G03X1096927Y590290I452J-1432D01*
G02X1096726Y589763I-365J-162D01*
G03X1097537Y586905I618J-1369D01*
G02X1097988Y586508I51J-397D01*
G01Y576748D01*
G02X1097543Y576351I-400J1D01*
G03X1096129Y575699I-169J-1492D01*
G02X1095643Y575554I-331J224D01*
G03X1095279Y575916I-1154J-796D01*
G01X1095191Y575976D01*
Y576282D01*
X1095590D01*
Y583384D01*
X1093386D01*
Y576282D01*
X1093789D01*
Y575976D01*
X1093701Y575916D01*
G03X1095697Y574044I789J-1159D01*
G02X1096192Y573933I180J-357D01*
G03X1097543Y573367I1182J926D01*
G02X1097988Y572970I45J-398D01*
G01Y571307D01*
G02X1097538Y570910I-400J0D01*
G03X1097259Y567921I-186J-1490D01*
G03X1097887Y567799I574J1279D01*
G02X1097988Y567533I-299J-266D01*
G01Y554577D01*
X1097848Y554532D01*
G03X1096927Y552490I452J-1432D01*
G02X1096726Y551963I-365J-162D01*
G03X1096892Y549162I618J-1369D01*
G03X1097602Y548539I1226J681D01*
G03X1097829Y548471I514J1304D01*
G01X1097988Y548437D01*
Y538948D01*
G02X1097543Y538551I-400J1D01*
G03X1096129Y537899I-169J-1492D01*
G02X1095643Y537754I-331J224D01*
G03X1095279Y538116I-1154J-796D01*
G01X1095191Y538176D01*
Y538482D01*
X1095590D01*
Y545584D01*
X1093386D01*
Y538482D01*
X1093789D01*
Y538176D01*
X1093701Y538116D01*
G03X1095697Y536244I789J-1159D01*
G02X1096192Y536133I180J-357D01*
G03X1097254Y535562I1182J926D01*
G03X1097301Y535531I795J1155D01*
G03X1097513Y535424I736J1194D01*
G02X1097528Y535060I-75J-185D01*
G03X1096869Y533263I632J-1251D01*
G02X1096763Y533001I-184J-78D01*
G03X1097040Y530151I589J-1381D01*
G03X1097311Y529945I978J1005D01*
G03X1097853Y529764I706J1211D01*
G01X1097988Y529744D01*
Y516777D01*
X1097848Y516732D01*
G03X1096927Y514690I452J-1432D01*
G02X1096726Y514163I-365J-162D01*
G03X1097537Y511305I618J-1369D01*
G02X1097988Y510908I51J-397D01*
G01Y506591D01*
X1091249Y499852D01*
Y494850D01*
X1068450Y472051D01*
Y458600D01*
X1067300Y457450D01*
Y439750D01*
X1068450Y438600D01*
Y410750D01*
X1067800Y410100D01*
X1067586D01*
X1065836Y408350D01*
Y394818D01*
X1062355Y391337D01*
G02X1061767Y391363I-282J283D01*
G03X1059791Y389387I-1073J-903D01*
G02X1059817Y388799I-257J-306D01*
G01X1056250Y385232D01*
Y359150D01*
X1053350Y356250D01*
X1052450D01*
X1050358Y358342D01*
X1050449Y358479D01*
G03X1049500Y360645I-1165J781D01*
G03X1047975Y359763I-216J-1385D01*
G03X1047995Y358708I1309J-503D01*
G02X1047628Y358150I-367J-158D01*
G01X1047026D01*
G03X1044782I-1122J-841D01*
G01X1044180D01*
G02X1043813Y358708I0J400D01*
G03X1041235I-1289J552D01*
G02X1040868Y358150I-367J-158D01*
G01X1040267D01*
G03X1038023I-1122J-841D01*
G01X1037421D01*
G02X1037054Y358708I0J400D01*
G03X1034476I-1289J552D01*
G02X1034109Y358150I-367J-158D01*
G01X1033507D01*
G03X1031263I-1122J-841D01*
G01X1030661D01*
G02X1030294Y358708I0J400D01*
G03X1028325Y360486I-1289J552D01*
G03X1028936Y357860I680J-1226D01*
G02X1029179Y357179I-40J-398D01*
G01X1028737Y356737D01*
X1028682Y356724D01*
G03X1027641Y355683I323J-1364D01*
G01X1027628Y355628D01*
X1026350Y354350D01*
Y351600D01*
X1025663Y350913D01*
X1025583Y350910D01*
G03X1025093Y350806I41J-1401D01*
G03X1024744Y350600I531J-1298D01*
G01X1023987D01*
G02X1023601Y351102I1J400D01*
G03X1020889I-1356J358D01*
G02X1020503Y350600I-387J-102D01*
G01X1019746D01*
G03X1018580Y350882I-881J-1091D01*
G03X1017469Y349634I285J-1373D01*
G01X1017462Y349562D01*
X1016850Y348950D01*
X1015668D01*
X1015656Y348951D01*
G03X1015314I-171J-1391D01*
G01X1015302Y348950D01*
X1013900D01*
G02X1013502Y349385I0J400D01*
G03X1010708I-1397J124D01*
G02X1010310Y348950I-398J-35D01*
G01X1008908D01*
X1008896Y348951D01*
G03X1008554I-171J-1391D01*
G01X1008542Y348950D01*
X1007140D01*
G02X1006742Y349385I0J400D01*
G03X1003948I-1397J124D01*
G02X1003550Y348950I-398J-35D01*
G01X1002148D01*
X1002136Y348951D01*
G03X1001794I-171J-1391D01*
G01X1001782Y348950D01*
X1000381D01*
G02X999983Y349385I0J400D01*
G03X997189I-1397J124D01*
G02X996791Y348950I-398J-35D01*
G01X995389D01*
X995377Y348951D01*
G03X995035I-171J-1391D01*
G01X995023Y348950D01*
X994250D01*
G37*
G36*
G01X1550952Y620054D02*
X1549402Y621604D01*
Y623679D01*
X1550297Y624574D01*
X1550535D01*
G02X1550904Y624020I0J-400D01*
G03X1553492I1294J-541D01*
G02X1553861Y624574I369J154D01*
G01X1555881D01*
G02X1556257Y624038I0J-400D01*
G03X1558813Y622900I1318J-479D01*
G02X1559517Y622904I353J-188D01*
G03X1562070Y624041I1230J672D01*
G02X1562447Y624574I377J133D01*
G01X1564901D01*
G02X1565261Y623998I1J-400D01*
G03X1567673Y622584I1259J-616D01*
G02X1568333Y622580I329J-228D01*
G03X1570147Y622124I1162J785D01*
G02X1570733Y621770I186J-354D01*
G01Y620683D01*
X1570104Y620054D01*
X1550952D01*
G37*
%LPC*%
G75*
G36*
G01X1603820Y433694D02*
G02X1602241Y433668I-770J-1171D01*
G03X1602230Y434329I-231J327D01*
G02X1603809Y434355I770J1171D01*
G03X1603820Y433694I231J-327D01*
G37*
G36*
G01X1685017Y192029D02*
G02X1685249Y190205I1166J-778D01*
G03X1684650Y190129I-266J-298D01*
G02X1684418Y191953I-1166J778D01*
G03X1685017Y192029I266J298D01*
G37*
G36*
G01X1675832Y195852D02*
G03X1675197Y195838I-312J-250D01*
G02X1675158Y197545I-1131J828D01*
G03X1675793Y197559I312J250D01*
G02X1675832Y195852I1131J-828D01*
G37*
G36*
G01X1606022Y557644D02*
Y561645D01*
G02X1607233Y563125I1511J-1D01*
G03X1607452Y563785I-79J393D01*
G02X1616289Y570393I3831J4090D01*
G02X1611415Y562272I-5004J-2520D01*
G02X1609474Y562570I-133J5602D01*
G03X1608983Y562072I-108J-385D01*
G02X1609044Y561654I-1450J-425D01*
G01Y557559D01*
X1609035Y557475D01*
G02X1606022Y557644I-1502J169D01*
G37*
G36*
G01X1514847Y92931D02*
X1514848D01*
Y92928D01*
X1514846D01*
Y92924D01*
X1514847D01*
G02X1514846Y92853I-1512J-14D01*
G01Y92836D01*
X1514844Y92817D01*
G02X1511844Y92664I-1509J102D01*
G01X1511820Y92780D01*
Y92784D01*
X1511819D01*
X1511496Y96414D01*
X1511497D01*
Y96415D01*
X1511501Y96542D01*
G02X1512516Y97974I1512J4D01*
G02X1513224Y98044I499J-1427D01*
G02X1514519Y96682I-211J-1498D01*
G01X1514529Y96683D01*
X1514541Y96554D01*
X1514534D01*
X1514535Y96548D01*
X1514541D01*
X1514852Y93055D01*
X1514849Y93053D01*
X1514848D01*
X1514843Y93048D01*
X1514844Y93026D01*
G02X1514847Y92931I-1509J-95D01*
G37*
G36*
G01X1756912Y37661D02*
Y37615D01*
X1756908Y37577D01*
G02X1754912Y36269I-1507J123D01*
G01X1754909Y36259D01*
X1751506Y37425D01*
Y37430D01*
X1751440Y37460D01*
G02X1751250Y37551I557J1406D01*
G03X1751065Y37198I-78J-184D01*
G02X1751762Y35935I-815J-1273D01*
G01Y35840D01*
X1751752Y35756D01*
G02X1750250Y34414I-1502J170D01*
G01X1746550D01*
G02X1745673Y37156I0J1511D01*
G03X1745687Y37796I-233J325D01*
G02X1747684Y38073I865J1104D01*
G03X1748006Y37436I323J-237D01*
G01X1750251D01*
G02X1750363Y37432I2J-1511D01*
G03X1750741Y38027I29J399D01*
G02X1752488Y40296I1260J837D01*
G01X1752491Y40306D01*
X1755896Y39140D01*
Y39138D01*
X1756013Y39082D01*
G02X1756350Y38877I-611J-1383D01*
G01Y38876D01*
G02X1756360Y38868I-939J-1184D01*
G01X1756362D01*
G02X1756912Y37710I-963J-1167D01*
G01Y37702D01*
G02Y37661I-1512J-20D01*
G37*
G36*
G01X1928253Y535242D02*
X1930653D01*
G02Y529840I0J-2701D01*
G01X1928253D01*
G02Y535242I0J2701D01*
G37*
G36*
G01X1926853Y513904D02*
X1932053D01*
G02Y508500I0J-2702D01*
G01X1926853D01*
G02Y513904I0J2702D01*
G37*
G36*
G01X1951554Y127860D02*
X1958054D01*
G02Y112456I0J-7702D01*
G01X1951554D01*
G02Y127860I0J7702D01*
G37*
G36*
G01X1884727Y535242D02*
X1889927D01*
G02Y529840I0J-2701D01*
G01X1884727D01*
G02Y535242I0J2701D01*
G37*
G36*
G01X1886127Y513904D02*
X1888527D01*
G02Y508500I0J-2702D01*
G01X1886127D01*
G02Y513904I0J2702D01*
G37*
G36*
G01X1833443Y127860D02*
X1839943D01*
G02Y112456I0J-7702D01*
G01X1833443D01*
G02Y127860I0J7702D01*
G37*
G36*
G01X1857035Y602728D02*
X1854331D01*
G02Y618532I1J7902D01*
G01X1857044D01*
G03X1860510Y619640I-2J5982D01*
G02X1860511Y601620I7622J-9010D01*
G03X1857035Y602728I-3476J-4898D01*
G37*
G36*
G01Y-15776D02*
X1854331D01*
G02Y28I1J7902D01*
G01X1857044D01*
G03X1860510Y1136I-2J5982D01*
G02X1860511Y-16884I7622J-9010D01*
G03X1857035Y-15776I-3476J-4898D01*
G37*
G36*
G01X1684261Y616623D02*
X1687214Y611111D01*
G02X1683070Y608889I-2072J-1111D01*
G01X1680117Y614401D01*
G02X1684261Y616623I2072J1111D01*
G37*
G36*
G01X1675404Y616622D02*
X1678356Y611110D01*
G02X1674210Y608890I-2073J-1110D01*
G01X1671258Y614402D01*
G02X1675404Y616622I2073J1110D01*
G37*
G36*
G01X1684261Y601662D02*
X1687214Y596150D01*
G02X1683070Y593928I-2072J-1111D01*
G01X1680117Y599440D01*
G02X1684261Y601662I2072J1111D01*
G37*
G36*
G01X1675404Y601661D02*
X1678356Y596149D01*
G02X1674210Y593929I-2073J-1110D01*
G01X1671258Y599441D01*
G02X1675404Y601661I2073J1110D01*
G37*
G36*
G01X1408216Y602728D02*
X1405512D01*
G02Y618532I1J7902D01*
G01X1408225D01*
G03X1411691Y619640I-2J5982D01*
G02X1411692Y601620I7622J-9010D01*
G03X1408216Y602728I-3476J-4898D01*
G37*
G36*
G01Y-15776D02*
X1405512D01*
G02Y28I1J7902D01*
G01X1408225D01*
G03X1411691Y1136I-2J5982D01*
G02X1411692Y-16884I7622J-9010D01*
G03X1408216Y-15776I-3476J-4898D01*
G37*
G36*
G01X679869Y602728D02*
X677165D01*
G02Y618532I1J7902D01*
G01X679878D01*
G03X683344Y619640I-2J5982D01*
G02X683345Y601620I7622J-9010D01*
G03X679869Y602728I-3476J-4898D01*
G37*
G36*
G01Y-15776D02*
X677165D01*
G02Y28I1J7902D01*
G01X679878D01*
G03X683344Y1136I-2J5982D01*
G02X683345Y-16884I7622J-9010D01*
G03X679869Y-15776I-3476J-4898D01*
G37*
G36*
G01X2704Y602728D02*
X0D01*
G02Y618532I1J7902D01*
G01X2713D01*
G03X6179Y619640I-2J5982D01*
G02X6180Y601620I7622J-9010D01*
G03X2704Y602728I-3476J-4898D01*
G37*
G36*
G01X1313465Y618530D02*
G03X1312887I-289J-277D01*
G02Y620472I-1011J971D01*
G03X1313465I289J277D01*
G02Y618530I1011J-971D01*
G37*
G36*
G01X1591926Y619723D02*
G03X1592512Y619711I299J266D01*
G02X1592474Y617801I1007J-975D01*
G03X1591888Y617813I-299J-266D01*
G02X1591926Y619723I-1007J975D01*
G37*
G36*
G01X1602539Y617279D02*
G03X1601961I-289J-277D01*
G02Y619221I-1011J971D01*
G03X1602539I289J277D01*
G02Y617279I1011J-971D01*
G37*
G36*
G01X1962583Y618411D02*
G03Y617789I252J-311D01*
G02X1960817I-883J-1089D01*
G03Y618411I-252J311D01*
G02X1962583I883J1089D01*
G37*
G36*
G01X713345Y616607D02*
G03X712901Y616223I-44J-398D01*
G02X711655Y617667I-1401J51D01*
G03X712099Y618051I44J398D01*
G02X713345Y616607I1401J-51D01*
G37*
G36*
G01X1931383Y617811D02*
G03Y617189I252J-311D01*
G02X1929617I-883J-1089D01*
G03Y617811I-252J311D01*
G02X1931383I883J1089D01*
G37*
G36*
G01X1372904Y615115D02*
G03X1372297Y615025I-266J-298D01*
G02X1372034Y616802I-1197J731D01*
G03X1372641Y616892I266J298D01*
G02X1372904Y615115I1197J-731D01*
G37*
G36*
G01X629517Y611700D02*
G03X629012Y611466I-132J-378D01*
G02X628165Y613297I-1307J507D01*
G03X628670Y613531I132J378D01*
G02X629517Y611700I1307J-507D01*
G37*
G36*
G01X656071Y613089D02*
G03Y612511I277J-289D01*
G02X654129I-971J-1011D01*
G03Y613089I-277J289D01*
G02X656071I971J1011D01*
G37*
G36*
G01X1533154Y612419D02*
G03X1533178Y611832I283J-282D01*
G02X1531276Y611753I-908J-1068D01*
G03X1531252Y612340I-283J282D01*
G02X1531212Y612375I903J1072D01*
G03X1530665Y612370I-271J-294D01*
G02X1528802Y612305I-968J1014D01*
G03X1528215Y612219I-255J-308D01*
G02X1527945Y614079I-1165J781D01*
G03X1528532Y614165I255J308D01*
G02X1528563Y614209I1162J-786D01*
G03X1528485Y614509I-161J118D01*
G02X1530296Y615109I582J1275D01*
G03X1530435Y614576I350J-193D01*
G02X1530645Y614417I-738J-1192D01*
G03X1531192Y614422I271J294D01*
G02X1533154Y612419I969J-1014D01*
G37*
G36*
G01X1383607Y611122D02*
G03X1383603Y610567I286J-280D01*
G02X1381584Y610582I-1017J-965D01*
G03X1381588Y611137I-286J280D01*
G02X1383607Y611122I1017J965D01*
G37*
G36*
G01X1652380Y614210D02*
Y609115D01*
X1652371Y609031D01*
G02X1649358Y609200I-1502J169D01*
G01Y614201D01*
G02X1652380Y614210I1511J-1D01*
G37*
G36*
G01X1637045Y616571D02*
X1637046Y616569D01*
X1639942Y611164D01*
X1639943Y611162D01*
G02X1635798Y608941I-2045J-1162D01*
G01X1635797Y608943D01*
X1632901Y614348D01*
X1632900Y614350D01*
G02X1637045Y616571I2045J1162D01*
G37*
G36*
G01X1628179Y616586D02*
X1628180Y616585D01*
X1631092Y611148D01*
X1631093Y611146D01*
G02X1626947Y608926I-2054J-1146D01*
G01X1626946Y608927D01*
X1624034Y614364D01*
X1624033Y614366D01*
G02X1628179Y616586I2054J1146D01*
G37*
G36*
G01X1505671Y610089D02*
G03Y609511I277J-289D01*
G02X1503729I-971J-1011D01*
G03Y610089I-277J289D01*
G02X1505671I971J1011D01*
G37*
G36*
G01X1307614Y609031D02*
G03X1307604Y608489I289J-276D01*
G02X1305542Y608527I-1049J-931D01*
G03X1305552Y609069I-289J276D01*
G02X1307614Y609031I1049J931D01*
G37*
G36*
G01X1225735Y608978D02*
G03X1225740Y608390I274J-292D01*
G02X1223839Y608371I-940J-1040D01*
G03X1223834Y608959I-274J292D01*
G02X1225735Y608978I940J1040D01*
G37*
G36*
G01X1188924D02*
G03X1188929Y608390I274J-292D01*
G02X1187028Y608371I-940J-1040D01*
G03X1187023Y608959I-274J292D01*
G02X1188924Y608978I940J1040D01*
G37*
G36*
G01X1152113D02*
G03X1152118Y608390I274J-292D01*
G02X1150217Y608371I-940J-1040D01*
G03X1150212Y608959I-274J292D01*
G02X1152113Y608978I940J1040D01*
G37*
G36*
G01X1115301D02*
G03X1115306Y608390I274J-292D01*
G02X1113405Y608371I-940J-1040D01*
G03X1113400Y608959I-274J292D01*
G02X1115301Y608978I940J1040D01*
G37*
G36*
G01X934593D02*
G03X934598Y608390I274J-292D01*
G02X932697Y608371I-940J-1040D01*
G03X932692Y608959I-274J292D01*
G02X934593Y608978I940J1040D01*
G37*
G36*
G01X897782D02*
G03X897787Y608390I274J-292D01*
G02X895886Y608371I-940J-1040D01*
G03X895881Y608959I-274J292D01*
G02X897782Y608978I940J1040D01*
G37*
G36*
G01X860971D02*
G03X860976Y608390I274J-292D01*
G02X859075Y608371I-940J-1040D01*
G03X859070Y608959I-274J292D01*
G02X860971Y608978I940J1040D01*
G37*
G36*
G01X824160D02*
G03X824165Y608390I274J-292D01*
G02X822264Y608371I-940J-1040D01*
G03X822259Y608959I-274J292D01*
G02X824160Y608978I940J1040D01*
G37*
G36*
G01X785453Y608371D02*
G03X785448Y608959I-274J292D01*
G02X787349Y608978I940J1040D01*
G03X787354Y608390I274J-292D01*
G02X785453Y608371I-940J-1040D01*
G37*
G36*
G01X576127Y608978D02*
G03X576132Y608390I274J-292D01*
G02X574231Y608371I-940J-1040D01*
G03X574226Y608959I-274J292D01*
G02X576127Y608978I940J1040D01*
G37*
G36*
G01X539316D02*
G03X539321Y608390I274J-292D01*
G02X537420Y608371I-940J-1040D01*
G03X537415Y608959I-274J292D01*
G02X539316Y608978I940J1040D01*
G37*
G36*
G01X502505D02*
G03X502510Y608390I274J-292D01*
G02X500609Y608371I-940J-1040D01*
G03X500604Y608959I-274J292D01*
G02X502505Y608978I940J1040D01*
G37*
G36*
G01X463797Y608371D02*
G03X463792Y608959I-274J292D01*
G02X465693Y608978I940J1040D01*
G03X465698Y608390I274J-292D01*
G02X463797Y608371I-940J-1040D01*
G37*
G36*
G01X284985Y608978D02*
G03X284990Y608390I274J-292D01*
G02X283089Y608371I-940J-1040D01*
G03X283084Y608959I-274J292D01*
G02X284985Y608978I940J1040D01*
G37*
G36*
G01X248174D02*
G03X248179Y608390I274J-292D01*
G02X246278Y608371I-940J-1040D01*
G03X246273Y608959I-274J292D01*
G02X248174Y608978I940J1040D01*
G37*
G36*
G01X211363D02*
G03X211368Y608390I274J-292D01*
G02X209467Y608371I-940J-1040D01*
G03X209462Y608959I-274J292D01*
G02X211363Y608978I940J1040D01*
G37*
G36*
G01X174552D02*
G03X174557Y608390I274J-292D01*
G02X172656Y608371I-940J-1040D01*
G03X172651Y608959I-274J292D01*
G02X174552Y608978I940J1040D01*
G37*
G36*
G01X135845Y608371D02*
G03X135840Y608959I-274J292D01*
G02X137741Y608978I940J1040D01*
G03X137746Y608390I274J-292D01*
G02X135845Y608371I-940J-1040D01*
G37*
G36*
G01X1230841Y608734D02*
G03Y608155I276J-290D01*
G02X1228907I-967J-1015D01*
G03Y608734I-276J289D01*
G02X1230841I967J1015D01*
G37*
G36*
G01X1194030D02*
G03Y608155I276J-290D01*
G02X1192096I-967J-1015D01*
G03Y608734I-276J289D01*
G02X1194030I967J1015D01*
G37*
G36*
G01X1157219D02*
G03Y608155I276J-290D01*
G02X1155285I-967J-1015D01*
G03Y608734I-276J289D01*
G02X1157219I967J1015D01*
G37*
G36*
G01X1120407D02*
G03Y608155I276J-290D01*
G02X1118473I-967J-1015D01*
G03Y608734I-276J289D01*
G02X1120407I967J1015D01*
G37*
G36*
G01X939699D02*
G03Y608155I276J-290D01*
G02X937765I-967J-1015D01*
G03Y608734I-276J289D01*
G02X939699I967J1015D01*
G37*
G36*
G01X902888D02*
G03Y608155I276J-290D01*
G02X900954I-967J-1015D01*
G03Y608734I-276J289D01*
G02X902888I967J1015D01*
G37*
G36*
G01X866077D02*
G03Y608155I276J-290D01*
G02X864143I-967J-1015D01*
G03Y608734I-276J289D01*
G02X866077I967J1015D01*
G37*
G36*
G01X829266D02*
G03Y608155I276J-290D01*
G02X827332I-967J-1015D01*
G03Y608734I-276J289D01*
G02X829266I967J1015D01*
G37*
G36*
G01X792455D02*
G03Y608155I276J-290D01*
G02X790521I-967J-1015D01*
G03Y608734I-276J289D01*
G02X792455I967J1015D01*
G37*
G36*
G01X581233D02*
G03Y608155I276J-290D01*
G02X579299I-967J-1015D01*
G03Y608734I-276J289D01*
G02X581233I967J1015D01*
G37*
G36*
G01X544422D02*
G03Y608155I276J-290D01*
G02X542488I-967J-1015D01*
G03Y608734I-276J289D01*
G02X544422I967J1015D01*
G37*
G36*
G01X507611D02*
G03Y608155I276J-290D01*
G02X505677I-967J-1015D01*
G03Y608734I-276J289D01*
G02X507611I967J1015D01*
G37*
G36*
G01X470800D02*
G03Y608155I276J-290D01*
G02X468865I-968J-1015D01*
G03Y608734I-276J289D01*
G02X470800I967J1015D01*
G37*
G36*
G01X290091D02*
G03Y608155I276J-290D01*
G02X288157I-967J-1015D01*
G03Y608734I-276J289D01*
G02X290091I967J1015D01*
G37*
G36*
G01X253280D02*
G03Y608155I276J-290D01*
G02X251346I-967J-1015D01*
G03Y608734I-276J289D01*
G02X253280I967J1015D01*
G37*
G36*
G01X216469D02*
G03Y608155I276J-290D01*
G02X214535I-967J-1015D01*
G03Y608734I-276J289D01*
G02X216469I967J1015D01*
G37*
G36*
G01X179658D02*
G03Y608155I276J-290D01*
G02X177724I-967J-1015D01*
G03Y608734I-276J289D01*
G02X179658I967J1015D01*
G37*
G36*
G01X142847D02*
G03Y608155I276J-290D01*
G02X140913I-967J-1015D01*
G03Y608734I-276J289D01*
G02X142847I967J1015D01*
G37*
G36*
G01X1545090Y606559D02*
G03X1545469Y606114I397J-46D01*
G02X1544014Y604873I-62J-1401D01*
G03X1543635Y605318I-397J46D01*
G02X1542337Y606379I62J1401D01*
G03X1541774Y606642I-388J-97D01*
G02X1542522Y608243I-612J1261D01*
G03X1543085Y607980I388J97D01*
G02X1545090Y606559I612J-1261D01*
G37*
G36*
G01X1605380Y608460D02*
Y604365D01*
X1605371Y604281D01*
G02X1602358Y604450I-1502J169D01*
G01Y608451D01*
G02X1605380Y608460I1511J-1D01*
G37*
G36*
G01X1659880Y606260D02*
Y602165D01*
X1659871Y602081D01*
G02X1656858Y602250I-1502J169D01*
G01Y606251D01*
G02X1659880Y606260I1511J-1D01*
G37*
G36*
G01X1572237Y600367D02*
G03X1571718Y600360I-255J-308D01*
G02X1571683Y602796I-1058J1203D01*
G03X1572202Y602803I255J308D01*
G02X1572237Y600367I1058J-1203D01*
G37*
G36*
G01X1804772Y601902D02*
G03X1804178Y601662I-207J-342D01*
G02X1803850Y604145I-3193J841D01*
G03X1804486Y604068I347J199D01*
G02X1804772Y601902I1014J-968D01*
G37*
G36*
G01X1614860Y603260D02*
Y599165D01*
X1614851Y599081D01*
G02X1611838Y599250I-1502J169D01*
G01Y603251D01*
G02X1614860Y603260I1511J-1D01*
G37*
G36*
G01X1325210Y599127D02*
G03Y598573I288J-277D01*
G02X1323190I-1010J-973D01*
G03Y599127I-288J277D01*
G02X1323229Y601111I1010J973D01*
G03Y601689I-277J289D01*
G02X1323154Y603634I971J1011D01*
G03Y604166I-298J266D01*
G02Y606034I1046J934D01*
G03Y606566I-298J266D01*
G02X1323229Y608511I1046J934D01*
G03Y609089I-277J289D01*
G02X1325171I971J1011D01*
G03Y608511I277J-289D01*
G02X1325246Y606566I-971J-1011D01*
G03Y606034I298J-266D01*
G02Y604166I-1046J-934D01*
G03Y603634I298J-266D01*
G02X1325171Y601689I-1046J-934D01*
G03Y601111I277J-289D01*
G02X1325210Y599127I-971J-1011D01*
G37*
G36*
G01X713010Y598527D02*
G03Y597973I288J-277D01*
G02X710990I-1010J-973D01*
G03Y598527I-288J277D01*
G02X713010I1010J973D01*
G37*
G36*
G01X1589293Y595924D02*
G03X1588711Y595918I-288J-277D01*
G02X1586692Y595871I-1032J949D01*
G03X1586137Y595879I-282J-284D01*
G02X1586166Y597898I-958J1023D01*
G03X1586721Y597890I282J284D01*
G02X1588690Y597839I959J-1023D01*
G03X1589272Y597845I288J277D01*
G02X1589293Y595924I1032J-949D01*
G37*
G36*
G01X709771Y598289D02*
G03Y597711I277J-289D01*
G02X707829I-971J-1011D01*
G03Y598289I-277J289D01*
G02X709771I971J1011D01*
G37*
G36*
G01X1637045Y601610D02*
X1637046Y601608D01*
X1639942Y596203D01*
X1639943Y596201D01*
G02X1635798Y593980I-2045J-1162D01*
G01X1635797Y593982D01*
X1632901Y599387D01*
X1632900Y599389D01*
G02X1637045Y601610I2045J1162D01*
G37*
G36*
G01X1628179Y601625D02*
X1628180Y601624D01*
X1631092Y596187D01*
X1631093Y596185D01*
G02X1626947Y593965I-2054J-1146D01*
G01X1626946Y593966D01*
X1624034Y599403D01*
X1624033Y599405D01*
G02X1628179Y601625I2054J1146D01*
G37*
G36*
G01X1654010Y597960D02*
Y593865D01*
X1654001Y593781D01*
G02X1650988Y593950I-1502J169D01*
G01Y597951D01*
G02X1654010Y597960I1511J-1D01*
G37*
G36*
G01X754907Y592660D02*
G03X754330Y592649I-283J-282D01*
G02X754293Y594590I-1030J951D01*
G03X754870Y594601I283J282D01*
G02X754907Y592660I1030J-951D01*
G37*
G36*
G01X1801343Y595110D02*
G03X1801349Y594538I283J-283D01*
G02X1799387Y594518I-971J-1011D01*
G03X1799381Y595090I-283J283D01*
G02X1801343Y595110I971J1011D01*
G37*
G36*
G01X1710951Y594470D02*
G03X1710940Y593893I271J-294D01*
G02X1708999Y593930I-990J-993D01*
G03X1709010Y594507I-271J294D01*
G02X1710951Y594470I990J993D01*
G37*
G36*
G01X1605430Y596760D02*
Y592665D01*
X1605421Y592581D01*
G02X1602408Y592750I-1502J169D01*
G01Y596751D01*
G02X1605430Y596760I1511J-1D01*
G37*
G36*
G01X1718962Y593631D02*
G03X1718956Y593035I264J-301D01*
G02X1717083Y593055I-948J-1033D01*
G03X1717089Y593651I-264J301D01*
G02X1717027Y595657I948J1033D01*
G03Y596211I-288J277D01*
G02X1719047I1010J973D01*
G03Y595657I288J-277D01*
G02X1718962Y593631I-1010J-972D01*
G37*
G36*
G01X1554589Y590129D02*
G03X1554011I-289J-277D01*
G02Y592071I-1011J971D01*
G03X1554589I289J277D01*
G02Y590129I1011J-971D01*
G37*
G36*
G01X648104Y592592D02*
G03X648419Y592084I383J-114D01*
G02X646836Y591102I-239J-1382D01*
G03X646521Y591610I-383J114D01*
G02X645381Y592738I239J1382D01*
G03X644880Y593050I-393J-73D01*
G02X645879Y594654I-380J1350D01*
G03X646380Y594342I393J73D01*
G02X648104Y592592I380J-1350D01*
G37*
G36*
G01X2455Y591389D02*
G03X2419Y590786I244J-317D01*
G02X584Y590894I-980J-1003D01*
G03X620Y591497I-244J317D01*
G02X506Y591623I981J1002D01*
G03X194I-156J-125D01*
G02X73Y593510I-1094J877D01*
G03X627I277J288D01*
G02X2455Y591389I972J-1010D01*
G37*
G36*
G01X1763216Y590944D02*
G03Y590666I144J-139D01*
G02X1760908I-1154J-1111D01*
G03Y590944I-144J139D01*
G02X1763216I1154J1111D01*
G37*
G36*
G01X1230845Y590103D02*
G03Y589525I277J-289D01*
G02X1228903I-971J-1011D01*
G03Y590103I-277J289D01*
G02X1230845I971J1011D01*
G37*
G36*
G01X1194034D02*
G03Y589525I277J-289D01*
G02X1192092I-971J-1011D01*
G03Y590103I-277J289D01*
G02X1194034I971J1011D01*
G37*
G36*
G01X1157223D02*
G03Y589525I277J-289D01*
G02X1155281I-971J-1011D01*
G03Y590103I-277J289D01*
G02X1157223I971J1011D01*
G37*
G36*
G01X1120411D02*
G03Y589525I277J-289D01*
G02X1118469I-971J-1011D01*
G03Y590103I-277J289D01*
G02X1120411I971J1011D01*
G37*
G36*
G01X939703D02*
G03Y589525I277J-289D01*
G02X937761I-971J-1011D01*
G03Y590103I-277J289D01*
G02X939703I971J1011D01*
G37*
G36*
G01X902892D02*
G03Y589525I277J-289D01*
G02X900950I-971J-1011D01*
G03Y590103I-277J289D01*
G02X902892I971J1011D01*
G37*
G36*
G01X866081D02*
G03Y589525I277J-289D01*
G02X864139I-971J-1011D01*
G03Y590103I-277J289D01*
G02X866081I971J1011D01*
G37*
G36*
G01X829270D02*
G03Y589525I277J-289D01*
G02X827328I-971J-1011D01*
G03Y590103I-277J289D01*
G02X829270I971J1011D01*
G37*
G36*
G01X792459D02*
G03Y589525I277J-289D01*
G02X790517I-971J-1011D01*
G03Y590103I-277J289D01*
G02X792459I971J1011D01*
G37*
G36*
G01X581237D02*
G03Y589525I277J-289D01*
G02X579295I-971J-1011D01*
G03Y590103I-277J289D01*
G02X581237I971J1011D01*
G37*
G36*
G01X544426D02*
G03Y589525I277J-289D01*
G02X542484I-971J-1011D01*
G03Y590103I-277J289D01*
G02X544426I971J1011D01*
G37*
G36*
G01X507615D02*
G03Y589525I277J-289D01*
G02X505673I-971J-1011D01*
G03Y590103I-277J289D01*
G02X507615I971J1011D01*
G37*
G36*
G01X470803D02*
G03Y589525I277J-289D01*
G02X468861I-971J-1011D01*
G03Y590103I-277J289D01*
G02X470803I971J1011D01*
G37*
G36*
G01X290095D02*
G03Y589525I277J-289D01*
G02X288153I-971J-1011D01*
G03Y590103I-277J289D01*
G02X290095I971J1011D01*
G37*
G36*
G01X253284D02*
G03Y589525I277J-289D01*
G02X251342I-971J-1011D01*
G03Y590103I-277J289D01*
G02X253284I971J1011D01*
G37*
G36*
G01X216473D02*
G03Y589525I277J-289D01*
G02X214531I-971J-1011D01*
G03Y590103I-277J289D01*
G02X216473I971J1011D01*
G37*
G36*
G01X179662D02*
G03Y589525I277J-289D01*
G02X177720I-971J-1011D01*
G03Y590103I-277J289D01*
G02X179662I971J1011D01*
G37*
G36*
G01X142851D02*
G03Y589525I277J-289D01*
G02X140909I-971J-1011D01*
G03Y590103I-277J289D01*
G02X142851I971J1011D01*
G37*
G36*
G01X1225745Y589889D02*
G03Y589311I277J-289D01*
G02X1223803I-971J-1011D01*
G03Y589889I-277J289D01*
G02X1225745I971J1011D01*
G37*
G36*
G01X1188934D02*
G03Y589311I277J-289D01*
G02X1186992I-971J-1011D01*
G03Y589889I-277J289D01*
G02X1188934I971J1011D01*
G37*
G36*
G01X1152123D02*
G03Y589311I277J-289D01*
G02X1150181I-971J-1011D01*
G03Y589889I-277J289D01*
G02X1152123I971J1011D01*
G37*
G36*
G01X1115311D02*
G03Y589311I277J-289D01*
G02X1113369I-971J-1011D01*
G03Y589889I-277J289D01*
G02X1115311I971J1011D01*
G37*
G36*
G01X934603D02*
G03Y589311I277J-289D01*
G02X932661I-971J-1011D01*
G03Y589889I-277J289D01*
G02X934603I971J1011D01*
G37*
G36*
G01X897792D02*
G03Y589311I277J-289D01*
G02X895850I-971J-1011D01*
G03Y589889I-277J289D01*
G02X897792I971J1011D01*
G37*
G36*
G01X860981D02*
G03Y589311I277J-289D01*
G02X859039I-971J-1011D01*
G03Y589889I-277J289D01*
G02X860981I971J1011D01*
G37*
G36*
G01X824170D02*
G03Y589311I277J-289D01*
G02X822228I-971J-1011D01*
G03Y589889I-277J289D01*
G02X824170I971J1011D01*
G37*
G36*
G01X787359D02*
G03Y589311I277J-289D01*
G02X785417I-971J-1011D01*
G03Y589889I-277J289D01*
G02X787359I971J1011D01*
G37*
G36*
G01X576137D02*
G03Y589311I277J-289D01*
G02X574195I-971J-1011D01*
G03Y589889I-277J289D01*
G02X576137I971J1011D01*
G37*
G36*
G01X539326D02*
G03Y589311I277J-289D01*
G02X537384I-971J-1011D01*
G03Y589889I-277J289D01*
G02X539326I971J1011D01*
G37*
G36*
G01X502515D02*
G03Y589311I277J-289D01*
G02X500573I-971J-1011D01*
G03Y589889I-277J289D01*
G02X502515I971J1011D01*
G37*
G36*
G01X465703D02*
G03Y589311I277J-289D01*
G02X463761I-971J-1011D01*
G03Y589889I-277J289D01*
G02X465703I971J1011D01*
G37*
G36*
G01X284995D02*
G03Y589311I277J-289D01*
G02X283053I-971J-1011D01*
G03Y589889I-277J289D01*
G02X284995I971J1011D01*
G37*
G36*
G01X248184D02*
G03Y589311I277J-289D01*
G02X246242I-971J-1011D01*
G03Y589889I-277J289D01*
G02X248184I971J1011D01*
G37*
G36*
G01X211373D02*
G03Y589311I277J-289D01*
G02X209431I-971J-1011D01*
G03Y589889I-277J289D01*
G02X211373I971J1011D01*
G37*
G36*
G01X174562D02*
G03Y589311I277J-289D01*
G02X172620I-971J-1011D01*
G03Y589889I-277J289D01*
G02X174562I971J1011D01*
G37*
G36*
G01X137751D02*
G03Y589311I277J-289D01*
G02X135809I-971J-1011D01*
G03Y589889I-277J289D01*
G02X137751I971J1011D01*
G37*
G36*
G01X1662192Y590760D02*
Y586665D01*
X1662182Y586581D01*
G02X1659168Y586750I-1502J169D01*
G01Y590751D01*
G02X1662192Y590760I1512J-1D01*
G37*
G36*
G01X1419447Y585240D02*
G03X1418893I-277J-288D01*
G02X1416824Y585375I-973J1010D01*
G03X1416215Y585394I-313J-249D01*
G02X1414200Y585322I-1042J938D01*
G03X1413646I-277J-288D01*
G02Y587342I-973J1010D01*
G03X1414200I277J288D01*
G02X1416269Y587207I973J-1010D01*
G03X1416878Y587188I313J249D01*
G02X1418893Y587260I1042J-938D01*
G03X1419447I277J288D01*
G02X1421393I973J-1010D01*
G03X1421947I277J288D01*
G02Y585240I973J-1010D01*
G03X1421393I-277J-288D01*
G02X1419447I-973J1010D01*
G37*
G36*
G01X1611008Y590005D02*
G02X1614030Y590014I1511J-1D01*
G01Y586004D01*
X1614031D01*
Y585919D01*
X1614021Y585835D01*
G02X1611008Y586004I-1502J169D01*
G01Y590005D01*
G37*
G36*
G01X1544189Y584753D02*
G03X1543611I-289J-277D01*
G02Y586695I-1011J971D01*
G03X1544189I289J277D01*
G02Y584753I1011J-971D01*
G37*
G36*
G01X1372689Y583685D02*
G03X1372111I-289J-277D01*
G02Y585627I-1011J971D01*
G03X1372689I289J277D01*
G02Y583685I1011J-971D01*
G37*
G36*
G01X1815255Y582948D02*
G03X1814679Y582814I-227J-329D01*
G02X1814253Y584653I-1223J686D01*
G03X1814829Y584787I227J329D01*
G02X1815255Y582948I1223J-686D01*
G37*
G36*
G01X1731818Y580896D02*
G03X1732393Y580876I297J267D01*
G02X1732324Y578932I975J-1008D01*
G03X1731749Y578952I-297J-267D01*
G02X1731818Y580896I-975J1008D01*
G37*
G36*
G01X1294692Y581162D02*
G03X1295092Y580762I400J0D01*
G02X1293688Y579358I-2J-1402D01*
G03X1293288Y579758I-400J0D01*
G02X1294692Y581162I2J1402D01*
G37*
G36*
G01X1684289Y586650D02*
X1684290Y586648D01*
X1687186Y581243D01*
X1687187Y581241D01*
G02X1683042Y579020I-2045J-1162D01*
G01X1683041Y579022D01*
X1680145Y584427D01*
X1680144Y584429D01*
G02X1684289Y586650I2045J1162D01*
G37*
G36*
G01X1675423Y586665D02*
X1675424Y586664D01*
X1678336Y581227D01*
X1678337Y581225D01*
G02X1674191Y579005I-2054J-1146D01*
G01X1674190Y579006D01*
X1671278Y584443D01*
X1671277Y584445D01*
G02X1675423Y586665I2054J1146D01*
G37*
G36*
G01X1637045Y586650D02*
X1637046Y586648D01*
X1639942Y581243D01*
X1639943Y581241D01*
G02X1635798Y579020I-2045J-1162D01*
G01X1635797Y579022D01*
X1632901Y584427D01*
X1632900Y584429D01*
G02X1637045Y586650I2045J1162D01*
G37*
G36*
G01X1628179Y586665D02*
X1628180Y586664D01*
X1631092Y581227D01*
X1631093Y581225D01*
G02X1626947Y579005I-2054J-1146D01*
G01X1626946Y579006D01*
X1624034Y584443D01*
X1624033Y584445D01*
G02X1628179Y586665I2054J1146D01*
G37*
G36*
G01X1607506Y582510D02*
Y578415D01*
X1607496Y578331D01*
G02X1604482Y578500I-1502J169D01*
G01Y582501D01*
G02X1607506Y582510I1512J-1D01*
G37*
G36*
G01X1654180Y582360D02*
Y578265D01*
X1654171Y578181D01*
G02X1651158Y578350I-1502J169D01*
G01Y582351D01*
G02X1654180Y582360I1511J-1D01*
G37*
G36*
G01X651238Y573438D02*
G03X650696Y573413I-257J-306D01*
G02X648729Y575411I-996J987D01*
G03Y575989I-277J289D01*
G02X650645Y578036I971J1011D01*
G03X651186Y578039I269J296D01*
G02X653150Y576038I954J-1028D01*
G03Y575484I288J-277D01*
G02X651238Y573438I-1009J-973D01*
G37*
G36*
G01X664689Y573229D02*
G03X664111I-289J-277D01*
G02Y575171I-1011J971D01*
G03X664689I289J277D01*
G02Y573229I1011J-971D01*
G37*
G36*
G01X1772522Y574592D02*
G03X1772110Y574142I-15J-400D01*
G02X1770775Y575365I-1391J-178D01*
G03X1771187Y575815I15J400D01*
G02X1772522Y574592I1391J178D01*
G37*
G36*
G01X660489Y568829D02*
G03X659911I-289J-277D01*
G02Y570771I-1011J971D01*
G03X660489I289J277D01*
G02Y568829I1011J-971D01*
G37*
G36*
G01X1225735Y571178D02*
G03X1225740Y570590I274J-292D01*
G02X1223839Y570571I-940J-1040D01*
G03X1223834Y571159I-274J292D01*
G02X1225735Y571178I940J1040D01*
G37*
G36*
G01X1188924D02*
G03X1188929Y570590I274J-292D01*
G02X1187028Y570571I-940J-1040D01*
G03X1187023Y571159I-274J292D01*
G02X1188924Y571178I940J1040D01*
G37*
G36*
G01X1152113D02*
G03X1152118Y570590I274J-292D01*
G02X1150217Y570571I-940J-1040D01*
G03X1150212Y571159I-274J292D01*
G02X1152113Y571178I940J1040D01*
G37*
G36*
G01X1115301D02*
G03X1115306Y570590I274J-292D01*
G02X1113405Y570571I-940J-1040D01*
G03X1113400Y571159I-274J292D01*
G02X1115301Y571178I940J1040D01*
G37*
G36*
G01X934593D02*
G03X934598Y570590I274J-292D01*
G02X932697Y570571I-940J-1040D01*
G03X932692Y571159I-274J292D01*
G02X934593Y571178I940J1040D01*
G37*
G36*
G01X897782D02*
G03X897787Y570590I274J-292D01*
G02X895886Y570571I-940J-1040D01*
G03X895881Y571159I-274J292D01*
G02X897782Y571178I940J1040D01*
G37*
G36*
G01X860971D02*
G03X860976Y570590I274J-292D01*
G02X859075Y570571I-940J-1040D01*
G03X859070Y571159I-274J292D01*
G02X860971Y571178I940J1040D01*
G37*
G36*
G01X824160D02*
G03X824165Y570590I274J-292D01*
G02X822264Y570571I-940J-1040D01*
G03X822259Y571159I-274J292D01*
G02X824160Y571178I940J1040D01*
G37*
G36*
G01X787349D02*
G03X787354Y570590I274J-292D01*
G02X785453Y570571I-940J-1040D01*
G03X785448Y571159I-274J292D01*
G02X787349Y571178I940J1040D01*
G37*
G36*
G01X576127D02*
G03X576132Y570590I274J-292D01*
G02X574231Y570571I-940J-1040D01*
G03X574226Y571159I-274J292D01*
G02X576127Y571178I940J1040D01*
G37*
G36*
G01X539316D02*
G03X539321Y570590I274J-292D01*
G02X537420Y570571I-940J-1040D01*
G03X537415Y571159I-274J292D01*
G02X539316Y571178I940J1040D01*
G37*
G36*
G01X502505D02*
G03X502510Y570590I274J-292D01*
G02X500609Y570571I-940J-1040D01*
G03X500604Y571159I-274J292D01*
G02X502505Y571178I940J1040D01*
G37*
G36*
G01X463797Y570571D02*
G03X463792Y571159I-274J292D01*
G02X465693Y571178I940J1040D01*
G03X465698Y570590I274J-292D01*
G02X463797Y570571I-940J-1040D01*
G37*
G36*
G01X284985Y571178D02*
G03X284990Y570590I274J-292D01*
G02X283089Y570571I-940J-1040D01*
G03X283084Y571159I-274J292D01*
G02X284985Y571178I940J1040D01*
G37*
G36*
G01X248174D02*
G03X248179Y570590I274J-292D01*
G02X246278Y570571I-940J-1040D01*
G03X246273Y571159I-274J292D01*
G02X248174Y571178I940J1040D01*
G37*
G36*
G01X211363D02*
G03X211368Y570590I274J-292D01*
G02X209467Y570571I-940J-1040D01*
G03X209462Y571159I-274J292D01*
G02X211363Y571178I940J1040D01*
G37*
G36*
G01X174552D02*
G03X174557Y570590I274J-292D01*
G02X172656Y570571I-940J-1040D01*
G03X172651Y571159I-274J292D01*
G02X174552Y571178I940J1040D01*
G37*
G36*
G01X135845Y570571D02*
G03X135840Y571159I-274J292D01*
G02X137741Y571178I940J1040D01*
G03X137746Y570590I274J-292D01*
G02X135845Y570571I-940J-1040D01*
G37*
G36*
G01X1230841Y570934D02*
G03Y570355I276J-290D01*
G02X1228907I-967J-1015D01*
G03Y570934I-276J289D01*
G02X1230841I967J1015D01*
G37*
G36*
G01X1194030D02*
G03Y570355I276J-290D01*
G02X1192096I-967J-1015D01*
G03Y570934I-276J289D01*
G02X1194030I967J1015D01*
G37*
G36*
G01X1157219D02*
G03Y570355I276J-290D01*
G02X1155285I-967J-1015D01*
G03Y570934I-276J289D01*
G02X1157219I967J1015D01*
G37*
G36*
G01X1120407D02*
G03Y570355I276J-290D01*
G02X1118473I-967J-1015D01*
G03Y570934I-276J289D01*
G02X1120407I967J1015D01*
G37*
G36*
G01X939699D02*
G03Y570355I276J-290D01*
G02X937765I-967J-1015D01*
G03Y570934I-276J289D01*
G02X939699I967J1015D01*
G37*
G36*
G01X902888D02*
G03Y570355I276J-290D01*
G02X900954I-967J-1015D01*
G03Y570934I-276J289D01*
G02X902888I967J1015D01*
G37*
G36*
G01X866077D02*
G03Y570355I276J-290D01*
G02X864143I-967J-1015D01*
G03Y570934I-276J289D01*
G02X866077I967J1015D01*
G37*
G36*
G01X829266D02*
G03Y570355I276J-290D01*
G02X827332I-967J-1015D01*
G03Y570934I-276J289D01*
G02X829266I967J1015D01*
G37*
G36*
G01X792455D02*
G03Y570355I276J-290D01*
G02X790521I-967J-1015D01*
G03Y570934I-276J289D01*
G02X792455I967J1015D01*
G37*
G36*
G01X581233D02*
G03Y570355I276J-290D01*
G02X579299I-967J-1015D01*
G03Y570934I-276J289D01*
G02X581233I967J1015D01*
G37*
G36*
G01X544422D02*
G03Y570355I276J-290D01*
G02X542488I-967J-1015D01*
G03Y570934I-276J289D01*
G02X544422I967J1015D01*
G37*
G36*
G01X507611D02*
G03Y570355I276J-290D01*
G02X505677I-967J-1015D01*
G03Y570934I-276J289D01*
G02X507611I967J1015D01*
G37*
G36*
G01X470799D02*
G03Y570355I276J-290D01*
G02X468865I-967J-1015D01*
G03Y570934I-276J289D01*
G02X470799I967J1015D01*
G37*
G36*
G01X290091D02*
G03Y570355I276J-290D01*
G02X288157I-967J-1015D01*
G03Y570934I-276J289D01*
G02X290091I967J1015D01*
G37*
G36*
G01X253280D02*
G03Y570355I276J-290D01*
G02X251346I-967J-1015D01*
G03Y570934I-276J289D01*
G02X253280I967J1015D01*
G37*
G36*
G01X216469D02*
G03Y570355I276J-290D01*
G02X214535I-967J-1015D01*
G03Y570934I-276J289D01*
G02X216469I967J1015D01*
G37*
G36*
G01X179658D02*
G03Y570355I276J-290D01*
G02X177724I-967J-1015D01*
G03Y570934I-276J289D01*
G02X179658I967J1015D01*
G37*
G36*
G01X142847D02*
G03Y570355I276J-290D01*
G02X140913I-967J-1015D01*
G03Y570934I-276J289D01*
G02X142847I967J1015D01*
G37*
G36*
G01X703008Y570426D02*
G03X703030Y569849I288J-278D01*
G02X701092Y569774I-930J-1049D01*
G03X701070Y570351I-288J278D01*
G02X703008Y570426I930J1049D01*
G37*
G36*
G01X649000Y567694D02*
G03X648400I-300J-265D01*
G02Y569552I-1050J929D01*
G03X649000I300J265D01*
G02Y567694I1050J-929D01*
G37*
G36*
G01X1603336Y572335D02*
Y568240D01*
X1603327Y568156D01*
G02X1600314Y568325I-1502J169D01*
G01Y572326D01*
G02X1603336Y572335I1511J-1D01*
G37*
G36*
G01X4611Y568271D02*
G03X5189I289J277D01*
G02Y566329I1011J-971D01*
G03X4611I-289J-277D01*
G02Y568271I-1011J971D01*
G37*
G36*
G01X1684289Y571689D02*
X1684290Y571687D01*
X1687186Y566282D01*
X1687187Y566280D01*
G02X1683042Y564059I-2045J-1162D01*
G01X1683041Y564061D01*
X1680145Y569466D01*
X1680144Y569468D01*
G02X1684289Y571689I2045J1162D01*
G37*
G36*
G01X1675423Y571704D02*
X1675424Y571703D01*
X1678336Y566266D01*
X1678337Y566264D01*
G02X1674191Y564044I-2054J-1146D01*
G01X1674190Y564045D01*
X1671278Y569482D01*
X1671277Y569484D01*
G02X1675423Y571704I2054J1146D01*
G37*
G36*
G01X1637045Y571689D02*
X1637046Y571687D01*
X1639942Y566282D01*
X1639943Y566280D01*
G02X1635798Y564059I-2045J-1162D01*
G01X1635797Y564061D01*
X1632901Y569466D01*
X1632900Y569468D01*
G02X1637045Y571689I2045J1162D01*
G37*
G36*
G01X1628179Y571704D02*
X1628180Y571703D01*
X1631092Y566266D01*
X1631093Y566264D01*
G02X1626947Y564044I-2054J-1146D01*
G01X1626946Y564045D01*
X1624034Y569482D01*
X1624033Y569484D01*
G02X1628179Y571704I2054J1146D01*
G37*
G36*
G01X1448234Y562842D02*
G03X1447666I-284J-282D01*
G02Y564958I-1066J1058D01*
G03X1448234I284J282D01*
G02X1450327Y564996I1066J-1058D01*
G03X1450873I273J292D01*
G02X1452966Y564958I1027J-1096D01*
G03X1453534I284J282D01*
G02X1455666I1066J-1058D01*
G03X1456234I284J282D01*
G02Y562842I1066J-1058D01*
G03X1455666I-284J-282D01*
G02X1453534I-1066J1058D01*
G03X1452966I-284J-282D01*
G02X1450873Y562804I-1066J1058D01*
G03X1450327I-273J-292D01*
G02X1448234Y562842I-1027J1096D01*
G37*
G36*
G01X1655911Y562918D02*
G03X1655333Y562646I-187J-354D01*
G02X1653568Y564276I-1373J284D01*
G03X1653794Y564874I-112J384D01*
G02X1655911Y562918I4734J3000D01*
G37*
G36*
G01X1598097Y561256D02*
G03X1597543I-277J-288D01*
G02X1595579Y563258I-973J1010D01*
G03X1595590Y563812I-283J283D01*
G02X1595597Y565723I1030J952D01*
G03X1595593Y566275I-292J274D01*
G02X1597623Y566291I1007J975D01*
G03X1597627Y565739I292J-274D01*
G02X1597714Y565641I-1004J-979D01*
G03X1598026I156J125D01*
G02X1600111Y563772I1093J-878D01*
G03X1600100Y563218I283J-283D01*
G02X1598097Y561256I-1030J-952D01*
G37*
G36*
G01X1469299Y560816D02*
G03X1468752Y560810I-270J-295D01*
G02X1468729Y563003I-1038J1086D01*
G03X1469276Y563009I270J295D01*
G02X1471350Y563010I1038J-1086D01*
G03X1471919Y563027I276J289D01*
G02X1471982Y560916I1099J-1024D01*
G03X1471413Y560899I-276J-289D01*
G02X1469299Y560816I-1099J1024D01*
G37*
G36*
G01X1491088Y560819D02*
G03X1490484Y560798I-293J-273D01*
G02X1490415Y562765I-1168J944D01*
G03X1491019Y562786I293J273D01*
G02X1493372Y562765I1168J-944D01*
G03X1494002I315J246D01*
G02X1496254Y562899I1185J-923D01*
G03X1496828Y562906I284J282D01*
G02X1498949Y562964I1090J-1034D01*
G03X1499499I275J291D01*
G02Y560780I1031J-1092D01*
G03X1498949I-275J-291D01*
G02X1496851Y560815I-1031J1092D01*
G03X1496277Y560808I-284J-282D01*
G02X1494002Y560919I-1090J1034D01*
G03X1493372I-315J-246D01*
G02X1491088Y560819I-1185J923D01*
G37*
G36*
G01X1383118Y561641D02*
G03X1383081Y561073I262J-302D01*
G02X1381114Y561202I-1049J-930D01*
G03X1381151Y561770I-262J302D01*
G02X1383118Y561641I1049J930D01*
G37*
G36*
G01X1739133Y559735D02*
G03X1739297Y559155I335J-218D01*
G02X1737522Y558653I-600J-1267D01*
G03X1737358Y559233I-335J218D01*
G02X1739133Y559735I600J1267D01*
G37*
G36*
G01X1626606Y559210D02*
Y555115D01*
X1626596Y555031D01*
G02X1623582Y555200I-1502J169D01*
G01Y559200D01*
G02X1626606Y559210I1512J0D01*
G37*
G36*
G01X2336Y555456D02*
G03X2345Y554853I267J-298D01*
G02X503Y554827I-906J-1070D01*
G03X494Y555430I-267J298D01*
G02X389Y555529I908J1068D01*
G03X-189I-289J-277D01*
G02Y557471I-1011J971D01*
G03X389I289J277D01*
G02X2336Y555456I1011J-971D01*
G37*
G36*
G01X652611Y551617D02*
G03X651989I-311J-252D01*
G02Y553383I-1089J883D01*
G03X652611I311J252D01*
G02Y551617I1089J-883D01*
G37*
G36*
G01X1663754Y549588D02*
X1658753D01*
G02X1658754Y552412I1J1412D01*
G01X1663754D01*
G02X1665166Y551010I0J-1412D01*
G01Y550916D01*
X1665155Y550832D01*
G02X1663754Y549588I-1401J167D01*
G37*
G36*
G01X1230845Y552303D02*
G03Y551725I277J-289D01*
G02X1228903I-971J-1011D01*
G03Y552303I-277J289D01*
G02X1230845I971J1011D01*
G37*
G36*
G01X1194034D02*
G03Y551725I277J-289D01*
G02X1192092I-971J-1011D01*
G03Y552303I-277J289D01*
G02X1194034I971J1011D01*
G37*
G36*
G01X1157223D02*
G03Y551725I277J-289D01*
G02X1155281I-971J-1011D01*
G03Y552303I-277J289D01*
G02X1157223I971J1011D01*
G37*
G36*
G01X1120411D02*
G03Y551725I277J-289D01*
G02X1118469I-971J-1011D01*
G03Y552303I-277J289D01*
G02X1120411I971J1011D01*
G37*
G36*
G01X939703D02*
G03Y551725I277J-289D01*
G02X937761I-971J-1011D01*
G03Y552303I-277J289D01*
G02X939703I971J1011D01*
G37*
G36*
G01X902892D02*
G03Y551725I277J-289D01*
G02X900950I-971J-1011D01*
G03Y552303I-277J289D01*
G02X902892I971J1011D01*
G37*
G36*
G01X866081D02*
G03Y551725I277J-289D01*
G02X864139I-971J-1011D01*
G03Y552303I-277J289D01*
G02X866081I971J1011D01*
G37*
G36*
G01X829270D02*
G03Y551725I277J-289D01*
G02X827328I-971J-1011D01*
G03Y552303I-277J289D01*
G02X829270I971J1011D01*
G37*
G36*
G01X792459D02*
G03Y551725I277J-289D01*
G02X790517I-971J-1011D01*
G03Y552303I-277J289D01*
G02X792459I971J1011D01*
G37*
G36*
G01X581237D02*
G03Y551725I277J-289D01*
G02X579295I-971J-1011D01*
G03Y552303I-277J289D01*
G02X581237I971J1011D01*
G37*
G36*
G01X544426D02*
G03Y551725I277J-289D01*
G02X542484I-971J-1011D01*
G03Y552303I-277J289D01*
G02X544426I971J1011D01*
G37*
G36*
G01X507615D02*
G03Y551725I277J-289D01*
G02X505673I-971J-1011D01*
G03Y552303I-277J289D01*
G02X507615I971J1011D01*
G37*
G36*
G01X470803D02*
G03Y551725I277J-289D01*
G02X468861I-971J-1011D01*
G03Y552303I-277J289D01*
G02X470803I971J1011D01*
G37*
G36*
G01X290095D02*
G03Y551725I277J-289D01*
G02X288153I-971J-1011D01*
G03Y552303I-277J289D01*
G02X290095I971J1011D01*
G37*
G36*
G01X253284D02*
G03Y551725I277J-289D01*
G02X251342I-971J-1011D01*
G03Y552303I-277J289D01*
G02X253284I971J1011D01*
G37*
G36*
G01X216473D02*
G03Y551725I277J-289D01*
G02X214531I-971J-1011D01*
G03Y552303I-277J289D01*
G02X216473I971J1011D01*
G37*
G36*
G01X179662D02*
G03Y551725I277J-289D01*
G02X177720I-971J-1011D01*
G03Y552303I-277J289D01*
G02X179662I971J1011D01*
G37*
G36*
G01X142851D02*
G03Y551725I277J-289D01*
G02X140909I-971J-1011D01*
G03Y552303I-277J289D01*
G02X142851I971J1011D01*
G37*
G36*
G01X1225745Y552089D02*
G03Y551511I277J-289D01*
G02X1223803I-971J-1011D01*
G03Y552089I-277J289D01*
G02X1225745I971J1011D01*
G37*
G36*
G01X1188934D02*
G03Y551511I277J-289D01*
G02X1186992I-971J-1011D01*
G03Y552089I-277J289D01*
G02X1188934I971J1011D01*
G37*
G36*
G01X1152123D02*
G03Y551511I277J-289D01*
G02X1150181I-971J-1011D01*
G03Y552089I-277J289D01*
G02X1152123I971J1011D01*
G37*
G36*
G01X1115311D02*
G03Y551511I277J-289D01*
G02X1113369I-971J-1011D01*
G03Y552089I-277J289D01*
G02X1115311I971J1011D01*
G37*
G36*
G01X934603D02*
G03Y551511I277J-289D01*
G02X932661I-971J-1011D01*
G03Y552089I-277J289D01*
G02X934603I971J1011D01*
G37*
G36*
G01X897792D02*
G03Y551511I277J-289D01*
G02X895850I-971J-1011D01*
G03Y552089I-277J289D01*
G02X897792I971J1011D01*
G37*
G36*
G01X860981D02*
G03Y551511I277J-289D01*
G02X859039I-971J-1011D01*
G03Y552089I-277J289D01*
G02X860981I971J1011D01*
G37*
G36*
G01X824170D02*
G03Y551511I277J-289D01*
G02X822228I-971J-1011D01*
G03Y552089I-277J289D01*
G02X824170I971J1011D01*
G37*
G36*
G01X787359D02*
G03Y551511I277J-289D01*
G02X785417I-971J-1011D01*
G03Y552089I-277J289D01*
G02X787359I971J1011D01*
G37*
G36*
G01X576137D02*
G03Y551511I277J-289D01*
G02X574195I-971J-1011D01*
G03Y552089I-277J289D01*
G02X576137I971J1011D01*
G37*
G36*
G01X539326D02*
G03Y551511I277J-289D01*
G02X537384I-971J-1011D01*
G03Y552089I-277J289D01*
G02X539326I971J1011D01*
G37*
G36*
G01X502515D02*
G03Y551511I277J-289D01*
G02X500573I-971J-1011D01*
G03Y552089I-277J289D01*
G02X502515I971J1011D01*
G37*
G36*
G01X465703D02*
G03Y551511I277J-289D01*
G02X463761I-971J-1011D01*
G03Y552089I-277J289D01*
G02X465703I971J1011D01*
G37*
G36*
G01X284995D02*
G03Y551511I277J-289D01*
G02X283053I-971J-1011D01*
G03Y552089I-277J289D01*
G02X284995I971J1011D01*
G37*
G36*
G01X248184D02*
G03Y551511I277J-289D01*
G02X246242I-971J-1011D01*
G03Y552089I-277J289D01*
G02X248184I971J1011D01*
G37*
G36*
G01X211373D02*
G03Y551511I277J-289D01*
G02X209431I-971J-1011D01*
G03Y552089I-277J289D01*
G02X211373I971J1011D01*
G37*
G36*
G01X174562D02*
G03Y551511I277J-289D01*
G02X172620I-971J-1011D01*
G03Y552089I-277J289D01*
G02X174562I971J1011D01*
G37*
G36*
G01X137751D02*
G03Y551511I277J-289D01*
G02X135809I-971J-1011D01*
G03Y552089I-277J289D01*
G02X137751I971J1011D01*
G37*
G36*
G01X1685000Y549032D02*
X1679999D01*
G02X1680000Y552056I1J1512D01*
G01X1685000D01*
G02X1686512Y550554I0J-1512D01*
G01Y550459D01*
X1686502Y550375D01*
G02X1685000Y549032I-1502J168D01*
G37*
G36*
G01X1794888Y551715D02*
G03X1794866Y551116I254J-309D01*
G02X1793012Y551185I-966J-1016D01*
G03X1793034Y551784I-254J309D01*
G02X1794888Y551715I966J1016D01*
G37*
G36*
G01X1936731Y551240D02*
G03X1937264Y550995I380J125D01*
G02X1936469Y549260I536J-1295D01*
G03X1935936Y549505I-380J-125D01*
G02X1936731Y551240I-536J1295D01*
G37*
G36*
G01X1739037Y549968D02*
G03X1739065Y549355I270J-295D01*
G02X1737267Y549271I-849J-1116D01*
G03X1737239Y549884I-270J295D01*
G02X1739037Y549968I849J1116D01*
G37*
G36*
G01X1364055Y546944D02*
G03X1363501I-277J-288D01*
G02Y548964I-973J1010D01*
G03X1364055I277J288D01*
G02Y546944I973J-1010D01*
G37*
G36*
G01X1705348Y545122D02*
X1700348D01*
G02Y548144I0J1511D01*
G01X1705348D01*
G02X1706860Y546643I0J-1512D01*
G01Y546548D01*
X1706850Y546464D01*
G02X1705348Y545122I-1502J169D01*
G37*
G36*
G01X1496253Y546907D02*
G03X1496829Y546883I300J265D01*
G02X1496743Y544800I1037J-1086D01*
G03X1496167Y544824I-300J-265D01*
G02X1493945Y544987I-1037J1086D01*
G03X1493315I-315J-246D01*
G02X1490948Y544983I-1185J923D01*
G03X1490356Y545023I-314J-247D01*
G02X1490440Y546948I-976J1007D01*
G03X1491034Y546937I302J262D01*
G02X1493315Y546833I1096J-1027D01*
G03X1493945I315J246D01*
G02X1496253Y546907I1185J-923D01*
G37*
G36*
G01X1439987Y544190D02*
G03X1439915Y543633I247J-315D01*
G02X1437935Y543889I-1116J-848D01*
G03X1438007Y544446I-247J315D01*
G02X1439987Y544190I1116J848D01*
G37*
G36*
G01X1676020Y550027D02*
G03X1676280Y549508I376J-136D01*
G02X1671633Y548350I-1359J-4449D01*
G03X1671350Y549032I-283J282D01*
G01X1669599D01*
G02X1669600Y552056I1J1512D01*
G01X1674600D01*
G02X1676112Y550554I0J-1512D01*
G01Y550459D01*
X1676102Y550375D01*
G02X1676020Y550027I-1502J170D01*
G37*
G36*
G01X1391359Y540723D02*
G03X1391368Y540101I256J-307D01*
G02X1389603Y540077I-868J-1101D01*
G03X1389594Y540699I-256J307D01*
G02X1391359Y540723I868J1101D01*
G37*
G36*
G01X1743894Y534951D02*
G03X1743351I-271J-294D01*
G02Y538631I-1697J1840D01*
G03X1743894I272J294D01*
G02X1747288I1697J-1840D01*
G03X1747831I272J294D01*
G02X1751225I1697J-1840D01*
G03X1751768I271J294D01*
G02X1755162I1697J-1840D01*
G03X1755705I271J294D01*
G02X1759099I1697J-1840D01*
G03X1759642I272J294D01*
G02Y534951I1697J-1840D01*
G03X1759099I-271J-294D01*
G02X1755705I-1697J1840D01*
G03X1755162I-272J-294D01*
G02X1751768I-1697J1840D01*
G03X1751225I-272J-294D01*
G02X1747831I-1697J1840D01*
G03X1747288I-271J-294D01*
G02X1743894I-1697J1840D01*
G37*
G36*
G01X735027Y534190D02*
G03X734473I-277J-288D01*
G02X732490Y536173I-973J1010D01*
G03Y536727I-288J277D01*
G02X734473Y538710I1010J973D01*
G03X735027I277J288D01*
G02X737010Y536727I973J-1010D01*
G03Y536173I288J-277D01*
G02X735027Y534190I-1010J-973D01*
G37*
G36*
G01X1712206Y533780D02*
X1707204D01*
G02X1704820Y534952I0J3011D01*
G03X1704207Y534977I-317J-244D01*
G02X1700203Y534976I-2002J1814D01*
G03X1699590Y534952I-296J-268D01*
G02X1697206Y533780I-2384J1839D01*
G01X1692204D01*
G02X1689820Y534952I0J3011D01*
G03X1689207Y534977I-317J-244D01*
G02Y538605I-2002J1814D01*
G03X1689820Y538630I296J269D01*
G02X1692204Y539802I2384J-1839D01*
G01X1697206D01*
G02X1699590Y538630I0J-3011D01*
G03X1700203Y538606I317J244D01*
G02X1704207Y538605I2002J-1815D01*
G03X1704820Y538630I296J269D01*
G02X1707204Y539802I2384J-1839D01*
G01X1712206D01*
G02X1714590Y538630I0J-3011D01*
G03X1715203Y538606I317J244D01*
G02Y534976I2002J-1815D01*
G03X1714590Y534952I-296J-268D01*
G02X1712206Y533780I-2384J1839D01*
G37*
G36*
G01X1225735Y533378D02*
G03X1225740Y532790I274J-292D01*
G02X1223839Y532771I-940J-1040D01*
G03X1223834Y533359I-274J292D01*
G02X1225735Y533378I940J1040D01*
G37*
G36*
G01X1188924D02*
G03X1188929Y532790I274J-292D01*
G02X1187028Y532771I-940J-1040D01*
G03X1187023Y533359I-274J292D01*
G02X1188924Y533378I940J1040D01*
G37*
G36*
G01X1152113D02*
G03X1152118Y532790I274J-292D01*
G02X1150217Y532771I-940J-1040D01*
G03X1150212Y533359I-274J292D01*
G02X1152113Y533378I940J1040D01*
G37*
G36*
G01X1115301D02*
G03X1115306Y532790I274J-292D01*
G02X1113405Y532771I-940J-1040D01*
G03X1113400Y533359I-274J292D01*
G02X1115301Y533378I940J1040D01*
G37*
G36*
G01X934593D02*
G03X934598Y532790I274J-292D01*
G02X932697Y532771I-940J-1040D01*
G03X932692Y533359I-274J292D01*
G02X934593Y533378I940J1040D01*
G37*
G36*
G01X897782D02*
G03X897787Y532790I274J-292D01*
G02X895886Y532771I-940J-1040D01*
G03X895881Y533359I-274J292D01*
G02X897782Y533378I940J1040D01*
G37*
G36*
G01X860971D02*
G03X860976Y532790I274J-292D01*
G02X859075Y532771I-940J-1040D01*
G03X859070Y533359I-274J292D01*
G02X860971Y533378I940J1040D01*
G37*
G36*
G01X824160D02*
G03X824165Y532790I274J-292D01*
G02X822264Y532771I-940J-1040D01*
G03X822259Y533359I-274J292D01*
G02X824160Y533378I940J1040D01*
G37*
G36*
G01X785453Y532771D02*
G03X785448Y533359I-274J292D01*
G02X787349Y533378I940J1040D01*
G03X787354Y532790I274J-292D01*
G02X785453Y532771I-940J-1040D01*
G37*
G36*
G01X576127Y533378D02*
G03X576132Y532790I274J-292D01*
G02X574231Y532771I-940J-1040D01*
G03X574226Y533359I-274J292D01*
G02X576127Y533378I940J1040D01*
G37*
G36*
G01X539316D02*
G03X539321Y532790I274J-292D01*
G02X537420Y532771I-940J-1040D01*
G03X537415Y533359I-274J292D01*
G02X539316Y533378I940J1040D01*
G37*
G36*
G01X502505D02*
G03X502510Y532790I274J-292D01*
G02X500609Y532771I-940J-1040D01*
G03X500604Y533359I-274J292D01*
G02X502505Y533378I940J1040D01*
G37*
G36*
G01X463797Y532771D02*
G03X463792Y533359I-274J292D01*
G02X465693Y533378I940J1040D01*
G03X465698Y532790I274J-292D01*
G02X463797Y532771I-940J-1040D01*
G37*
G36*
G01X284985Y533378D02*
G03X284990Y532790I274J-292D01*
G02X283089Y532771I-940J-1040D01*
G03X283084Y533359I-274J292D01*
G02X284985Y533378I940J1040D01*
G37*
G36*
G01X248174D02*
G03X248179Y532790I274J-292D01*
G02X246278Y532771I-940J-1040D01*
G03X246273Y533359I-274J292D01*
G02X248174Y533378I940J1040D01*
G37*
G36*
G01X211363D02*
G03X211368Y532790I274J-292D01*
G02X209467Y532771I-940J-1040D01*
G03X209462Y533359I-274J292D01*
G02X211363Y533378I940J1040D01*
G37*
G36*
G01X174552D02*
G03X174557Y532790I274J-292D01*
G02X172656Y532771I-940J-1040D01*
G03X172651Y533359I-274J292D01*
G02X174552Y533378I940J1040D01*
G37*
G36*
G01X135845Y532771D02*
G03X135840Y533359I-274J292D01*
G02X137741Y533378I940J1040D01*
G03X137746Y532790I274J-292D01*
G02X135845Y532771I-940J-1040D01*
G37*
G36*
G01X1230841Y533134D02*
G03Y532555I276J-290D01*
G02X1228907I-967J-1015D01*
G03Y533134I-276J289D01*
G02X1230841I967J1015D01*
G37*
G36*
G01X1194030D02*
G03Y532555I276J-290D01*
G02X1192096I-967J-1015D01*
G03Y533134I-276J289D01*
G02X1194030I967J1015D01*
G37*
G36*
G01X1157219D02*
G03Y532555I276J-290D01*
G02X1155285I-967J-1015D01*
G03Y533134I-276J289D01*
G02X1157219I967J1015D01*
G37*
G36*
G01X1120407D02*
G03Y532555I276J-290D01*
G02X1118473I-967J-1015D01*
G03Y533134I-276J289D01*
G02X1120407I967J1015D01*
G37*
G36*
G01X939699D02*
G03Y532555I276J-290D01*
G02X937765I-967J-1015D01*
G03Y533134I-276J289D01*
G02X939699I967J1015D01*
G37*
G36*
G01X902888D02*
G03Y532555I276J-290D01*
G02X900954I-967J-1015D01*
G03Y533134I-276J289D01*
G02X902888I967J1015D01*
G37*
G36*
G01X866077D02*
G03Y532555I276J-290D01*
G02X864143I-967J-1015D01*
G03Y533134I-276J289D01*
G02X866077I967J1015D01*
G37*
G36*
G01X829266D02*
G03Y532555I276J-290D01*
G02X827332I-967J-1015D01*
G03Y533134I-276J289D01*
G02X829266I967J1015D01*
G37*
G36*
G01X792455D02*
G03Y532555I276J-290D01*
G02X790521I-967J-1015D01*
G03Y533134I-276J289D01*
G02X792455I967J1015D01*
G37*
G36*
G01X581233D02*
G03Y532555I276J-290D01*
G02X579299I-967J-1015D01*
G03Y533134I-276J289D01*
G02X581233I967J1015D01*
G37*
G36*
G01X544422D02*
G03Y532555I276J-290D01*
G02X542488I-967J-1015D01*
G03Y533134I-276J289D01*
G02X544422I967J1015D01*
G37*
G36*
G01X507611D02*
G03Y532555I276J-290D01*
G02X505677I-967J-1015D01*
G03Y533134I-276J289D01*
G02X507611I967J1015D01*
G37*
G36*
G01X470799D02*
G03Y532555I276J-290D01*
G02X468865I-967J-1015D01*
G03Y533134I-276J289D01*
G02X470799I967J1015D01*
G37*
G36*
G01X290091D02*
G03Y532555I276J-290D01*
G02X288157I-967J-1015D01*
G03Y533134I-276J289D01*
G02X290091I967J1015D01*
G37*
G36*
G01X253280D02*
G03Y532555I276J-290D01*
G02X251346I-967J-1015D01*
G03Y533134I-276J289D01*
G02X253280I967J1015D01*
G37*
G36*
G01X216469D02*
G03Y532555I276J-290D01*
G02X214535I-967J-1015D01*
G03Y533134I-276J289D01*
G02X216469I967J1015D01*
G37*
G36*
G01X179658D02*
G03Y532555I276J-290D01*
G02X177724I-967J-1015D01*
G03Y533134I-276J289D01*
G02X179658I967J1015D01*
G37*
G36*
G01X142847D02*
G03Y532555I276J-290D01*
G02X140913I-967J-1015D01*
G03Y533134I-276J289D01*
G02X142847I967J1015D01*
G37*
G36*
G01X4611Y532271D02*
G03X5189I289J277D01*
G02Y530329I1011J-971D01*
G03X4611I-289J-277D01*
G02Y532271I-1011J971D01*
G37*
G36*
G01X1482727Y530190D02*
G03X1482173I-277J-288D01*
G02Y532210I-973J1010D01*
G03X1482727I277J288D01*
G02Y530190I973J-1010D01*
G37*
G36*
G01X115539Y527414D02*
G03X115435Y526832I214J-338D01*
G02X113575Y527166I-1113J-852D01*
G03X113679Y527748I-214J338D01*
G02X115539Y527414I1113J852D01*
G37*
G36*
G01X1818548Y526492D02*
G03X1818168Y526005I11J-400D01*
G02X1816761Y527101I-1368J-305D01*
G03X1817141Y527588I-11J400D01*
G02X1818548Y526492I1368J305D01*
G37*
G36*
G01X1638728Y528723D02*
G03X1638940Y528154I350J-194D01*
G02X1636593Y527726I-810J-2208D01*
G03X1636591Y528333I-261J303D01*
G02X1638728Y528723I909J1067D01*
G37*
G36*
G01X1785026Y521592D02*
G03X1784449Y521570I-278J-288D01*
G02X1782379Y521539I-1049J930D01*
G03X1781811Y521552I-290J-275D01*
G02X1781859Y523523I-973J1010D01*
G03X1782427Y523510I290J275D01*
G02X1784374Y523508I972J-1010D01*
G03X1784951Y523530I278J288D01*
G02X1785026Y521592I1049J-930D01*
G37*
G36*
G01X1629183Y519602D02*
G03X1628572Y519538I-279J-287D01*
G02X1628383Y521324I-1165J780D01*
G03X1628994Y521388I279J287D01*
G02X1629183Y519602I1165J-780D01*
G37*
G36*
G01X1698850Y519221D02*
G03X1698272I-289J-277D01*
G02Y521163I-1011J971D01*
G03X1698850I289J277D01*
G02Y519221I1011J-971D01*
G37*
G36*
G01X1790804Y521062D02*
G03X1790594Y520541I159J-367D01*
G02X1788746Y521288I-1294J-541D01*
G03X1788956Y521809I-159J367D01*
G02X1790804Y521062I1294J541D01*
G37*
G36*
G01X1377636Y518921D02*
G03X1377082I-277J-288D01*
G02X1375031Y519035I-973J1010D01*
G03X1374417Y519037I-308J-256D01*
G02X1374423Y520836I-1072J903D01*
G03X1375037Y520834I308J256D01*
G02X1377082Y520941I1073J-903D01*
G03X1377636I277J288D01*
G02X1379572Y520950I973J-1010D01*
G03X1380124Y520952I275J290D01*
G02X1382173Y520836I970J-1012D01*
G03X1382787Y520834I308J256D01*
G02X1384832Y520941I1073J-903D01*
G03X1385386I277J288D01*
G02Y518921I973J-1010D01*
G03X1384832I-277J-288D01*
G02X1382781Y519035I-973J1010D01*
G03X1382167Y519037I-308J-256D01*
G02X1380132Y518921I-1072J903D01*
G03X1379580Y518919I-275J-290D01*
G02X1377636Y518921I-971J1012D01*
G37*
G36*
G01X1492700Y518498D02*
X1490099D01*
G02X1490100Y521502I1J1502D01*
G01X1492700D01*
G02X1494202Y520010I0J-1502D01*
G01Y519915D01*
X1494192Y519831D01*
G02X1492700Y518498I-1492J168D01*
G37*
G36*
G01X753910Y520148D02*
G03Y519594I288J-277D01*
G02X751890I-1010J-973D01*
G03Y520148I-288J277D01*
G02X753910I1010J973D01*
G37*
G36*
G01X1510005Y516654D02*
X1507404D01*
G02X1507405Y519656I1J1501D01*
G01X1510005D01*
G02X1511506Y518165I0J-1501D01*
G01Y518070D01*
X1511497Y517986D01*
G02X1510005Y516654I-1492J169D01*
G37*
G36*
G01X53987Y525432D02*
G03X54513I263J302D01*
G02X56487I987J-1132D01*
G03X57013I263J302D01*
G02X59132Y523313I987J-1132D01*
G03Y522787I302J-263D01*
G02X59075Y520751I-1132J-987D01*
G03X59061Y520207I286J-280D01*
G02X56933Y518094I-1125J-995D01*
G03X56420Y518113I-268J-297D01*
G02X54397Y518281I-920J1187D01*
G03X54103I-147J-136D01*
G02X54037Y518214I-1102J1020D01*
G03X54036Y517925I138J-145D01*
G02X51848Y517819I-1044J-1079D01*
G03X51849Y518335I-305J259D01*
G02X51868Y520287I1151J965D01*
G03Y520813I-302J263D01*
G02Y522787I1132J987D01*
G03Y523313I-302J263D01*
G02X53987Y525432I1132J987D01*
G37*
G36*
G01X1498054Y517624D02*
X1500655D01*
G02X1502156Y516132I-1J-1502D01*
G01Y516037D01*
X1502147Y515953D01*
G02X1500655Y514620I-1492J169D01*
G01X1498054D01*
G02Y517624I0J1502D01*
G37*
G36*
G01X1483227Y514690D02*
G03X1482673I-277J-288D01*
G02Y516710I-973J1010D01*
G03X1483227I277J288D01*
G02Y514690I973J-1010D01*
G37*
G36*
G01X63468Y516587D02*
G03Y517113I-302J263D01*
G02X63617Y519235I1132J987D01*
G03X63596Y519857I-262J303D01*
G02X63343Y522008I907J1197D01*
G03X63317Y522545I-309J254D01*
G02X63282Y524631I1063J1061D01*
G03Y525177I-292J273D01*
G02X65087Y527527I1098J1025D01*
G03X65604Y527653I188J353D01*
G02X67972Y525813I1237J-852D01*
G03Y525287I302J-263D01*
G02X67864Y523201I-1132J-987D01*
G03X67853Y522919I136J-147D01*
G02X67882Y520913I-1103J-1019D01*
G03Y520387I302J-263D01*
G02Y518413I-1132J-987D01*
G03Y517887I302J-263D01*
G02X66485Y515422I-1132J-987D01*
G03X66032Y515148I-71J-394D01*
G02X63468Y516587I-1432J452D01*
G37*
G36*
G01X1314671Y516789D02*
G03Y516211I277J-289D01*
G02X1312729I-971J-1011D01*
G03Y516789I-277J289D01*
G02X1314671I971J1011D01*
G37*
G36*
G01X1230845Y514503D02*
G03Y513925I277J-289D01*
G02X1228903I-971J-1011D01*
G03Y514503I-277J289D01*
G02X1230845I971J1011D01*
G37*
G36*
G01X1194034D02*
G03Y513925I277J-289D01*
G02X1192092I-971J-1011D01*
G03Y514503I-277J289D01*
G02X1194034I971J1011D01*
G37*
G36*
G01X1157223D02*
G03Y513925I277J-289D01*
G02X1155281I-971J-1011D01*
G03Y514503I-277J289D01*
G02X1157223I971J1011D01*
G37*
G36*
G01X1120411D02*
G03Y513925I277J-289D01*
G02X1118469I-971J-1011D01*
G03Y514503I-277J289D01*
G02X1120411I971J1011D01*
G37*
G36*
G01X939703D02*
G03Y513925I277J-289D01*
G02X937761I-971J-1011D01*
G03Y514503I-277J289D01*
G02X939703I971J1011D01*
G37*
G36*
G01X902892D02*
G03Y513925I277J-289D01*
G02X900950I-971J-1011D01*
G03Y514503I-277J289D01*
G02X902892I971J1011D01*
G37*
G36*
G01X866081D02*
G03Y513925I277J-289D01*
G02X864139I-971J-1011D01*
G03Y514503I-277J289D01*
G02X866081I971J1011D01*
G37*
G36*
G01X829270D02*
G03Y513925I277J-289D01*
G02X827328I-971J-1011D01*
G03Y514503I-277J289D01*
G02X829270I971J1011D01*
G37*
G36*
G01X792459D02*
G03Y513925I277J-289D01*
G02X790517I-971J-1011D01*
G03Y514503I-277J289D01*
G02X792459I971J1011D01*
G37*
G36*
G01X581237D02*
G03Y513925I277J-289D01*
G02X579295I-971J-1011D01*
G03Y514503I-277J289D01*
G02X581237I971J1011D01*
G37*
G36*
G01X544426D02*
G03Y513925I277J-289D01*
G02X542484I-971J-1011D01*
G03Y514503I-277J289D01*
G02X544426I971J1011D01*
G37*
G36*
G01X507615D02*
G03Y513925I277J-289D01*
G02X505673I-971J-1011D01*
G03Y514503I-277J289D01*
G02X507615I971J1011D01*
G37*
G36*
G01X470803D02*
G03Y513925I277J-289D01*
G02X468861I-971J-1011D01*
G03Y514503I-277J289D01*
G02X470803I971J1011D01*
G37*
G36*
G01X290095D02*
G03Y513925I277J-289D01*
G02X288153I-971J-1011D01*
G03Y514503I-277J289D01*
G02X290095I971J1011D01*
G37*
G36*
G01X253284D02*
G03Y513925I277J-289D01*
G02X251342I-971J-1011D01*
G03Y514503I-277J289D01*
G02X253284I971J1011D01*
G37*
G36*
G01X216473D02*
G03Y513925I277J-289D01*
G02X214531I-971J-1011D01*
G03Y514503I-277J289D01*
G02X216473I971J1011D01*
G37*
G36*
G01X179662D02*
G03Y513925I277J-289D01*
G02X177720I-971J-1011D01*
G03Y514503I-277J289D01*
G02X179662I971J1011D01*
G37*
G36*
G01X142851D02*
G03Y513925I277J-289D01*
G02X140909I-971J-1011D01*
G03Y514503I-277J289D01*
G02X142851I971J1011D01*
G37*
G36*
G01X1225745Y514289D02*
G03Y513711I277J-289D01*
G02X1223803I-971J-1011D01*
G03Y514289I-277J289D01*
G02X1225745I971J1011D01*
G37*
G36*
G01X1188934D02*
G03Y513711I277J-289D01*
G02X1186992I-971J-1011D01*
G03Y514289I-277J289D01*
G02X1188934I971J1011D01*
G37*
G36*
G01X1152123D02*
G03Y513711I277J-289D01*
G02X1150181I-971J-1011D01*
G03Y514289I-277J289D01*
G02X1152123I971J1011D01*
G37*
G36*
G01X1115311D02*
G03Y513711I277J-289D01*
G02X1113369I-971J-1011D01*
G03Y514289I-277J289D01*
G02X1115311I971J1011D01*
G37*
G36*
G01X934603D02*
G03Y513711I277J-289D01*
G02X932661I-971J-1011D01*
G03Y514289I-277J289D01*
G02X934603I971J1011D01*
G37*
G36*
G01X897792D02*
G03Y513711I277J-289D01*
G02X895850I-971J-1011D01*
G03Y514289I-277J289D01*
G02X897792I971J1011D01*
G37*
G36*
G01X860981D02*
G03Y513711I277J-289D01*
G02X859039I-971J-1011D01*
G03Y514289I-277J289D01*
G02X860981I971J1011D01*
G37*
G36*
G01X824170D02*
G03Y513711I277J-289D01*
G02X822228I-971J-1011D01*
G03Y514289I-277J289D01*
G02X824170I971J1011D01*
G37*
G36*
G01X787359D02*
G03Y513711I277J-289D01*
G02X785417I-971J-1011D01*
G03Y514289I-277J289D01*
G02X787359I971J1011D01*
G37*
G36*
G01X576137D02*
G03Y513711I277J-289D01*
G02X574195I-971J-1011D01*
G03Y514289I-277J289D01*
G02X576137I971J1011D01*
G37*
G36*
G01X539326D02*
G03Y513711I277J-289D01*
G02X537384I-971J-1011D01*
G03Y514289I-277J289D01*
G02X539326I971J1011D01*
G37*
G36*
G01X502515D02*
G03Y513711I277J-289D01*
G02X500573I-971J-1011D01*
G03Y514289I-277J289D01*
G02X502515I971J1011D01*
G37*
G36*
G01X465703D02*
G03Y513711I277J-289D01*
G02X463761I-971J-1011D01*
G03Y514289I-277J289D01*
G02X465703I971J1011D01*
G37*
G36*
G01X284995D02*
G03Y513711I277J-289D01*
G02X283053I-971J-1011D01*
G03Y514289I-277J289D01*
G02X284995I971J1011D01*
G37*
G36*
G01X248184D02*
G03Y513711I277J-289D01*
G02X246242I-971J-1011D01*
G03Y514289I-277J289D01*
G02X248184I971J1011D01*
G37*
G36*
G01X211373D02*
G03Y513711I277J-289D01*
G02X209431I-971J-1011D01*
G03Y514289I-277J289D01*
G02X211373I971J1011D01*
G37*
G36*
G01X174562D02*
G03Y513711I277J-289D01*
G02X172620I-971J-1011D01*
G03Y514289I-277J289D01*
G02X174562I971J1011D01*
G37*
G36*
G01X137751D02*
G03Y513711I277J-289D01*
G02X135809I-971J-1011D01*
G03Y514289I-277J289D01*
G02X137751I971J1011D01*
G37*
G36*
G01X1775235Y513745D02*
G03X1775789Y513710I295J270D01*
G02X1775660Y511695I906J-1070D01*
G03X1775106Y511730I-295J-270D01*
G02X1775235Y513745I-906J1070D01*
G37*
G36*
G01X1460011Y514043D02*
G03X1459949Y513438I227J-329D01*
G02X1458137Y513623I-1014J-968D01*
G03X1458199Y514228I-227J329D01*
G02X1460186Y516206I1014J968D01*
G03X1460740I277J288D01*
G02Y514186I973J-1010D01*
G03X1460186I-277J-288D01*
G02X1460011Y514043I-972J1011D01*
G37*
G36*
G01X730626Y510592D02*
G03X730049Y510570I-278J-288D01*
G02X729974Y512508I-1049J930D01*
G03X730551Y512530I278J288D01*
G02X730626Y510592I1049J-930D01*
G37*
G36*
G01X1509586Y509144D02*
X1506984D01*
G02X1506985Y512146I1J1501D01*
G01X1509586D01*
G02X1510889Y511390I0J-1501D01*
G02X1511086Y510655I-1304J-744D01*
G01Y510653D01*
X1511087Y510652D01*
G02X1509586Y509144I-1501J-7D01*
G37*
G36*
G01X682999Y529502D02*
X683501D01*
G03X683878Y530034I0J400D01*
G02X683958Y531151I1322J467D01*
G03X683803Y531684I-354J186D01*
G02X685742Y532249I697J1216D01*
G03X685897Y531716I354J-186D01*
G02X686521Y530031I-697J-1216D01*
G03X686898Y529498I377J-133D01*
G01X700010D01*
X703002Y526506D01*
Y519999D01*
X702402Y519399D01*
Y510599D01*
X701601Y509798D01*
X679401D01*
X678501Y508898D01*
X675430D01*
X674298Y510030D01*
Y517499D01*
X673699Y518098D01*
X671999D01*
X670998Y519099D01*
Y522001D01*
X671002Y522005D01*
Y522468D01*
X672500Y523966D01*
X680963D01*
X681498Y524501D01*
Y528001D01*
X682999Y529502D01*
G37*
G36*
G01X1614027Y509290D02*
G03X1613473I-277J-288D01*
G02Y511310I-973J1010D01*
G03X1614027I277J288D01*
G02Y509290I973J-1010D01*
G37*
G36*
G01X1549271Y510789D02*
G03Y510211I277J-289D01*
G02X1547329I-971J-1011D01*
G03Y510789I-277J289D01*
G02X1549271I971J1011D01*
G37*
G36*
G01X721845Y510766D02*
G03X722033Y510244I365J-163D01*
G02X720134Y509558I-619J-1258D01*
G03X719946Y510080I-365J163D01*
G02X721845Y510766I619J1258D01*
G37*
G36*
G01X1500877Y506738D02*
X1498276D01*
G02X1498277Y509740I1J1501D01*
G01X1500877D01*
G02X1502378Y508249I0J-1501D01*
G01Y508154D01*
X1502369Y508070D01*
G02X1500877Y506738I-1492J169D01*
G37*
G36*
G01X1485692Y509502D02*
X1488293D01*
G02X1489794Y508010I0J-1501D01*
G01Y507915D01*
X1489785Y507831D01*
G02X1488293Y506498I-1492J168D01*
G01X1485692D01*
G02Y509502I0J1502D01*
G37*
G36*
G01X1481975Y506474D02*
X1479374D01*
G02X1479375Y509476I1J1501D01*
G01X1481975D01*
G02X1483476Y507985I0J-1501D01*
G01Y507890D01*
X1483467Y507806D01*
G02X1481975Y506474I-1492J169D01*
G37*
G36*
G01X115452Y509327D02*
G03Y508773I288J-277D01*
G02X113432I-1010J-973D01*
G03Y509327I-288J277D01*
G02X115452I1010J973D01*
G37*
G36*
G01X1844304Y507840D02*
G03X1843851Y507461I-54J-396D01*
G02X1842636Y508910I-1401J59D01*
G03X1843089Y509289I54J396D01*
G02X1844304Y507840I1401J-59D01*
G37*
G36*
G01X34223Y509289D02*
G03X34058Y509518I-197J32D01*
G02X33490Y509735I241J1482D01*
G03X32964Y509651I-216J-337D01*
G02X32610Y511865I-1164J949D01*
G03X33136Y511949I216J337D01*
G02X35288Y512131I1164J-949D01*
G03X35856Y512173I263J301D01*
G02X38495Y511340I1144J-973D01*
G03X38958Y510982I399J37D01*
G02X39428Y508015I241J-1483D01*
G03X39092Y507574I61J-395D01*
G02X36111Y507205I-1492J-174D01*
G03X35713Y507553I-397J-52D01*
G02X34223Y509289I-6J1502D01*
G37*
G36*
G01X1556448Y508744D02*
G03Y508190I288J-277D01*
G02X1554428I-1010J-973D01*
G03Y508744I-288J277D01*
G02X1556448I1010J973D01*
G37*
G36*
G01X1543446Y508589D02*
G03Y508011I277J-289D01*
G02X1541504I-971J-1011D01*
G03Y508589I-277J289D01*
G02X1543446I971J1011D01*
G37*
G36*
G01X764960Y507567D02*
G03Y507013I288J-277D01*
G02X762940I-1010J-973D01*
G03Y507567I-288J277D01*
G02Y509513I1010J973D01*
G03Y510067I-288J277D01*
G02X764960I1010J973D01*
G03Y509513I288J-277D01*
G02Y507567I-1010J-973D01*
G37*
G36*
G01X703409Y505754D02*
G03X702898Y505399I-112J-384D01*
G02X701891Y506846I-1398J101D01*
G03X702402Y507201I112J384D01*
G02X703409Y505754I1398J-101D01*
G37*
G36*
G01X712207Y504510D02*
G03X711639I-284J-282D01*
G02X709492Y504695I-997J986D01*
G03X708872Y504741I-329J-228D01*
G02X709001Y506501I-1022J960D01*
G03X709621Y506455I329J228D01*
G02X711636Y506486I1022J-959D01*
G03X712204I284J282D01*
G02X714199Y506484I997J-986D01*
G03X714798Y506517I285J280D01*
G02X714901Y504666I1102J-867D01*
G03X714302Y504633I-285J-280D01*
G02X712207Y504510I-1102J867D01*
G37*
G36*
G01X1650037Y503846D02*
G03X1649482Y503744I-226J-330D01*
G02X1648998Y505777I-1152J800D01*
G03X1649539Y505936I191J351D01*
G02X1650037Y503846I1405J-770D01*
G37*
G36*
G01X1568662Y504677D02*
G03X1569135Y505096I74J393D01*
G02X1570261Y502751I3463J220D01*
G03X1569638Y502643I-270J-296D01*
G02X1568662Y504677I-1238J657D01*
G37*
G36*
G01X1508625Y504540D02*
X1511126D01*
G02X1512628Y503048I0J-1502D01*
G01Y503038D01*
G02X1511126Y501536I-1502J0D01*
G01X1508625D01*
G02Y504540I0J1502D01*
G37*
G36*
G01X1549310Y503027D02*
G03Y502473I288J-277D01*
G02X1547290I-1010J-973D01*
G03Y503027I-288J277D01*
G02X1549310I1010J973D01*
G37*
G36*
G01X1528002Y503810D02*
Y501300D01*
G02X1524998I-1502J0D01*
G01Y503801D01*
G02X1528002Y503810I1502J-1D01*
G37*
G36*
G01X675626Y500292D02*
G03X675049Y500270I-278J-288D01*
G02X672987Y500231I-1049J930D01*
G03X672432Y500253I-289J-277D01*
G02X672513Y502269I-932J1047D01*
G03X673068Y502247I289J277D01*
G02X674974Y502208I932J-1047D01*
G03X675551Y502230I278J288D01*
G02X675626Y500292I1049J-930D01*
G37*
G36*
G01X1738703Y502186D02*
G03X1738508Y501612I149J-371D01*
G02X1736777Y502201I-1208J-712D01*
G03X1736972Y502775I-149J371D01*
G02X1738703Y502186I1208J712D01*
G37*
G36*
G01X1874950Y501383D02*
G03X1875469Y501146I376J136D01*
G02X1874655Y499359I504J-1308D01*
G03X1874136Y499596I-376J-136D01*
G02X1874950Y501383I-504J1308D01*
G37*
G36*
G01X648006Y500173D02*
G03X647601Y499757I-5J-400D01*
G02X646219Y501102I-1401J-57D01*
G03X646624Y501518I5J400D01*
G02X648006Y500173I1401J57D01*
G37*
G36*
G01X1269329Y500380D02*
G03X1268968Y499918I34J-398D01*
G02X1267464Y501091I-1384J-224D01*
G03X1267825Y501553I-34J398D01*
G02X1269329Y500380I1384J224D01*
G37*
G36*
G01X745051Y498664D02*
G03X744497I-277J-288D01*
G02X742514Y500647I-973J1010D01*
G03Y501201I-288J277D01*
G02X744497Y503184I1010J973D01*
G03X745051I277J288D01*
G02X746997I973J-1010D01*
G03X747551I277J288D01*
G02X749401Y501080I973J-1010D01*
G03Y500768I125J-156D01*
G02X749485Y500695I-877J-1094D01*
G03X749786Y500725I138J145D01*
G02X750099Y498788I1145J-809D01*
G03X749564Y498734I-238J-322D01*
G02X747551Y498664I-1040J940D01*
G03X746997I-277J-288D01*
G02X745051I-973J1010D01*
G37*
G36*
G01X1532695Y501067D02*
G03Y500513I288J-277D01*
G02X1530675I-1010J-973D01*
G03Y501067I-288J277D01*
G02X1532695I1010J973D01*
G37*
G36*
G01X1556520Y501002D02*
G03Y500448I288J-277D01*
G02X1554500I-1010J-973D01*
G03Y501002I-288J277D01*
G02X1556520I1010J973D01*
G37*
G36*
G01X1543485Y500927D02*
G03Y500373I288J-277D01*
G02X1541465I-1010J-973D01*
G03Y500927I-288J277D01*
G02X1543485I1010J973D01*
G37*
G36*
G01X710341Y498494D02*
G03X709755Y498476I-285J-281D01*
G02X709698Y500384I-1055J923D01*
G03X710284Y500402I285J281D01*
G02X710341Y498494I1055J-923D01*
G37*
G36*
G01X1705601Y500560D02*
G03X1705612Y499982I282J-284D01*
G02X1703453Y497902I-1015J-1107D01*
G03X1702908Y497962I-304J-259D01*
G02X1700871Y500148I-904J1200D01*
G03X1700844Y500702I-301J263D01*
G02X1702995Y502794I1030J1093D01*
G03X1703557Y502759I299J266D01*
G02X1705601Y500560I986J-1133D01*
G37*
G36*
G01X1343068Y499298D02*
X1342740D01*
G03X1342365Y498760I0J-400D01*
G02X1340023Y497320I-1315J-485D01*
G03X1339447Y497331I-293J-272D01*
G01X1339415Y497298D01*
X1330585D01*
X1328998Y498885D01*
Y510324D01*
X1332576Y513902D01*
X1343055D01*
X1344967Y511990D01*
X1356013D01*
X1359002Y509001D01*
Y505499D01*
X1357502Y503999D01*
Y498671D01*
X1356129Y497298D01*
X1347185D01*
X1346678Y497806D01*
G03X1346032Y497691I-283J-283D01*
G02X1343444Y498762I-1271J591D01*
G03X1343068Y499298I-376J136D01*
G37*
G36*
G01X-17651Y498430D02*
G03X-17666Y499031I-271J294D01*
G02X-15815Y499076I900J1075D01*
G03X-15800Y498475I271J-294D01*
G02X-17651Y498430I-900J-1075D01*
G37*
G36*
G01X1673481Y498725D02*
G03X1673416Y498165I250J-313D01*
G02X1671438Y498395I-1103J-865D01*
G03X1671503Y498955I-250J313D01*
G02X1673481Y498725I1103J865D01*
G37*
G36*
G01X113060Y499007D02*
G03X113164Y498418I314J-248D01*
G02X111328Y498095I-737J-1193D01*
G03X111224Y498684I-314J248D01*
G02X113060Y499007I737J1193D01*
G37*
G36*
G01X1758575Y494894D02*
X1753575D01*
G02Y497918I0J1512D01*
G01X1758575D01*
G02X1760086Y496416I-1J-1512D01*
G01Y496321D01*
X1760077Y496237D01*
G02X1758575Y494894I-1502J169D01*
G37*
G36*
G01X1748125Y494888D02*
X1743124D01*
G02X1743125Y497912I1J1512D01*
G01X1748125D01*
G02X1749636Y496410I-1J-1512D01*
G01Y496315D01*
X1749627Y496231D01*
G02X1748125Y494888I-1502J168D01*
G37*
G36*
G01X1157223Y495156D02*
G03Y494578I277J-289D01*
G02X1155281I-971J-1011D01*
G03Y495156I-277J289D01*
G02X1157223I971J1011D01*
G37*
G36*
G01X507615D02*
G03Y494578I277J-289D01*
G02X505673I-971J-1011D01*
G03Y495156I-277J289D01*
G02X507615I971J1011D01*
G37*
G36*
G01X1193992Y495159D02*
G03Y494559I265J-300D01*
G02X1192134I-929J-1050D01*
G03Y495159I-265J300D01*
G02X1193992I929J1050D01*
G37*
G36*
G01X544384D02*
G03Y494559I265J-300D01*
G02X542526I-929J-1050D01*
G03Y495159I-265J300D01*
G02X544384I929J1050D01*
G37*
G36*
G01X1152097Y495117D02*
G03Y494517I265J-300D01*
G02X1150239I-929J-1050D01*
G03Y495117I-265J300D01*
G02X1152097I929J1050D01*
G37*
G36*
G01X502489D02*
G03Y494517I265J-300D01*
G02X500631I-929J-1050D01*
G03Y495117I-265J300D01*
G02X502489I929J1050D01*
G37*
G36*
G01X939703Y494933D02*
G03Y494355I277J-289D01*
G02X937761I-971J-1011D01*
G03Y494933I-277J289D01*
G02X939703I971J1011D01*
G37*
G36*
G01X934618D02*
G03Y494355I277J-289D01*
G02X932676I-971J-1011D01*
G03Y494933I-277J289D01*
G02X934618I971J1011D01*
G37*
G36*
G01X290095D02*
G03Y494355I277J-289D01*
G02X288153I-971J-1011D01*
G03Y494933I-277J289D01*
G02X290095I971J1011D01*
G37*
G36*
G01X285010D02*
G03Y494355I277J-289D01*
G02X283068I-971J-1011D01*
G03Y494933I-277J289D01*
G02X285010I971J1011D01*
G37*
G36*
G01X902892Y494803D02*
G03Y494225I277J-289D01*
G02X900950I-971J-1011D01*
G03Y494803I-277J289D01*
G02X902892I971J1011D01*
G37*
G36*
G01X253284D02*
G03Y494225I277J-289D01*
G02X251342I-971J-1011D01*
G03Y494803I-277J289D01*
G02X253284I971J1011D01*
G37*
G36*
G01X1188907Y494859D02*
G03Y494259I265J-300D01*
G02X1187049I-929J-1050D01*
G03Y494859I-265J300D01*
G02X1188907I929J1050D01*
G37*
G36*
G01X897765D02*
G03Y494259I265J-300D01*
G02X895907I-929J-1050D01*
G03Y494859I-265J300D01*
G02X897765I929J1050D01*
G37*
G36*
G01X539299D02*
G03Y494259I265J-300D01*
G02X537441I-929J-1050D01*
G03Y494859I-265J300D01*
G02X539299I929J1050D01*
G37*
G36*
G01X248157D02*
G03Y494259I265J-300D01*
G02X246299I-929J-1050D01*
G03Y494859I-265J300D01*
G02X248157I929J1050D01*
G37*
G36*
G01X1296341Y494226D02*
G03X1296927Y494180I314J248D01*
G02X1296777Y492283I951J-1030D01*
G03X1296191Y492329I-314J-248D01*
G02X1296341Y494226I-951J1030D01*
G37*
G36*
G01X694614Y493330D02*
G03Y492776I288J-277D01*
G02X692594I-1010J-973D01*
G03Y493330I-288J277D01*
G02X694614I1010J973D01*
G37*
G36*
G01X690835Y493282D02*
G03Y492728I288J-277D01*
G02X688815I-1010J-973D01*
G03Y493282I-288J277D01*
G02X690835I1010J973D01*
G37*
G36*
G01X88867Y500506D02*
G03X89413I273J292D01*
G02X91467I1027J-1096D01*
G03X92013I273J292D01*
G02X94067I1027J-1096D01*
G03X94613I273J292D01*
G02X96667I1027J-1096D01*
G03X97213I273J292D01*
G02X99336Y498383I1027J-1096D01*
G03Y497837I292J-273D01*
G02X97093Y495841I-1096J-1027D01*
G03X96787I-153J-130D01*
G02X96668Y495715I-1150J966D01*
G03X96684Y495410I137J-146D01*
G02X94678Y493190I-907J-1197D01*
G03X94092Y493189I-293J-273D01*
G02X91963Y493114I-1102J1021D01*
G03X91417I-273J-292D01*
G02X91359Y493063I-1020J1102D01*
G03Y492757I130J-153D01*
G02X89363Y490514I-969J-1147D01*
G03X88817I-273J-292D01*
G02X86694Y492637I-1027J1096D01*
G03Y493183I-292J273D01*
G02X86714Y495258I1096J1027D01*
G03X86724Y495804I-287J278D01*
G02X86744Y497837I1116J1006D01*
G03Y498383I-292J273D01*
G02X88867Y500506I1096J1027D01*
G37*
G36*
G01X1842089Y490529D02*
G03X1841511I-289J-277D01*
G02X1839529Y492511I-1011J971D01*
G03Y493089I-277J289D01*
G02X1841511Y495071I971J1011D01*
G03X1842089I289J277D01*
G02X1844071Y493089I1011J-971D01*
G03Y492511I277J-289D01*
G02X1842089Y490529I-971J-1011D01*
G37*
G36*
G01X1249880Y490086D02*
G03X1249721Y489554I196J-348D01*
G02X1247787Y490135I-1247J-641D01*
G03X1247946Y490667I-196J348D01*
G02X1249880Y490086I1247J641D01*
G37*
G36*
G01X1819124Y490442D02*
X1824125D01*
G02X1825636Y488940I-1J-1512D01*
G01Y488845D01*
X1825627Y488761D01*
G02X1824125Y487418I-1502J169D01*
G01X1819124D01*
G02Y490442I0J1512D01*
G37*
G36*
G01X1796124D02*
X1801125D01*
G02X1802636Y488940I-1J-1512D01*
G01Y488845D01*
X1802627Y488761D01*
G02X1801125Y487418I-1502J169D01*
G01X1796124D01*
G02Y490442I0J1512D01*
G37*
G36*
G01X1784524D02*
X1789525D01*
G02X1791036Y488940I-1J-1512D01*
G01Y488845D01*
X1791027Y488761D01*
G02X1789525Y487418I-1502J169D01*
G01X1784524D01*
G02Y490442I0J1512D01*
G37*
G36*
G01X1811975Y487218D02*
X1806975D01*
G02Y490242I0J1512D01*
G01X1811975D01*
G02X1813486Y488740I-1J-1512D01*
G01Y488645D01*
X1813477Y488561D01*
G02X1811975Y487218I-1502J169D01*
G37*
G36*
G01X1754300Y486344D02*
X1749299D01*
G02X1749300Y489366I1J1511D01*
G01X1754300D01*
G02X1755812Y487865I0J-1512D01*
G01Y487770D01*
X1755802Y487686D01*
G02X1754300Y486344I-1502J170D01*
G37*
G36*
G01X1741900Y486244D02*
X1736899D01*
G02X1736900Y489266I1J1511D01*
G01X1741900D01*
G02X1743412Y487765I0J-1512D01*
G01Y487670D01*
X1743402Y487586D01*
G02X1741900Y486244I-1502J170D01*
G37*
G36*
G01X1770325Y485844D02*
X1765324D01*
G02X1765325Y488866I1J1511D01*
G01X1770325D01*
G02X1771836Y487365I0J-1511D01*
G01Y487270D01*
X1771827Y487186D01*
G02X1770325Y485844I-1502J169D01*
G37*
G36*
G01X1450607Y488218D02*
G03X1451188Y488206I296J268D01*
G02X1451149Y486281I1000J-983D01*
G03X1450568Y486293I-296J-268D01*
G02X1450607Y488218I-1000J983D01*
G37*
G36*
G01X1257127Y484913D02*
G02X1257642Y486624I-777J1167D01*
G01X1257694Y486502D01*
X1266752D01*
Y484498D01*
X1257748D01*
Y484580D01*
G03X1257127Y484913I-400J0D01*
G37*
G36*
G01X721807Y486893D02*
G03X721585Y486360I145J-373D01*
G02X719794Y487107I-1285J-560D01*
G03X720016Y487640I-145J373D01*
G02X721934Y489451I1285J560D01*
G03X722487Y489661I181J357D01*
G02X723159Y487897I1305J-513D01*
G03X722606Y487687I-181J-357D01*
G02X721807Y486893I-1304J514D01*
G37*
G36*
G01X676752Y484669D02*
G03X676148Y484662I-299J-266D01*
G02X676128Y486501I-1068J908D01*
G03X676732Y486508I299J266D01*
G02X678732Y486647I1068J-908D01*
G03X679287Y486669I266J299D01*
G02X679368Y484653I1013J-969D01*
G03X678813Y484631I-266J-299D01*
G02X676752Y484669I-1013J969D01*
G37*
G36*
G01X1841471Y486239D02*
G03Y485661I277J-289D01*
G02X1839529I-971J-1011D01*
G03Y486239I-277J289D01*
G02X1841471I971J1011D01*
G37*
G36*
G01X610478Y485035D02*
G03X611039Y485021I288J278D01*
G02X610992Y483025I961J-1021D01*
G03X610431Y483039I-288J-278D01*
G02X610478Y485035I-961J1021D01*
G37*
G36*
G01X709168Y482570D02*
G03X708585Y482538I-277J-289D01*
G02X708480Y484452I-1074J901D01*
G03X709063Y484484I277J289D01*
G02X709168Y482570I1074J-901D01*
G37*
G36*
G01X1652882Y483774D02*
G03X1652896Y483210I290J-275D01*
G02X1650911Y483164I-970J-1013D01*
G03X1650897Y483728I-290J275D01*
G02X1652882Y483774I970J1013D01*
G37*
G36*
G01X1616627Y480390D02*
G03X1616073I-277J-288D01*
G02Y482410I-973J1010D01*
G03X1616627I277J288D01*
G02Y480390I973J-1010D01*
G37*
G36*
G01X1672021Y482589D02*
G03Y482011I277J-289D01*
G02X1670079I-971J-1011D01*
G03Y482589I-277J289D01*
G02X1672021I971J1011D01*
G37*
G36*
G01X606268Y482376D02*
G03X606278Y481843I303J-261D01*
G02X604187Y481806I-1029J-952D01*
G03X604177Y482339I-303J261D01*
G02X606268Y482376I1029J952D01*
G37*
G36*
G01X1291510Y481727D02*
G03Y481173I288J-277D01*
G02X1289490I-1010J-973D01*
G03Y481727I-288J277D01*
G02X1291510I1010J973D01*
G37*
G36*
G01X1794975Y477788D02*
X1789974D01*
G02X1789975Y480812I1J1512D01*
G01X1794975D01*
G02X1796486Y479310I-1J-1512D01*
G01Y479215D01*
X1796477Y479131D01*
G02X1794975Y477788I-1502J168D01*
G37*
G36*
G01X658794Y478143D02*
G03X658229Y478136I-279J-287D01*
G02X658203Y480122I-1002J980D01*
G03X658768Y480129I279J287D01*
G02X660708Y480191I1002J-980D01*
G03X661243I267J297D01*
G02Y478107I938J-1042D01*
G03X660708I-268J-297D01*
G02X658794Y478143I-938J1042D01*
G37*
G36*
G01X1817375Y476808D02*
X1812375D01*
G02Y479832I0J1512D01*
G01X1817375D01*
G02X1818886Y478330I-1J-1512D01*
G01Y478235D01*
X1818877Y478151D01*
G02X1817375Y476808I-1502J169D01*
G37*
G36*
G01X1829967Y475416D02*
X1825297D01*
G02Y478438I0J1511D01*
G01X1829967D01*
G02X1831478Y476937I0J-1511D01*
G01Y476842D01*
X1831469Y476758D01*
G02X1829967Y475416I-1502J169D01*
G37*
G36*
G01X1766700Y474144D02*
X1761699D01*
G02X1761700Y477166I1J1511D01*
G01X1766700D01*
G02X1768212Y475665I0J-1512D01*
G01Y475570D01*
X1768202Y475486D01*
G02X1766700Y474144I-1502J170D01*
G37*
G36*
G01X15473Y476510D02*
G03X16027I277J288D01*
G02Y474490I973J-1010D01*
G03X15473I-277J-288D01*
G02X13549Y474470I-973J1010D01*
G03X12988Y474451I-271J-294D01*
G02X12923Y476447I-1016J966D01*
G03X13484Y476466I271J294D01*
G02X15473Y476510I1016J-966D01*
G37*
G36*
G01X1779300Y473544D02*
X1774299D01*
G02X1774300Y476566I1J1511D01*
G01X1779300D01*
G02X1780812Y475065I0J-1512D01*
G01Y474970D01*
X1780802Y474886D01*
G02X1779300Y473544I-1502J170D01*
G37*
G36*
G01X1806525Y472444D02*
X1801524D01*
G02X1801525Y475466I1J1511D01*
G01X1806525D01*
G02X1808036Y473965I0J-1511D01*
G01Y473870D01*
X1808027Y473786D01*
G02X1806525Y472444I-1502J169D01*
G37*
G36*
G01X-13140Y474769D02*
G03X-12540I300J265D01*
G02Y472911I1050J-929D01*
G03X-13140I-300J-265D01*
G02Y474769I-1050J929D01*
G37*
G36*
G01X1679576Y472270D02*
G03X1679022Y472244I-263J-301D01*
G02X1678925Y474260I-1021J961D01*
G03X1679479Y474286I263J301D01*
G02X1679576Y472270I1021J-961D01*
G37*
G36*
G01X1895789Y469229D02*
G03X1895211I-289J-277D01*
G02X1893117Y471090I-1011J971D01*
G03X1893095Y471623I-309J254D01*
G02X1895111Y473571I1005J977D01*
G03X1895689I289J277D01*
G02X1897634Y473646I1011J-971D01*
G03X1898166I266J298D01*
G02X1900111Y473571I934J-1046D01*
G03X1900689I289J277D01*
G02X1902632Y473647I1011J-971D01*
G03X1903187Y473669I266J299D01*
G02X1905283Y471810I1013J-969D01*
G03X1905305Y471277I309J-254D01*
G02X1903368Y469253I-1005J-977D01*
G03X1902813Y469231I-266J-299D01*
G02X1900789Y469229I-1013J969D01*
G03X1900211I-289J-277D01*
G02X1898266Y469154I-1011J971D01*
G03X1897734I-266J-298D01*
G02X1895789Y469229I-934J1046D01*
G37*
G36*
G01X1634422Y471660D02*
G03X1634365Y471124I265J-299D01*
G02X1632012Y471373I-1290J-950D01*
G03X1632069Y471909I-265J299D01*
G02X1634422Y471660I1290J950D01*
G37*
G36*
G01X1463389Y464529D02*
G03X1462811I-289J-277D01*
G02Y466471I-1011J971D01*
G03X1463389I289J277D01*
G02Y464529I1011J-971D01*
G37*
G36*
G01X1455589D02*
G03X1455011I-289J-277D01*
G02Y466471I-1011J971D01*
G03X1455589I289J277D01*
G02Y464529I1011J-971D01*
G37*
G36*
G01X1667496Y465448D02*
G03X1667236Y465939I-384J111D01*
G02X1666657Y466306I438J1332D01*
G03X1666074Y466303I-290J-276D01*
G02X1666064Y468222I-1027J954D01*
G03X1666647Y468225I290J276D01*
G02X1669021Y466883I1027J-954D01*
G03X1669281Y466392I384J-111D01*
G02X1667496Y465448I-438J-1332D01*
G37*
G36*
G01X1322493Y464943D02*
G03X1323080Y464737I377J134D01*
G02X1322494Y463074I735J-1194D01*
G03X1321907Y463280I-377J-134D01*
G02X1322493Y464943I-735J1194D01*
G37*
G36*
G01X1624247Y462902D02*
G03X1624014Y462389I142J-374D01*
G02X1622202Y463211I-1314J-489D01*
G03X1622435Y463724I-142J374D01*
G02X1624247Y462902I1314J489D01*
G37*
G36*
G01X1586502Y459200D02*
G03X1585948I-277J-288D01*
G02X1583863Y459356I-973J1010D01*
G03X1583247Y459378I-317J-244D01*
G02X1580798Y460293I-1047J932D01*
G03X1580392Y460688I-400J-5D01*
G02X1581772Y462107I-22J1402D01*
G03X1582178Y461712I400J5D01*
G02X1582413Y461696I23J-1402D01*
G03X1582857Y462206I61J395D01*
G02X1585455Y461984I1343J404D01*
G03X1585627Y461451I358J-179D01*
G02X1585948Y461220I-650J-1242D01*
G03X1586502I277J288D01*
G02Y459200I973J-1010D01*
G37*
G36*
G01X1463389Y458829D02*
G03X1462811I-289J-277D01*
G02Y460771I-1011J971D01*
G03X1463389I289J277D01*
G02Y458829I1011J-971D01*
G37*
G36*
G01X1455589D02*
G03X1455011I-289J-277D01*
G02Y460771I-1011J971D01*
G03X1455589I289J277D01*
G02Y458829I1011J-971D01*
G37*
G36*
G01X1640942Y458579D02*
G03X1640920Y457958I241J-319D01*
G02X1639158Y458021I-920J-1058D01*
G03X1639180Y458642I-241J319D01*
G02X1640942Y458579I920J1058D01*
G37*
G36*
G01X1685410Y458414D02*
G03Y457839I279J-288D01*
G02X1683460I-975J-1007D01*
G03Y458414I-279J287D01*
G02X1685410I975J1007D01*
G37*
G36*
G01X1676848Y457738D02*
G03X1676782Y457142I230J-327D01*
G02X1674937Y457346I-1038J-942D01*
G03X1675003Y457942I-230J327D01*
G02X1676848Y457738I1038J942D01*
G37*
G36*
G01X1529333Y455957D02*
G03X1529260Y455398I245J-316D01*
G02X1527289Y455655I-1113J-852D01*
G03X1527362Y456214I-245J316D01*
G02X1529333Y455957I1113J852D01*
G37*
G36*
G01X1463389Y453129D02*
G03X1462811I-289J-277D01*
G02Y455071I-1011J971D01*
G03X1463389I289J277D01*
G02Y453129I1011J-971D01*
G37*
G36*
G01X1455589D02*
G03X1455011I-289J-277D01*
G02Y455071I-1011J971D01*
G03X1455589I289J277D01*
G02Y453129I1011J-971D01*
G37*
G36*
G01X1411986Y457571D02*
Y453476D01*
X1411977Y453392D01*
G02X1408964Y453561I-1502J169D01*
G01Y457561D01*
G02X1411986Y457571I1511J0D01*
G37*
G36*
G01X1404286D02*
Y453476D01*
X1404277Y453392D01*
G02X1401264Y453561I-1502J169D01*
G01Y457561D01*
G02X1404286Y457571I1511J0D01*
G37*
G36*
G01X1396886D02*
Y453476D01*
X1396877Y453392D01*
G02X1393864Y453561I-1502J169D01*
G01Y457562D01*
G02X1396886Y457571I1511J-1D01*
G37*
G36*
G01X1589693Y453068D02*
G03X1590295Y453064I303J261D01*
G02X1590283Y451217I1049J-930D01*
G03X1589681Y451221I-303J-261D01*
G02X1587504Y451319I-1049J930D01*
G03X1586902Y451367I-322J-238D01*
G02X1584927Y451378I-982J1001D01*
G03X1584325Y451338I-284J-282D01*
G02X1584201Y453175I-1117J847D01*
G03X1584803Y453215I284J282D01*
G02X1587048Y453200I1117J-847D01*
G03X1587650Y453152I322J238D01*
G02X1589693Y453068I982J-1001D01*
G37*
G36*
G01X1620175Y453672D02*
G03X1620664Y453361I393J77D01*
G02X1619625Y451728I336J-1361D01*
G03X1619136Y452039I-393J-77D01*
G02X1620175Y453672I-336J1361D01*
G37*
G36*
G01X1662542Y452789D02*
G03X1662548Y452234I291J-274D01*
G02X1660529Y452213I-999J-983D01*
G03X1660523Y452768I-291J274D01*
G02X1660492Y454703I999J984D01*
G03X1660481Y455257I-294J271D01*
G02X1662500Y455299I989J994D01*
G03X1662511Y454745I294J-271D01*
G02X1662542Y452789I-989J-994D01*
G37*
G36*
G01X1867886Y451591D02*
G03X1867450Y451172I-36J-398D01*
G02X1866179Y452496I-1400J-72D01*
G03X1866615Y452915I36J398D01*
G02X1869093Y453883I1400J72D01*
G03X1869715Y453891I308J256D01*
G02X1869737Y452126I1100J-869D01*
G03X1869115Y452118I-308J-256D01*
G02X1867886Y451591I-1100J869D01*
G37*
G36*
G01X1836495Y449088D02*
X1831494D01*
G02X1831495Y452112I1J1512D01*
G01X1836495D01*
G02X1838006Y450610I-1J-1512D01*
G01Y450515D01*
X1837997Y450431D01*
G02X1836495Y449088I-1502J168D01*
G37*
G36*
G01X1818760Y451920D02*
X1823760D01*
G02X1825272Y450418I0J-1512D01*
G01Y450323D01*
X1825262Y450239D01*
G02X1823760Y448896I-1502J169D01*
G01X1818760D01*
G02Y451920I0J1512D01*
G37*
G36*
G01X1811161Y448896D02*
X1806161D01*
G02Y451920I0J1512D01*
G01X1811161D01*
G02X1812672Y450418I-1J-1512D01*
G01Y450323D01*
X1812663Y450239D01*
G02X1811161Y448896I-1502J169D01*
G37*
G36*
G01X1793562Y451920D02*
X1798563D01*
G02X1800074Y450418I-1J-1512D01*
G01Y450323D01*
X1800065Y450239D01*
G02X1798563Y448896I-1502J169D01*
G01X1793562D01*
G02Y451920I1J1512D01*
G37*
G36*
G01X1780963D02*
X1785964D01*
G02X1787476Y450418I0J-1512D01*
G01Y450323D01*
X1787466Y450239D01*
G02X1785964Y448896I-1502J168D01*
G01X1780963D01*
G02Y451920I0J1512D01*
G37*
G36*
G01X1768366D02*
X1773366D01*
G02X1774878Y450418I0J-1512D01*
G01Y450323D01*
X1774868Y450239D01*
G02X1773366Y448896I-1502J169D01*
G01X1768366D01*
G02Y451920I0J1512D01*
G37*
G36*
G01X1760767Y448896D02*
X1755767D01*
G02Y451920I0J1512D01*
G01X1760767D01*
G02X1762278Y450418I-1J-1512D01*
G01Y450323D01*
X1762269Y450239D01*
G02X1760767Y448896I-1502J169D01*
G37*
G36*
G01X1748169D02*
X1743169D01*
G02Y451920I0J1512D01*
G01X1748169D01*
G02X1749680Y450418I-1J-1512D01*
G01Y450323D01*
X1749671Y450239D01*
G02X1748169Y448896I-1502J169D01*
G37*
G36*
G01X1470989Y449026D02*
G03X1470411I-289J-277D01*
G02Y450968I-1011J971D01*
G03X1470989I289J277D01*
G02Y449026I1011J-971D01*
G37*
G36*
G01X1463189D02*
G03X1462611I-289J-277D01*
G02Y450968I-1011J971D01*
G03X1463189I289J277D01*
G02Y449026I1011J-971D01*
G37*
G36*
G01X1631268Y451086D02*
G03X1631263Y450513I277J-289D01*
G02X1629308Y450531I-987J-996D01*
G03X1629313Y451104I-277J289D01*
G02X1629282Y453064I987J996D01*
G03X1629260Y453635I-291J275D01*
G02X1629190Y455648I940J1040D01*
G03Y456202I-288J277D01*
G02X1631210I1010J973D01*
G03Y455648I288J-277D01*
G02X1631218Y453711I-1010J-973D01*
G03X1631240Y453140I291J-275D01*
G02X1631268Y451086I-940J-1040D01*
G37*
G36*
G01X1682201Y450789D02*
G03X1682187Y450234I281J-285D01*
G02X1680168Y450283I-1033J-948D01*
G03X1680182Y450838I-281J285D01*
G02X1682201Y450789I1033J948D01*
G37*
G36*
G01X1873831Y449539D02*
G03Y448961I277J-289D01*
G02X1871889I-971J-1011D01*
G03Y449539I-277J289D01*
G02X1873831I971J1011D01*
G37*
G36*
G01X1647500Y449140D02*
G03X1647513Y448585I294J-271D01*
G02X1645494Y448540I-988J-995D01*
G03X1645481Y449095I-294J271D01*
G02X1645452Y451055I988J995D01*
G03X1645448Y451610I-290J275D01*
G02X1647468Y451625I1003J980D01*
G03X1647472Y451070I290J-275D01*
G02X1647500Y449140I-1003J-980D01*
G37*
G36*
G01X1677288Y448795D02*
G03X1677284Y448229I281J-285D01*
G02X1675303Y448243I-998J-985D01*
G03X1675307Y448809I-281J285D01*
G02X1677288Y448795I998J985D01*
G37*
G36*
G01X1674076Y447548D02*
G03X1674075Y446993I288J-278D01*
G02X1672056Y446996I-1011J-971D01*
G03X1672057Y447551I-288J278D01*
G02X1674076Y447548I1011J971D01*
G37*
G36*
G01X-616Y454932D02*
G03X-328Y455438I-94J389D01*
G02X2535Y455410I1436J441D01*
G03X2794Y454904I380J-125D01*
G02X3435Y452446I-455J-1431D01*
G03Y451900I292J-273D01*
G02Y449846I-1096J-1027D01*
G03Y449300I292J-273D01*
G02Y447246I-1096J-1027D01*
G03Y446700I292J-273D01*
G02X1312Y444577I-1096J-1027D01*
G03X766I-273J-292D01*
G02X-1357Y446700I-1027J1096D01*
G03Y447246I-292J273D01*
G02Y449300I1096J1027D01*
G03Y449846I-292J273D01*
G02Y451900I1096J1027D01*
G03Y452446I-292J273D01*
G02X-616Y454932I1096J1027D01*
G37*
G36*
G01X6770Y447971D02*
G03X7316I273J292D01*
G02X9705Y447508I1027J-1096D01*
G03X10297Y447349I363J169D01*
G02X9857Y445552I803J-1149D01*
G03X9258Y445684I-355J-185D01*
G02X7316Y445779I-915J1191D01*
G03X6770I-273J-292D01*
G02X6712Y445728I-1020J1102D01*
G03Y445422I130J-153D01*
G02X4647Y445302I-969J-1147D01*
G03Y445848I-292J273D01*
G02X6770Y447971I1096J1027D01*
G37*
G36*
G01X1670826Y445480D02*
G03Y444926I288J-277D01*
G02X1668806I-1010J-973D01*
G03Y445480I-288J277D01*
G02Y447426I1010J973D01*
G03Y447980I-288J277D01*
G02X1670826I1010J973D01*
G03Y447426I288J-277D01*
G02Y445480I-1010J-973D01*
G37*
G36*
G01X1718140Y442709D02*
G03X1717978Y443287I-335J218D01*
G02X1717595Y443559I609J1263D01*
G03X1717029I-283J-282D01*
G02Y445541I-992J991D01*
G03X1717595I283J282D01*
G02X1719764Y443788I992J-991D01*
G03X1719926Y443210I335J-218D01*
G02X1718140Y442709I-609J-1263D01*
G37*
G36*
G01X10786Y443296D02*
X15787D01*
G02X17298Y441795I0J-1512D01*
G01Y441700D01*
X17288Y441616D01*
G02X15786Y440274I-1502J170D01*
G01X10786D01*
G02Y443296I0J1511D01*
G37*
G36*
G01X1413300Y442491D02*
G03X1413324Y441870I264J-301D01*
G02X1411559Y441802I-841J-1122D01*
G03X1411535Y442423I-264J301D01*
G02X1413300Y442491I841J1122D01*
G37*
G36*
G01X1589900Y441497D02*
G03X1590472Y441480I294J271D01*
G02X1590416Y439521I974J-1008D01*
G03X1589844Y439538I-294J-271D01*
G02X1589900Y441497I-974J1008D01*
G37*
G36*
G01X1613207Y441666D02*
G03X1613223Y441103I292J-273D01*
G02X1611232Y441045I-967J-1015D01*
G03X1611216Y441608I-292J273D01*
G02X1613207Y441666I967J1015D01*
G37*
G36*
G01X22936Y444354D02*
G02X25958Y444364I1511J0D01*
G01Y439354D01*
X25959D01*
X25958Y439269D01*
X25949Y439185D01*
G02X22936Y439354I-1502J169D01*
G01Y444354D01*
G37*
G36*
G01X750525Y439327D02*
G03X749900Y438975I-226J-330D01*
G02X747401Y439770I-1400J-75D01*
G03X747278Y440369I-314J248D01*
G02X748440Y442914I672J1231D01*
G03X748971Y443205I140J375D01*
G02X750525Y439327I3670J-780D01*
G37*
G36*
G01X1409123Y439924D02*
G03Y439309I257J-307D01*
G02X1407327I-898J-1076D01*
G03Y439924I-257J307D01*
G02X1409123I898J1076D01*
G37*
G36*
G01X1506427Y436187D02*
G03X1506443Y435632I296J-269D01*
G02X1504427Y435576I-981J-1002D01*
G03X1504411Y436131I-296J269D01*
G02X1506427Y436187I981J1002D01*
G37*
G36*
G01X1640510Y434727D02*
G03Y434173I288J-277D01*
G02X1638490I-1010J-973D01*
G03Y434727I-288J277D01*
G02X1640510I1010J973D01*
G37*
G36*
G01X1461099Y431902D02*
G03X1460510I-294J-271D01*
G02Y433800I-1032J949D01*
G03X1461099I295J271D01*
G02Y431902I1032J-949D01*
G37*
G36*
G01X1468386Y433869D02*
G03X1468958Y433852I294J271D01*
G02X1468900Y431892I973J-1010D01*
G03X1468328Y431909I-294J-271D01*
G02X1468386Y433869I-973J1010D01*
G37*
G36*
G01X1588351Y433445D02*
G03X1588973Y433428I318J243D01*
G02X1588924Y431663I1064J-913D01*
G03X1588302Y431680I-318J-243D01*
G02X1588351Y433445I-1064J913D01*
G37*
G36*
G01X1410812Y434785D02*
Y429690D01*
X1410802Y429606D01*
G02X1407788Y429775I-1502J169D01*
G01Y434776D01*
G02X1410812Y434785I1512J-1D01*
G37*
G36*
G01X1402910D02*
Y429690D01*
X1402900Y429606D01*
G02X1399886Y429775I-1502J169D01*
G01Y434776D01*
G02X1402910Y434785I1512J-1D01*
G37*
G36*
G01X1468885Y427046D02*
G03X1468305I-290J-276D01*
G02Y428980I-1015J967D01*
G03X1468885I290J276D01*
G02Y427046I1015J-967D01*
G37*
G36*
G01X1548776Y429391D02*
G03Y428844I292J-274D01*
G02X1546732I-1022J-960D01*
G03Y429391I-292J274D01*
G02X1548097Y431710I1022J960D01*
G03X1548579Y431986I98J388D01*
G02X1549582Y430235I1346J-392D01*
G03X1549100Y429959I-98J-388D01*
G02X1548776Y429391I-1346J392D01*
G37*
G36*
G01X1583820Y426607D02*
G03X1583311Y426307I-118J-382D01*
G02X1582352Y427934I-1372J287D01*
G03X1582861Y428234I118J382D01*
G02X1583820Y426607I1372J-287D01*
G37*
G36*
G01X17025Y423338D02*
X12024D01*
G02X12025Y426362I1J1512D01*
G01X17025D01*
G02X18536Y424860I-1J-1512D01*
G01Y424765D01*
X18527Y424681D01*
G02X17025Y423338I-1502J168D01*
G37*
G36*
G01X7025D02*
X2024D01*
G02X2025Y426362I1J1512D01*
G01X7025D01*
G02X8536Y424860I-1J-1512D01*
G01Y424765D01*
X8527Y424681D01*
G02X7025Y423338I-1502J168D01*
G37*
G36*
G01X62516Y424220D02*
X62507Y424136D01*
G02X59494Y424305I-1502J169D01*
G01Y429306D01*
G02X62516Y429315I1511J-1D01*
G01Y424220D01*
G37*
G36*
G01X1589368Y424272D02*
G03X1588961Y423864I-7J-400D01*
G02X1587587Y425237I-1402J-29D01*
G03X1587994Y425645I7J400D01*
G02X1589368Y424272I1402J29D01*
G37*
G36*
G01X1559675Y420042D02*
X1555775D01*
G02Y422866I0J1412D01*
G01X1559676D01*
G02X1561086Y421464I-1J-1412D01*
G01Y421370D01*
X1561076Y421286D01*
G02X1559675Y420042I-1401J167D01*
G37*
G36*
G01X1548790Y422624D02*
G03Y422084I295J-270D01*
G02X1546720I-1035J-946D01*
G03Y422624I-295J270D01*
G02X1548139Y424918I1035J946D01*
G03X1548629Y425181I109J385D01*
G02X1549580Y423405I1335J-428D01*
G03X1549090Y423142I-109J-385D01*
G02X1548790Y422624I-1335J427D01*
G37*
G36*
G01X1504996Y419784D02*
G03X1504478Y419514I-133J-377D01*
G02X1501738Y419711I-1350J378D01*
G03X1501304Y420058I-397J-51D01*
G02X1502565Y421635I-129J1396D01*
G03X1502999Y421288I397J51D01*
G02X1503591Y421215I128J-1396D01*
G03X1504109Y421485I133J377D01*
G02X1504508Y422137I1350J-378D01*
G03X1504541Y422692I-271J295D01*
G02X1506556Y422574I1064J912D01*
G03X1506523Y422019I271J-295D01*
G02X1504996Y419784I-1065J-912D01*
G37*
G36*
G01X50776Y424005D02*
Y418910D01*
X50767Y418826D01*
G02X47754Y418995I-1502J169D01*
G01Y423996D01*
G02X50776Y424005I1511J-1D01*
G37*
G36*
G01X1557725Y416662D02*
X1553824D01*
G02X1553825Y419486I1J1412D01*
G01X1554448D01*
G02X1554998Y418963I0J-551D01*
G03X1555016Y418813I777J17D01*
G02X1555159Y418507I-1189J-742D01*
G03X1556391I616J472D01*
G02X1556534Y418813I1332J-436D01*
G03X1556550Y419022I-759J163D01*
G02X1557050Y419486I500J-37D01*
G01X1557725D01*
G02X1559136Y418084I0J-1411D01*
G01Y417990D01*
X1559126Y417906D01*
G02X1557725Y416662I-1401J167D01*
G37*
G36*
G01X1413476Y416907D02*
X1413461Y417081D01*
X1413626Y421997D01*
X1413634Y422005D01*
X1413640Y422078D01*
G02X1416647Y422124I1506J-131D01*
G01X1416668Y421948D01*
X1416504Y417042D01*
X1416505D01*
X1416502Y416988D01*
X1416477Y416817D01*
G02X1413476Y416907I-1495J222D01*
G37*
G36*
G01X1405646Y421576D02*
G02X1408670Y421585I1512J-1D01*
G01Y416490D01*
X1408660Y416406D01*
G02X1405646Y416572I-1502J167D01*
G01Y421576D01*
G37*
G36*
G01X1567475Y413282D02*
X1563574D01*
G02X1563575Y416106I1J1412D01*
G01X1564198D01*
G02X1564748Y415583I0J-551D01*
G03X1564766Y415433I777J17D01*
G02X1564909Y415127I-1189J-742D01*
G03X1566141I616J472D01*
G02X1566284Y415433I1332J-436D01*
G03X1566300Y415642I-759J163D01*
G02X1566800Y416106I500J-37D01*
G01X1567475D01*
G02X1568886Y414704I0J-1411D01*
G01Y414610D01*
X1568876Y414526D01*
G02X1567475Y413282I-1401J167D01*
G37*
G36*
G01X767237Y416062D02*
G03X767281Y415483I296J-269D01*
G02X765357Y415340I-887J-1086D01*
G03X765313Y415919I-296J269D01*
G02X766261Y418406I887J1086D01*
G03X766678Y418800I17J399D01*
G02X768019Y417379I1402J-20D01*
G03X767602Y416985I-17J-399D01*
G02X767237Y416062I-1402J21D01*
G37*
G36*
G01X47006Y415201D02*
G03Y414590I258J-306D01*
G02X45194I-906J-1070D01*
G03Y415201I-258J305D01*
G02X47006I906J1070D01*
G37*
G36*
G01X1471147Y413091D02*
G03X1471720Y413069I297J268D01*
G02X1471647Y411116I968J-1014D01*
G03X1471074Y411138I-297J-268D01*
G02X1471147Y413091I-968J1014D01*
G37*
G36*
G01X1588551Y411003D02*
G03X1587996Y410990I-271J-295D01*
G02X1587949Y413008I-996J986D01*
G03X1588504Y413021I271J295D01*
G02X1588551Y411003I996J-986D01*
G37*
G36*
G01X120018Y413220D02*
G03X120037Y412643I286J-279D01*
G02X118098Y412581I-937J-1043D01*
G03X118079Y413158I-286J279D01*
G02X120018Y413220I937J1043D01*
G37*
G36*
G01X20473Y414391D02*
G03X21740Y414794I-2J2199D01*
G02X21756Y410156I1488J-2314D01*
G03X20502Y410569I-1283J-1786D01*
G01X20471D01*
G03X19204Y410166I2J-2199D01*
G02X19188Y414804I-1488J2314D01*
G03X20442Y414391I1283J1786D01*
G01X20473D01*
G37*
G36*
G01X3938D02*
G03X5205Y414794I-2J2199D01*
G02X5221Y410156I1488J-2314D01*
G03X3967Y410569I-1283J-1786D01*
G01X3936D01*
G03X2669Y410166I2J-2199D01*
G02X2653Y414804I-1488J2314D01*
G03X3907Y414391I1283J1786D01*
G01X3938D01*
G37*
G36*
G01X-12598D02*
G03X-11331Y414794I-2J2199D01*
G02X-11315Y410156I1488J-2314D01*
G03X-12569Y410569I-1283J-1786D01*
G01X-12599D01*
G03X-13866Y410166I2J-2199D01*
G02X-13882Y414804I-1488J2314D01*
G03X-12628Y414391I1283J1786D01*
G01X-12598D01*
G37*
G36*
G01X749612Y408828D02*
G03X749058I-277J-288D01*
G02X747075Y410811I-973J1010D01*
G03Y411365I-288J277D01*
G02X749058Y413348I1010J973D01*
G03X749612I277J288D01*
G02X751558I973J-1010D01*
G03X752112I277J288D01*
G02X753991Y413408I973J-1010D01*
G03X754524Y413422I259J305D01*
G02X755905Y413741I963J-1019D01*
G03X756424Y414133I119J382D01*
G02X758799Y415177I1402J34D01*
G03X759353I277J288D01*
G02X761303Y415172I972J-1010D01*
G03X761912Y415233I279J287D01*
G02X763960Y413358I1157J-793D01*
G03X763942Y412756I254J-309D01*
G02X761975Y410760I-953J-1028D01*
G03X761384Y410747I-290J-276D01*
G02X759353Y410657I-1058J920D01*
G03X758799I-277J-288D01*
G02X757408Y410329I-972J1010D01*
G03X756889Y409937I-119J-382D01*
G02X754581Y408833I-1402J-34D01*
G03X754048Y408819I-259J-305D01*
G02X752112Y408828I-963J1019D01*
G03X751558I-277J-288D01*
G02X749612I-973J1010D01*
G37*
G36*
G01X1403912Y408281D02*
Y413282D01*
G02X1406934Y413291I1511J-1D01*
G01Y408281D01*
X1406935D01*
X1406934Y408196D01*
X1406925Y408112D01*
G02X1403912Y408281I-1502J169D01*
G37*
G36*
G01X1571375Y406522D02*
X1567474D01*
G02X1567475Y409346I1J1412D01*
G01X1568098D01*
G02X1568648Y408823I0J-551D01*
G03X1568666Y408673I777J17D01*
G02X1568809Y408367I-1189J-742D01*
G03X1570041I616J472D01*
G02X1570184Y408673I1332J-436D01*
G03X1570200Y408882I-759J163D01*
G02X1570700Y409346I500J-37D01*
G01X1571375D01*
G02X1572786Y407944I0J-1411D01*
G01Y407850D01*
X1572776Y407766D01*
G02X1571375Y406522I-1401J167D01*
G37*
G36*
G01X1444049Y407876D02*
G03X1443955Y407308I227J-329D01*
G02X1442033Y407625I-1125J-836D01*
G03X1442127Y408193I-227J329D01*
G02X1444049Y407876I1125J836D01*
G37*
G36*
G01X120709Y404984D02*
G03X120136Y405156I-363J-168D01*
G02X120670Y406937I-738J1192D01*
G03X121243Y406765I363J168D01*
G02X120709Y404984I738J-1192D01*
G37*
G36*
G01X53088Y406598D02*
X55227Y409137D01*
G02X57894Y408173I1156J-974D01*
G01Y408078D01*
X57885Y407994D01*
G02X57539Y407189I-1503J169D01*
G01X56228Y405632D01*
X56227D01*
X55422Y404678D01*
X55421Y404676D01*
G02X53088Y406598I-1177J948D01*
G37*
G36*
G01X1589833Y402984D02*
G03X1589253Y402806I-214J-338D01*
G02X1588716Y404554I-1285J562D01*
G03X1589296Y404732I214J338D01*
G02X1589833Y402984I1285J-562D01*
G37*
G36*
G01X25591Y406517D02*
G03X26858Y406920I-2J2199D01*
G02X26874Y402282I1488J-2314D01*
G03X25620Y402695I-1283J-1786D01*
G01X25590D01*
G03X24323Y402292I2J-2199D01*
G02X24307Y406930I-1488J2314D01*
G03X25561Y406517I1283J1786D01*
G01X25591D01*
G37*
G36*
G01X9056D02*
G03X10323Y406920I-2J2199D01*
G02X10339Y402282I1488J-2314D01*
G03X9085Y402695I-1283J-1786D01*
G01X9054D01*
G03X7787Y402292I2J-2199D01*
G02X7771Y406930I-1488J2314D01*
G03X9025Y406517I1283J1786D01*
G01X9056D01*
G37*
G36*
G01X-7480D02*
G03X-6213Y406920I-2J2199D01*
G02X-6197Y402282I1488J-2314D01*
G03X-7451Y402695I-1283J-1786D01*
G01X-7481D01*
G03X-8748Y402292I2J-2199D01*
G02X-8764Y406930I-1488J2314D01*
G03X-7510Y406517I1283J1786D01*
G01X-7480D01*
G37*
G36*
G01X66896Y403268D02*
Y403173D01*
X66886Y403089D01*
G02X64311Y402193I-1502J169D01*
G01X61973Y404550D01*
X61972Y404551D01*
G02X64097Y406701I1052J1085D01*
G01X65153Y405638D01*
X66457Y404323D01*
G02X66896Y403268I-1073J-1065D01*
G37*
G36*
G01X1383327Y397890D02*
G03X1382773I-277J-288D01*
G02X1380751Y399830I-973J1010D01*
G03X1380740Y400372I-299J265D01*
G02X1380658Y400466I1015J968D01*
G03X1380346I-156J-125D01*
G02X1378023Y400669I-1094J877D01*
G03X1377479Y400826I-350J-193D01*
G02X1375827Y401043I-679J1227D01*
G03X1375273I-277J-288D01*
G02Y403063I-973J1010D01*
G03X1375827I277J288D01*
G02X1378029Y402727I973J-1010D01*
G03X1378573Y402570I350J193D01*
G02X1380225Y402353I679J-1227D01*
G03X1380779I277J288D01*
G02X1382725I973J-1010D01*
G03X1383279I277J288D01*
G02X1385225I973J-1010D01*
G03X1385779I277J288D01*
G02X1387801Y400413I973J-1010D01*
G03X1387812Y399871I299J-265D01*
G02X1385827Y397890I-1012J-971D01*
G03X1385273I-277J-288D01*
G02X1383327I-973J1010D01*
G37*
G36*
G01X1586703Y396411D02*
G03X1586141Y396408I-279J-286D01*
G02X1586130Y398403I-991J992D01*
G03X1586692Y398406I279J286D01*
G02X1586703Y396411I991J-992D01*
G37*
G36*
G01X102066Y400958D02*
G03X102634I284J282D01*
G02X104766I1066J-1058D01*
G03X105334I284J282D01*
G02X107466I1066J-1058D01*
G03X108034I284J282D01*
G02X110499Y400446I1066J-1058D01*
G03X111017Y400219I373J146D01*
G02X111112Y397386I544J-1400D01*
G03X110594Y397045I-120J-382D01*
G02X108034Y396142I-1494J155D01*
G03X107466I-284J-282D01*
G02X105334I-1066J1058D01*
G03X104766I-284J-282D01*
G02X102634I-1066J1058D01*
G03X102066I-284J-282D01*
G02X99942Y398266I-1066J1058D01*
G03Y398834I-282J284D01*
G02X102066Y400958I1058J1066D01*
G37*
G36*
G01X1370996Y395697D02*
G03X1370418I-289J-277D01*
G02Y397639I-1011J971D01*
G03X1370996I289J277D01*
G02Y395697I1011J-971D01*
G37*
G36*
G01X1655811Y398206D02*
G03X1655831Y397649I297J-268D01*
G02X1653820Y397576I-970J-1012D01*
G03X1653800Y398133I-297J268D01*
G02X1653776Y400133I970J1012D01*
G03X1653784Y400688I-284J282D01*
G02X1655803Y400657I1024J957D01*
G03X1655795Y400102I284J-282D01*
G02X1655811Y398206I-1025J-957D01*
G37*
G36*
G01X3938Y398643D02*
G03X5205Y399046I-2J2199D01*
G02X5221Y394408I1488J-2314D01*
G03X3967Y394821I-1283J-1786D01*
G01X3936D01*
G03X2669Y394418I2J-2199D01*
G02X2653Y399056I-1488J2314D01*
G03X3907Y398643I1283J1786D01*
G01X3938D01*
G37*
G36*
G01X-12598D02*
G03X-11331Y399046I-2J2199D01*
G02X-11315Y394408I1488J-2314D01*
G03X-12569Y394821I-1283J-1786D01*
G01X-12599D01*
G03X-13866Y394418I2J-2199D01*
G02X-13882Y399056I-1488J2314D01*
G03X-12628Y398643I1283J1786D01*
G01X-12598D01*
G37*
G36*
G01X66236Y391560D02*
X66227Y391476D01*
G02X63214Y391645I-1502J169D01*
G01Y396645D01*
G02X66236Y396655I1511J0D01*
G01Y391560D01*
G37*
G36*
G01X1662125Y389274D02*
G03X1662056Y388723I251J-311D01*
G02X1660052Y388973I-1122J-840D01*
G03X1660121Y389524I-251J311D01*
G02X1660264Y391367I1122J840D01*
G03Y391940I-280J286D01*
G02X1662222I979J1003D01*
G03Y391367I280J-286D01*
G02X1662125Y389274I-979J-1003D01*
G37*
G36*
G01X25591Y390769D02*
G03X26858Y391172I-2J2199D01*
G02X26874Y386534I1488J-2314D01*
G03X25620Y386947I-1283J-1786D01*
G01X25590D01*
G03X24323Y386544I2J-2199D01*
G02X24307Y391182I-1488J2314D01*
G03X25561Y390769I1283J1786D01*
G01X25591D01*
G37*
G36*
G01X175673Y385123D02*
G03Y384493I246J-315D01*
G02X173827I-923J-1185D01*
G03Y385123I-246J315D01*
G02Y387493I923J1185D01*
G03Y388123I-246J315D01*
G02X175673I923J1185D01*
G03Y387493I246J-315D01*
G02Y385123I-923J-1185D01*
G37*
G36*
G01X822033Y382027D02*
G03X821403I-315J-246D01*
G02X819295Y384135I-1185J923D01*
G03Y384765I-246J315D01*
G02X821403Y386873I923J1185D01*
G03X822033I315J246D01*
G02X824364Y386921I1185J-923D01*
G03X824969Y386915I305J259D01*
G02X827152Y384854I1128J-992D01*
G03X827177Y384262I281J-285D01*
G02X825081Y382125I-961J-1154D01*
G03X824450Y382091I-302J-262D01*
G02X822033Y382027I-1232J859D01*
G37*
G36*
G01X1465365Y384296D02*
G03X1465373Y383729I286J-280D01*
G02X1463396Y383699I-973J-1009D01*
G03X1463388Y384266I-286J280D01*
G02X1465365Y384296I973J1009D01*
G37*
G36*
G01X172081Y384583D02*
G03Y383953I246J-315D01*
G02X170235I-923J-1185D01*
G03Y384583I-246J315D01*
G02Y386953I923J1185D01*
G03Y387583I-246J315D01*
G02X172081I923J1185D01*
G03Y386953I246J-315D01*
G02Y384583I-923J-1185D01*
G37*
G36*
G01X1571657Y384060D02*
G03X1571944Y383585I390J-89D01*
G02X1570217Y382538I-359J-1355D01*
G03X1569930Y383013I-390J89D01*
G02X1571657Y384060I359J1355D01*
G37*
G36*
G01X3938Y382895D02*
G03X5205Y383298I-2J2199D01*
G02X5221Y378660I1488J-2314D01*
G03X3967Y379073I-1283J-1786D01*
G01X3936D01*
G03X2669Y378670I2J-2199D01*
G02X2653Y383308I-1488J2314D01*
G03X3907Y382895I1283J1786D01*
G01X3938D01*
G37*
G36*
G01X-12598D02*
G03X-11331Y383298I-2J2199D01*
G02X-11315Y378660I1488J-2314D01*
G03X-12569Y379073I-1283J-1786D01*
G01X-12599D01*
G03X-13866Y378670I2J-2199D01*
G02X-13882Y383308I-1488J2314D01*
G03X-12628Y382895I1283J1786D01*
G01X-12598D01*
G37*
G36*
G01X1665868Y378253D02*
G03X1665885Y377698I296J-269D01*
G02X1663866Y377636I-980J-1003D01*
G03X1663849Y378191I-296J269D01*
G02X1665868Y378253I980J1003D01*
G37*
G36*
G01X852304Y377641D02*
G03Y377095I292J-273D01*
G02X852361Y375106I-1096J-1027D01*
G03X852470Y374502I307J-256D01*
G02X850602Y372202I-743J-1305D01*
G03X850014Y372215I-300J-265D01*
G02X847807Y374252I-1082J1042D01*
G03X847739Y374843I-300J265D01*
G02X847581Y374972I869J1225D01*
G03X847035I-273J-292D01*
G02X844912Y377095I-1027J1096D01*
G03Y377641I-292J273D01*
G02X847035Y379764I1096J1027D01*
G03X847581I273J292D01*
G02X849635I1027J-1096D01*
G03X850181I273J292D01*
G02X852304Y377641I1027J-1096D01*
G37*
G36*
G01X778810Y371129D02*
G03X778193Y371122I-306J-258D01*
G02X778172Y372904I-1093J878D01*
G03X778789Y372911I306J258D01*
G02X778810Y371129I1093J-878D01*
G37*
G36*
G01X25591Y375021D02*
G03X26858Y375424I-2J2199D01*
G02X26874Y370786I1488J-2314D01*
G03X25620Y371199I-1283J-1786D01*
G01X25590D01*
G03X24323Y370796I2J-2199D01*
G02X24307Y375434I-1488J2314D01*
G03X25561Y375021I1283J1786D01*
G01X25591D01*
G37*
G36*
G01X9056D02*
G03X10323Y375424I-2J2199D01*
G02X10339Y370786I1488J-2314D01*
G03X9085Y371199I-1283J-1786D01*
G01X9054D01*
G03X7787Y370796I2J-2199D01*
G02X7771Y375434I-1488J2314D01*
G03X9025Y375021I1283J1786D01*
G01X9056D01*
G37*
G36*
G01X197824Y376256D02*
G03X198316Y376525I109J385D01*
G02X200871Y375085I1438J-436D01*
G03X200901Y374520I297J-268D01*
G02X200823Y372215I-1001J-1120D01*
G03Y371585I246J-315D01*
G02X198977I-923J-1185D01*
G03Y372215I-246J315D01*
G02X198429Y373097I923J1185D01*
G03X197906Y373394I-392J-81D01*
G02X197824Y376256I-495J1418D01*
G37*
G36*
G01X102761Y370050D02*
G03X102792Y369428I266J-298D01*
G02X101032Y369342I-827J-1132D01*
G03X101001Y369964I-266J298D01*
G02X102761Y370050I827J1132D01*
G37*
G36*
G01X1598821Y368943D02*
G03X1598810Y368350I263J-301D01*
G02X1596929Y368386I-960J-1021D01*
G03X1596940Y368979I-263J301D01*
G02X1598821Y368943I960J1021D01*
G37*
G36*
G01X835863Y367760D02*
G03X836181Y367756I161J119D01*
G02X836282Y365787I1182J-926D01*
G03X835713Y365794I-288J-278D01*
G02X833631Y365767I-1055J1069D01*
G03X833085I-273J-292D01*
G02X831031I-1027J1096D01*
G03X830485I-273J-292D01*
G02X828431I-1027J1096D01*
G03X827885I-273J-292D01*
G02X825831I-1027J1096D01*
G03X825285I-273J-292D01*
G02X823231I-1027J1096D01*
G03X822685I-273J-292D01*
G02X820562Y367890I-1027J1096D01*
G03Y368436I-292J273D01*
G02X822685Y370559I1096J1027D01*
G03X823231I273J292D01*
G02X825285I1027J-1096D01*
G03X825831I273J292D01*
G02X827885I1027J-1096D01*
G03X828431I273J292D01*
G02X830485I1027J-1096D01*
G03X831031I273J292D01*
G02X833085I1027J-1096D01*
G03X833631I273J292D01*
G02X835754Y368436I1027J-1096D01*
G03Y367890I292J-273D01*
G02X835863Y367760I-1095J-1029D01*
G37*
G36*
G01X175215Y365864D02*
G03X174585I-315J-246D01*
G02X172477Y367972I-1185J923D01*
G03Y368602I-246J315D01*
G02X174585Y370710I923J1185D01*
G03X175215I315J246D01*
G02X177585I1185J-923D01*
G03X178215I315J246D01*
G02X180585I1185J-923D01*
G03X181215I315J246D01*
G02X183585I1185J-923D01*
G03X184215I315J246D01*
G02X186585I1185J-923D01*
G03X187215I315J246D01*
G02X189323Y368602I1185J-923D01*
G03Y367972I246J-315D01*
G02X187215Y365864I-923J-1185D01*
G03X186585I-315J-246D01*
G02X184215I-1185J923D01*
G03X183585I-315J-246D01*
G02X181215I-1185J923D01*
G03X180585I-315J-246D01*
G02X178215I-1185J923D01*
G03X177585I-315J-246D01*
G02X175215I-1185J923D01*
G37*
G36*
G01X746646Y362913D02*
G03X746100I-273J-292D01*
G02X744063Y365121I-1027J1096D01*
G03X744042Y365730I-269J296D01*
G02X746000Y368005I932J1178D01*
G03X746546I273J292D01*
G02X748600I1027J-1096D01*
G03X749146I273J292D01*
G02X751183Y365797I1027J-1096D01*
G03X751204Y365188I269J-296D01*
G02X749246Y362913I-932J-1178D01*
G03X748700I-273J-292D01*
G02X746646I-1027J1096D01*
G37*
G36*
G01X20473Y367147D02*
G03X21740Y367550I-2J2199D01*
G02X21756Y362912I1488J-2314D01*
G03X20502Y363325I-1283J-1786D01*
G01X20471D01*
G03X19204Y362922I2J-2199D01*
G02X19188Y367560I-1488J2314D01*
G03X20442Y367147I1283J1786D01*
G01X20473D01*
G37*
G36*
G01X3938D02*
G03X5205Y367550I-2J2199D01*
G02X5221Y362912I1488J-2314D01*
G03X3967Y363325I-1283J-1786D01*
G01X3936D01*
G03X2669Y362922I2J-2199D01*
G02X2653Y367560I-1488J2314D01*
G03X3907Y367147I1283J1786D01*
G01X3938D01*
G37*
G36*
G01X-12598D02*
G03X-11331Y367550I-2J2199D01*
G02X-11315Y362912I1488J-2314D01*
G03X-12569Y363325I-1283J-1786D01*
G01X-12599D01*
G03X-13866Y362922I2J-2199D01*
G02X-13882Y367560I-1488J2314D01*
G03X-12628Y367147I1283J1786D01*
G01X-12598D01*
G37*
G36*
G01X175286Y362358D02*
G03X174656I-315J-246D01*
G02Y364204I-1185J923D01*
G03X175286I315J246D01*
G02X177656I1185J-923D01*
G03X178286I315J246D01*
G02X180656I1185J-923D01*
G03X181286I315J246D01*
G02X183656I1185J-923D01*
G03X184286I315J246D01*
G02X186656I1185J-923D01*
G03X187286I315J246D01*
G02Y362358I1185J-923D01*
G03X186656I-315J-246D01*
G02X184286I-1185J923D01*
G03X183656I-315J-246D01*
G02X181286I-1185J923D01*
G03X180656I-315J-246D01*
G02X178286I-1185J923D01*
G03X177656I-315J-246D01*
G02X175286I-1185J923D01*
G37*
G36*
G01X410478Y364173D02*
G03X410500Y364728I-277J289D01*
G02X410576Y366671I1047J932D01*
G03Y367249I-277J289D01*
G02X412518I971J1011D01*
G03Y366671I277J-289D01*
G02X412516Y364647I-971J-1011D01*
G03X412494Y364092I277J-289D01*
G02X410478Y364173I-1047J-932D01*
G37*
G36*
G01X1544310Y362427D02*
G03Y361873I288J-277D01*
G02X1542290I-1010J-973D01*
G03Y362427I-288J277D01*
G02X1544310I1010J973D01*
G37*
G36*
G01X1653798Y365610D02*
Y360515D01*
X1653788Y360430D01*
G02X1650574Y360600I-1603J170D01*
G01Y365601D01*
G02X1653798Y365610I1612J-1D01*
G37*
G36*
G01X1641878Y365510D02*
Y360415D01*
X1641868Y360330D01*
G02X1638654Y360500I-1603J170D01*
G01Y365501D01*
G02X1641878Y365510I1612J-1D01*
G37*
G36*
G01X1534756Y361839D02*
G03X1534771Y361284I295J-270D01*
G02X1532753Y361227I-982J-1001D01*
G03X1532738Y361782I-295J270D01*
G02X1534756Y361839I982J1001D01*
G37*
G36*
G01X823923Y358895D02*
G03X823292Y358882I-310J-252D01*
G02X821166Y360967I-1202J900D01*
G03Y361597I-246J315D01*
G02X823274Y363705I923J1185D01*
G03X823904I315J246D01*
G02X826274I1185J-923D01*
G03X826904I315J246D01*
G02X829274I1185J-923D01*
G03X829904I315J246D01*
G02X832274I1185J-923D01*
G03X832904I315J246D01*
G02X835042Y361621I1185J-923D01*
G03Y361002I253J-310D01*
G02X832904Y358918I-953J-1161D01*
G03X832274I-315J-246D01*
G02X829904I-1185J923D01*
G03X829274I-315J-246D01*
G02X826904I-1185J923D01*
G03X826274I-315J-246D01*
G02X823923Y358895I-1185J923D01*
G37*
G36*
G01X175239Y358698D02*
G03X174609I-315J-246D01*
G02Y360544I-1185J923D01*
G03X175239I315J246D01*
G02X177609I1185J-923D01*
G03X178239I315J246D01*
G02X180609I1185J-923D01*
G03X181239I315J246D01*
G02X183609I1185J-923D01*
G03X184239I315J246D01*
G02X186609I1185J-923D01*
G03X187239I315J246D01*
G02Y358698I1185J-923D01*
G03X186609I-315J-246D01*
G02X184239I-1185J923D01*
G03X183609I-315J-246D01*
G02X181239I-1185J923D01*
G03X180609I-315J-246D01*
G02X178239I-1185J923D01*
G03X177609I-315J-246D01*
G02X175239I-1185J923D01*
G37*
G36*
G01X49402Y358381D02*
G03X48839Y358449I-315J-246D01*
G02X49078Y360409I-869J1101D01*
G03X49641Y360341I315J246D01*
G02X49402Y358381I869J-1101D01*
G37*
G36*
G01X1479586Y360661D02*
G03X1479585Y360087I278J-287D01*
G02X1477633Y360091I-978J-1005D01*
G03X1477634Y360665I-278J287D01*
G02X1479586Y360661I978J1005D01*
G37*
G36*
G01X1588089Y357429D02*
G03X1587511I-289J-277D01*
G02Y359371I-1011J971D01*
G03X1588089I289J277D01*
G02Y357429I1011J-971D01*
G37*
G36*
G01X1489450Y359356D02*
G03Y358778I277J-289D01*
G02X1487508I-971J-1011D01*
G03Y359356I-277J289D01*
G02Y361378I971J1011D01*
G03Y361956I-277J289D01*
G02X1489450I971J1011D01*
G03Y361378I277J-289D01*
G02Y359356I-971J-1011D01*
G37*
G36*
G01X1484671Y358502D02*
G03X1484699Y357881I266J-299D01*
G02X1482936Y357801I-832J-1128D01*
G03X1482908Y358422I-266J299D01*
G02X1484671Y358502I832J1128D01*
G37*
G36*
G01X25591Y359273D02*
G03X26858Y359676I-2J2199D01*
G02X26874Y355038I1488J-2314D01*
G03X25620Y355451I-1283J-1786D01*
G01X25590D01*
G03X24323Y355048I2J-2199D01*
G02X24307Y359686I-1488J2314D01*
G03X25561Y359273I1283J1786D01*
G01X25591D01*
G37*
G36*
G01X9056D02*
G03X10323Y359676I-2J2199D01*
G02X10339Y355038I1488J-2314D01*
G03X9085Y355451I-1283J-1786D01*
G01X9054D01*
G03X7787Y355048I2J-2199D01*
G02X7771Y359686I-1488J2314D01*
G03X9025Y359273I1283J1786D01*
G01X9056D01*
G37*
G36*
G01X-7480D02*
G03X-6213Y359676I-2J2199D01*
G02X-6197Y355038I1488J-2314D01*
G03X-7451Y355451I-1283J-1786D01*
G01X-7481D01*
G03X-8748Y355048I2J-2199D01*
G02X-8764Y359686I-1488J2314D01*
G03X-7510Y359273I1283J1786D01*
G01X-7480D01*
G37*
G36*
G01X1631382Y356595D02*
G03X1631410Y355995I278J-288D01*
G02X1629560Y355908I-876J-1095D01*
G03X1629532Y356508I-278J288D01*
G02X1629425Y358603I876J1095D01*
G03X1629440Y359158I-280J285D01*
G02X1629414Y361018I1036J945D01*
G03X1629383Y361573I-303J261D01*
G02X1629291Y363533I954J1027D01*
G03X1629269Y364088I-299J266D01*
G02X1629267Y366108I971J1011D01*
G03X1629258Y366692I-278J288D01*
G02X1631173Y366721I942J1038D01*
G03X1631182Y366137I278J-288D01*
G02X1631286Y364166I-942J-1038D01*
G03X1631308Y363611I299J-266D01*
G02X1631399Y361685I-971J-1011D01*
G03X1631430Y361130I303J-261D01*
G02X1631459Y359103I-954J-1027D01*
G03X1631444Y358548I280J-285D01*
G02X1631382Y356595I-1036J-945D01*
G37*
G36*
G01X696625Y356247D02*
G03X696613Y355657I264J-300D01*
G02X694719Y355697I-969J-1013D01*
G03X694731Y356287I-264J300D01*
G02X696625Y356247I969J1013D01*
G37*
G36*
G01X1521289Y356063D02*
G03X1521315Y355466I279J-287D01*
G02X1519453Y355385I-885J-1087D01*
G03X1519427Y355982I-279J287D01*
G02X1521289Y356063I885J1087D01*
G37*
G36*
G01X1525756Y355744D02*
G03Y355190I288J-277D01*
G02X1523736I-1010J-973D01*
G03Y355744I-288J277D01*
G02Y357690I1010J973D01*
G03Y358244I-288J277D01*
G02X1525756I1010J973D01*
G03Y357690I288J-277D01*
G02Y355744I-1010J-973D01*
G37*
G36*
G01X1499217Y353894D02*
G03Y353316I277J-289D01*
G02X1497275I-971J-1011D01*
G03Y353894I-277J289D01*
G02Y355916I971J1011D01*
G03Y356494I-277J289D01*
G02X1497261Y358503I971J1011D01*
G03X1497275Y359058I-281J285D01*
G02X1497356Y361034I1034J947D01*
G03X1497342Y361633I-272J293D01*
G02X1497293Y363734I904J1072D01*
G03X1497279Y364333I-272J293D01*
G02X1499136Y364376I904J1072D01*
G03X1499150Y363777I272J-293D01*
G02X1499199Y361676I-904J-1072D01*
G03X1499213Y361077I272J-293D01*
G02X1499294Y359007I-904J-1072D01*
G03X1499280Y358452I281J-285D01*
G02X1499217Y356494I-1034J-947D01*
G03Y355916I277J-289D01*
G02Y353894I-971J-1011D01*
G37*
G36*
G01X1653157Y353689D02*
G03Y353111I277J-289D01*
G02X1651215I-971J-1011D01*
G03Y353689I-277J289D01*
G02X1653157I971J1011D01*
G37*
G36*
G01X767955Y352504D02*
G03X768121Y351953I349J-195D01*
G02X766254Y351393I-644J-1245D01*
G03X766088Y351944I-349J195D01*
G02X767955Y352504I644J1245D01*
G37*
G36*
G01X1539449Y352283D02*
G03Y351705I277J-289D01*
G02X1537507I-971J-1011D01*
G03Y352283I-277J289D01*
G02Y354305I971J1011D01*
G03Y354883I-277J289D01*
G02X1539449I971J1011D01*
G03Y354305I277J-289D01*
G02Y352283I-971J-1011D01*
G37*
G36*
G01X1416430Y352151D02*
G03X1416419Y351563I266J-299D01*
G02X1414520Y351599I-969J-1013D01*
G03X1414531Y352187I-266J299D01*
G02X1416430Y352151I969J1013D01*
G37*
G36*
G01X1447394Y350654D02*
G03X1446911Y350277I-83J-391D01*
G02X1445801Y351698I-1401J50D01*
G03X1446284Y352075I83J391D01*
G02X1447394Y350654I1401J-50D01*
G37*
G36*
G01X1490844Y351587D02*
G03X1490827Y351004I265J-299D01*
G02X1488909Y351061I-989J-993D01*
G03X1488926Y351644I-265J299D01*
G02X1490844Y351587I989J993D01*
G37*
G36*
G01X1544538Y351473D02*
G03Y350919I288J-277D01*
G02X1542518I-1010J-973D01*
G03Y351473I-288J277D01*
G02X1544538I1010J973D01*
G37*
G36*
G01X1331153Y351026D02*
G03X1331708Y350981I301J264D01*
G02X1331547Y348974I892J-1082D01*
G03X1330992Y349019I-301J-264D01*
G02X1331153Y351026I-892J1082D01*
G37*
G36*
G01X115528Y351963D02*
G03X115764Y352490I-135J377D01*
G02X117535Y351696I1299J526D01*
G03X117299Y351169I135J-377D01*
G02X117398Y350750I-1299J-528D01*
G03X117844Y350383I399J30D01*
G02X116610Y348884I164J-1392D01*
G03X116164Y349251I-399J-30D01*
G02X115528Y351963I-163J1392D01*
G37*
G36*
G01X746392Y343816D02*
G03X745804I-294J-270D01*
G02X743775Y346018I-1105J1018D01*
G03Y346648I-246J315D01*
G02X745804Y348850I924J1184D01*
G03X746392I294J270D01*
G02X748604I1106J-1017D01*
G03X749192I294J270D01*
G02X751221Y346648I1105J-1018D01*
G03Y346018I246J-315D01*
G02X749192Y343816I-924J-1184D01*
G03X748604I-294J-270D01*
G02X746392I-1106J1017D01*
G37*
G36*
G01X189515Y344231D02*
G03X190146Y344210I324J235D01*
G02X190085Y342365I1154J-962D01*
G03X189454Y342386I-324J-235D01*
G02X187115Y342425I-1154J962D01*
G03X186485I-315J-246D01*
G02X184085Y342465I-1185J923D01*
G03X183454Y342486I-324J-235D01*
G02X181115Y342525I-1154J962D01*
G03X180485I-315J-246D01*
G02X178115I-1185J923D01*
G03X177485I-315J-246D01*
G02X175115I-1185J923D01*
G03X174485I-315J-246D01*
G02Y344371I-1185J923D01*
G03X175115I315J246D01*
G02X177485I1185J-923D01*
G03X178115I315J246D01*
G02X180485I1185J-923D01*
G03X181115I315J246D01*
G02X183515Y344331I1185J-923D01*
G03X184146Y344310I324J235D01*
G02X186485Y344271I1154J-962D01*
G03X187115I315J246D01*
G02X189515Y344231I1185J-923D01*
G37*
G36*
G01X1643534Y343999D02*
G03X1643594Y343437I312J-251D01*
G02X1641621Y343227I-882J-1090D01*
G03X1641561Y343789I-312J251D01*
G02X1643534Y343999I882J1090D01*
G37*
G36*
G01X1556480Y340194D02*
G03X1555870I-305J-259D01*
G02Y342006I-1070J906D01*
G03X1556480I305J259D01*
G02Y340194I1070J-906D01*
G37*
G36*
G01X778862Y339127D02*
G03X778252I-305J-259D01*
G02Y340939I-1070J906D01*
G03X778862I305J259D01*
G02Y339127I1070J-906D01*
G37*
G36*
G01X700168Y337953D02*
G03X699613Y337931I-266J-299D01*
G02X699532Y339947I-1013J969D01*
G03X700087Y339969I266J299D01*
G02X700168Y337953I1013J-969D01*
G37*
G36*
G01X1582841Y337739D02*
G03X1582273Y337715I-272J-293D01*
G02X1579704Y339598I-1183J1080D01*
G03X1579581Y340130I-346J200D01*
G02X1581408Y342230I785J1162D01*
G03X1581962Y342189I298J267D01*
G02X1584152Y340570I897J-1077D01*
G03X1584360Y340050I369J-154D01*
G02X1582841Y337739I-566J-1283D01*
G37*
G36*
G01X1070007Y337750D02*
G03X1069377I-315J-246D01*
G02Y339596I-1185J923D01*
G03X1070007I315J246D01*
G02Y337750I1185J-923D01*
G37*
G36*
G01X1062807D02*
G03X1062177I-315J-246D01*
G02Y339596I-1185J923D01*
G03X1062807I315J246D01*
G02Y337750I1185J-923D01*
G37*
G36*
G01X824297Y336104D02*
G03X823667I-315J-246D01*
G02X821465Y338133I-1184J924D01*
G03Y338721I-270J294D01*
G02X821559Y341012I1017J1106D01*
G03Y341642I-246J315D01*
G02X823667Y343750I923J1185D01*
G03X824297I315J246D01*
G02X826667I1185J-923D01*
G03X827297I315J246D01*
G02X829667I1185J-923D01*
G03X830297I315J246D01*
G02X832667I1185J-923D01*
G03X833297I315J246D01*
G02X835610Y343818I1185J-923D01*
G03X836220Y343829I300J264D01*
G02X838474Y343909I1162J-952D01*
G03X839079Y343937I290J275D01*
G02X841293Y341919I1183J-926D01*
G03X841298Y341334I275J-290D01*
G02X841337Y339158I-1016J-1107D01*
G03X841358Y338569I281J-285D01*
G02X839303Y336382I-977J-1141D01*
G03X838672Y336308I-287J-278D01*
G02X836254Y336086I-1290J769D01*
G03X835644Y336075I-300J-264D01*
G02X833297Y336104I-1162J952D01*
G03X832667I-315J-246D01*
G02X830297I-1185J923D01*
G03X829667I-315J-246D01*
G02X827297I-1185J923D01*
G03X826667I-315J-246D01*
G02X824297I-1185J923D01*
G37*
G36*
G01X1620907Y337663D02*
G03Y337109I288J-277D01*
G02X1618887I-1010J-973D01*
G03Y337663I-288J277D01*
G02Y339609I1010J973D01*
G03Y340163I-288J277D01*
G02X1620907I1010J973D01*
G03Y339609I288J-277D01*
G02Y337663I-1010J-973D01*
G37*
G36*
G01X746392Y334499D02*
G03X745804I-294J-270D01*
G02X743681Y336622I-1106J1017D01*
G03Y337210I-270J294D01*
G02X745804Y339333I1017J1106D01*
G03X746392I294J270D01*
G02X748604I1106J-1017D01*
G03X749192I294J270D01*
G02X751315Y337210I1106J-1017D01*
G03Y336622I270J-294D01*
G02X749192Y334499I-1017J-1106D01*
G03X748604I-294J-270D01*
G02X746392I-1106J1017D01*
G37*
G36*
G01X852890Y334482D02*
G03X852260I-315J-246D01*
G02X850078Y336528I-1185J923D01*
G03X850058Y337143I-266J299D01*
G02X849797Y337404I924J1185D01*
G03X849167I-315J-246D01*
G02X847059Y339512I-1185J923D01*
G03Y340142I-246J315D01*
G02Y342512I923J1185D01*
G03Y343142I-246J315D01*
G02X849167Y345250I923J1185D01*
G03X849797I315J246D01*
G02X852167I1185J-923D01*
G03X852797I315J246D01*
G02X855167I1185J-923D01*
G03X855797I315J246D01*
G02X857905Y343142I1185J-923D01*
G03Y342512I246J-315D01*
G02Y340142I-923J-1185D01*
G03Y339512I246J-315D01*
G02X857979Y337204I-923J-1185D01*
G03X857999Y336589I266J-299D01*
G02X855890Y334482I-924J-1184D01*
G03X855260I-315J-246D01*
G02X852890I-1185J923D01*
G37*
G36*
G01X102187Y334221D02*
G03X101599Y334210I-289J-277D01*
G02X101563Y336109I-1049J930D01*
G03X102151Y336120I289J277D01*
G02X102187Y334221I1049J-930D01*
G37*
G36*
G01X1497795Y336516D02*
G03X1498283Y336166I398J40D01*
G02X1497205Y334660I317J-1366D01*
G03X1496717Y335010I-398J-40D01*
G02X1495105Y336914I-317J1366D01*
G03X1494893Y337435I-369J153D01*
G02X1494589Y339834I552J1289D01*
G03X1494670Y340384I-244J317D01*
G02X1496666Y340090I1140J816D01*
G03X1496585Y339540I244J-317D01*
G02X1496620Y339488I-1145J-808D01*
G03X1496939Y339466I168J109D01*
G02X1498126Y337150I1058J-920D01*
G03X1497771Y336668I36J-398D01*
G02X1497795Y336516I-1371J-294D01*
G37*
G36*
G01X1473398Y336467D02*
G03X1473409Y335868I270J-295D01*
G02X1471552Y335833I-909J-1068D01*
G03X1471541Y336432I-270J295D01*
G02X1473398Y336467I909J1068D01*
G37*
G36*
G01X1416971Y334489D02*
G03Y333911I277J-289D01*
G02X1415029I-971J-1011D01*
G03Y334489I-277J289D01*
G02Y336511I971J1011D01*
G03Y337089I-277J289D01*
G02X1416971I971J1011D01*
G03Y336511I277J-289D01*
G02Y334489I-971J-1011D01*
G37*
G36*
G01X1570182Y333131D02*
G03Y332553I277J-289D01*
G02X1568240I-971J-1011D01*
G03Y333131I-277J289D01*
G02X1570182I971J1011D01*
G37*
G36*
G01X1548600Y333102D02*
G03X1548734Y332556I343J-205D01*
G02X1546798Y332082I-733J-1195D01*
G03X1546664Y332628I-343J205D01*
G02X1548600Y333102I733J1195D01*
G37*
G36*
G01X773426Y331585D02*
G03X773170Y331092I128J-379D01*
G02X770343Y331241I-1440J-427D01*
G03X770038Y331789I-369J153D01*
G02X771437Y334227I240J1483D01*
G03X771999Y334172I309J255D01*
G02X774055Y334025I950J-1163D01*
G03X774640Y334021I294J271D01*
G02X776466Y331678I1091J-1033D01*
G03X776330Y331104I195J-349D01*
G02X774427Y331504I-1159J-788D01*
G03X774533Y332084I-213J339D01*
G02X774498Y332133I1204J897D01*
G03X774171Y332135I-164J-114D01*
G02X773426Y331585I-1221J875D01*
G37*
G36*
G01X1526765Y328878D02*
G03X1526213Y328768I-220J-334D01*
G02X1525823Y330723I-1162J785D01*
G03X1526375Y330833I220J334D01*
G02X1526765Y328878I1162J-785D01*
G37*
G36*
G01X1560995Y330789D02*
G03Y330211I277J-289D01*
G02X1559053I-971J-1011D01*
G03Y330789I-277J289D01*
G02X1560995I971J1011D01*
G37*
G36*
G01X1654016Y328102D02*
G03X1654038Y327534I292J-273D01*
G02X1652066Y327457I-947J-1034D01*
G03X1652044Y328025I-292J273D01*
G02X1654016Y328102I947J1034D01*
G37*
G36*
G01X645706Y326977D02*
G03X645589Y327576I-312J250D01*
G02X647366Y327923I683J1224D01*
G03X647483Y327324I312J-250D01*
G02X645706Y326977I-683J-1224D01*
G37*
G36*
G01X1493775Y327586D02*
G03X1493930Y327048I352J-190D01*
G02X1492005Y326492I-690J-1220D01*
G03X1491850Y327030I-352J190D01*
G02X1493775Y327586I690J1220D01*
G37*
G36*
G01X376986Y330493D02*
G03X377603Y330507I303J261D01*
G02X379341Y328185I1182J-927D01*
G03X379154Y327595I148J-372D01*
G02X376831Y325716I-1260J-818D01*
G03X376269Y325720I-283J-283D01*
G02X374123Y325775I-1046J1078D01*
G03X373528Y325764I-293J-272D01*
G02X371284Y325731I-1137J982D01*
G03X370728Y325764I-295J-270D01*
G02X368647Y325881I-980J1138D01*
G03X368094Y325913I-293J-272D01*
G02X368087Y325906I-1062J1055D01*
G03X368024Y325360I257J-306D01*
G02X365856Y325610I-1202J-901D01*
G03X365919Y326156I-257J306D01*
G02X368222Y328078I1202J900D01*
G03X368775Y328046I293J272D01*
G02X370855Y327917I973J-1144D01*
G03X371411Y327884I295J270D01*
G02X373491Y327769I980J-1138D01*
G03X374086Y327780I293J272D01*
G02X374473Y328099I1135J-983D01*
G03X374604Y328670I-200J346D01*
G02X376986Y330493I1244J842D01*
G37*
G36*
G01X1017937Y325288D02*
G03X1017717Y324783I156J-368D01*
G02X1015855Y325596I-1318J-479D01*
G03X1016075Y326101I-156J368D01*
G02X1018366Y327590I1318J480D01*
G03X1018920I277J288D01*
G02X1020866I973J-1010D01*
G03X1021420I277J288D01*
G02X1023366I973J-1010D01*
G03X1023920I277J288D01*
G02X1024287Y327844I971J-1011D01*
G03X1024479Y328371I-172J361D01*
G02X1026567Y330094I1276J580D01*
G03X1027153Y330233I232J326D01*
G02X1028642Y328200I1240J-653D01*
G03X1028420Y327534I71J-394D01*
G02X1026420Y325570I-1027J-955D01*
G03X1025866I-277J-288D01*
G02X1023920I-973J1010D01*
G03X1023366I-277J-288D01*
G02X1021420I-973J1010D01*
G03X1020866I-277J-288D01*
G02X1018920I-973J1010D01*
G03X1018366I-277J-288D01*
G02X1017937Y325288I-972J1011D01*
G37*
G36*
G01X1543591Y324428D02*
G03X1543924Y323984I397J-49D01*
G02X1542309Y322772I-224J-1384D01*
G03X1541976Y323216I-397J49D01*
G02X1543591Y324428I224J1384D01*
G37*
G36*
G01X1590800Y323413D02*
G03X1591385Y323202I378J131D01*
G02X1590786Y321542I725J-1200D01*
G03X1590201Y321753I-378J-131D01*
G02X1590800Y323413I-725J1200D01*
G37*
G36*
G01X688320Y318775D02*
G03X688262Y318235I263J-301D01*
G02X686218Y318455I-1124J-838D01*
G03X686276Y318995I-263J301D01*
G02X688320Y318775I1124J838D01*
G37*
G36*
G01X647783Y319011D02*
G03Y318389I252J-311D01*
G02X646017I-883J-1089D01*
G03Y319011I-252J311D01*
G02X647783I883J1089D01*
G37*
G36*
G01X115528Y319963D02*
G03X115764Y320490I-135J377D01*
G02X117535Y319696I1299J526D01*
G03X117299Y319169I135J-377D01*
G02X117398Y318750I-1299J-528D01*
G03X117844Y318383I399J30D01*
G02X116610Y316884I164J-1392D01*
G03X116164Y317251I-399J-30D01*
G02X115528Y319963I-163J1392D01*
G37*
G36*
G01X1549195Y318450D02*
G03X1549443Y317930I374J-141D01*
G02X1547687Y317092I-443J-1330D01*
G03X1547439Y317612I-374J141D01*
G02X1549195Y318450I443J1330D01*
G37*
G36*
G01X1568271Y314778D02*
G03X1568629Y314283I388J-96D01*
G02X1567163Y313224I-105J-1398D01*
G03X1566805Y313719I-388J96D01*
G02X1565900Y314144I104J1398D01*
G03X1565346Y314165I-288J-277D01*
G02X1565421Y316183I-935J1045D01*
G03X1565975Y316162I288J277D01*
G02X1568271Y314778I935J-1045D01*
G37*
G36*
G01X1517245Y312208D02*
G03X1517209Y311654I269J-296D01*
G02X1515194Y311785I-1071J-905D01*
G03X1515230Y312339I-269J296D01*
G02X1517245Y312208I1071J905D01*
G37*
G36*
G01X1640423Y311762D02*
G03Y311208I288J-277D01*
G02X1638403I-1010J-973D01*
G03Y311762I-288J277D01*
G02X1640423I1010J973D01*
G37*
G36*
G01X1047773Y310863D02*
G03X1048390Y310862I309J254D01*
G02X1048386Y308951I1157J-958D01*
G03X1047769Y308952I-309J-254D01*
G02X1047773Y310863I-1157J958D01*
G37*
G36*
G01X1040555Y310849D02*
G03X1041179Y310848I312J250D01*
G02X1041175Y308965I1168J-944D01*
G03X1040551Y308966I-312J-250D01*
G02X1040555Y310849I-1168J944D01*
G37*
G36*
G01X405294Y310843D02*
G03X405920Y310841I314J248D01*
G02X405917Y308971I1174J-937D01*
G03X405291Y308973I-314J-248D01*
G02X405294Y310843I-1174J937D01*
G37*
G36*
G01X383682Y310833D02*
G03X384312Y310831I316J245D01*
G02X384309Y308981I1182J-927D01*
G03X383679Y308983I-316J-245D01*
G02X383682Y310833I-1182J927D01*
G37*
G36*
G01X1565345Y310023D02*
G03X1565339Y309424I262J-302D01*
G02X1563482Y309443I-939J-1041D01*
G03X1563488Y310042I-262J302D01*
G02X1565345Y310023I939J1041D01*
G37*
G36*
G01X714980Y309887D02*
G03Y309333I288J-277D01*
G02X712960I-1010J-973D01*
G03Y309887I-288J277D01*
G02X714980I1010J973D01*
G37*
G36*
G01X455158Y309368D02*
G03Y308814I288J-277D01*
G02X452981Y307064I-1010J-972D01*
G03X452426Y307175I-333J-222D01*
G02X450266Y308104I-778J1166D01*
G03X449789Y308428I-394J-67D01*
G02X448527Y308790I-289J1372D01*
G03X447973I-277J-288D01*
G02Y310810I-973J1010D01*
G03X448527I277J288D01*
G02X450882Y310037I973J-1010D01*
G03X451359Y309713I394J67D01*
G02X452218Y309622I289J-1372D01*
G03X452773Y310066I163J365D01*
G02X455158Y309368I1375J275D01*
G37*
G36*
G01X1561087Y309435D02*
G03X1561176Y308850I311J-252D01*
G02X1559310Y308565I-776J-1167D01*
G03X1559221Y309150I-311J252D01*
G02X1561087Y309435I776J1167D01*
G37*
G36*
G01X849497Y305804D02*
G03X848867I-315J-246D01*
G02X846586Y307754I-1185J923D01*
G03Y308300I-292J273D01*
G02X846624Y310393I1096J1027D01*
G03Y310961I-282J284D01*
G02X846586Y313054I1058J1066D01*
G03Y313600I-292J273D01*
G02X848867Y315550I1096J1027D01*
G03X849497I315J246D01*
G02X851867I1185J-923D01*
G03X852497I315J246D01*
G02X854867I1185J-923D01*
G03X855497I315J246D01*
G02X857778Y313600I1185J-923D01*
G03Y313054I292J-273D01*
G02X857740Y310961I-1096J-1027D01*
G03Y310393I282J-284D01*
G02X857778Y308300I-1058J-1066D01*
G03Y307754I292J-273D01*
G02X855497Y305804I-1096J-1027D01*
G03X854867I-315J-246D01*
G02X852497I-1185J923D01*
G03X851867I-315J-246D01*
G02X849497I-1185J923D01*
G37*
G36*
G01X1306859Y308248D02*
G03X1306876Y307664I281J-284D01*
G02X1304964Y307608I-926J-1053D01*
G03X1304947Y308192I-281J284D01*
G02X1304824Y308315I928J1051D01*
G03X1304271Y308358I-299J-266D01*
G02X1304429Y310371I-891J1083D01*
G03X1304982Y310328I299J266D01*
G02X1306859Y308248I891J-1083D01*
G37*
G36*
G01X198962Y305776D02*
G03X198423Y305919I-343J-205D01*
G02X196657Y308323I-739J1308D01*
G03X196667Y308898I-273J292D01*
G02X198757Y308863I1063J1061D01*
G03X198747Y308288I273J-292D01*
G02X198973Y307999I-1061J-1063D01*
G03X199512Y307856I343J205D01*
G02X198962Y305776I739J-1308D01*
G37*
G36*
G01X1537386Y305392D02*
G03X1537870Y305102I388J98D01*
G02X1536847Y303397I336J-1361D01*
G03X1536363Y303687I-388J-98D01*
G02X1537386Y305392I-336J1361D01*
G37*
G36*
G01X1637893Y304142D02*
G03X1637906Y303586I294J-271D01*
G02X1635890Y303537I-984J-998D01*
G03X1635877Y304093I-294J271D01*
G02X1637893Y304142I984J998D01*
G37*
G36*
G01X1564358Y302020D02*
G03X1564356Y302642I-253J310D01*
G02X1566121Y302648I879J1092D01*
G03X1566123Y302026I253J-310D01*
G02X1564358Y302020I-879J-1092D01*
G37*
G36*
G01X1584487Y302124D02*
G03Y301556I281J-284D01*
G02X1582513I-987J-996D01*
G03Y302124I-281J284D01*
G02X1584487I987J996D01*
G37*
G36*
G01X1300631Y300220D02*
G03X1300624Y299612I256J-307D01*
G02X1298804Y299635I-923J-1055D01*
G03X1298811Y300243I-256J307D01*
G02X1300631Y300220I923J1055D01*
G37*
G36*
G01X657627Y294985D02*
G03X657426Y295549I-350J193D01*
G02X659176Y296170I524J1301D01*
G03X659377Y295606I350J-193D01*
G02X657627Y294985I-524J-1301D01*
G37*
G36*
G01X1026147Y293881D02*
G03X1026758Y293878I307J256D01*
G02X1026749Y291941I1144J-974D01*
G03X1026138Y291944I-307J-256D01*
G02X1026147Y293881I-1144J974D01*
G37*
G36*
G01X405427Y293983D02*
G03X406022Y293956I310J253D01*
G02X405933Y291951I1072J-1052D01*
G03X405338Y291978I-310J-253D01*
G02X405427Y293983I-1072J1052D01*
G37*
G36*
G01X398128Y293919D02*
G03X398758Y293887I327J229D01*
G02X398663Y292043I1136J-983D01*
G03X398033Y292075I-327J-229D01*
G02X398128Y293919I-1136J983D01*
G37*
G36*
G01X383861Y294061D02*
G03X384464Y293997I329J227D01*
G02X384258Y292050I1030J-1093D01*
G03X383655Y292114I-329J-227D01*
G02X383861Y294061I-1030J1093D01*
G37*
G36*
G01X372760Y291927D02*
G03X372204Y291892I-260J-304D01*
G02X369861Y292046I-1110J1012D01*
G03X369235Y292085I-328J-228D01*
G02X369349Y293945I-1119J1002D01*
G03X369975Y293906I328J228D01*
G02X372070Y294045I1119J-1002D01*
G03X372626Y294080I260J304D01*
G02X372760Y291927I1110J-1012D01*
G37*
G36*
G01X1637832Y293973D02*
G03Y293419I288J-277D01*
G02X1635812I-1010J-973D01*
G03Y293973I-288J277D01*
G02X1635853Y295959I1010J973D01*
G03X1635876Y296514I-276J289D01*
G02X1637894Y296431I1049J930D01*
G03X1637871Y295876I276J-289D01*
G02X1637832Y293973I-1049J-930D01*
G37*
G36*
G01X1305637Y292913D02*
G03X1305262Y292476I23J-399D01*
G02X1303787Y293745I-1396J-131D01*
G03X1304162Y294182I-23J399D01*
G02X1305637Y292913I1396J131D01*
G37*
G36*
G01X1335501Y292918D02*
G03X1336123Y292909I315J247D01*
G02X1336099Y291144I1077J-897D01*
G03X1335477Y291153I-315J-247D01*
G02X1335501Y292918I-1077J897D01*
G37*
G36*
G01X1534824Y287709D02*
G03X1534841Y287125I281J-284D01*
G02X1532928Y287070I-927J-1052D01*
G03X1532911Y287654I-281J284D01*
G02X1534824Y287709I927J1052D01*
G37*
G36*
G01X1548006Y287663D02*
G03X1548358Y287223I398J-43D01*
G02X1546805Y285979I-159J-1393D01*
G03X1546453Y286419I-398J43D01*
G02X1548006Y287663I159J1393D01*
G37*
G36*
G01X637881Y287185D02*
G03X637839Y286610I255J-308D01*
G02X636064Y286864I-1040J-940D01*
G03X636087Y287187I-105J170D01*
G02X635967Y287300I900J1076D01*
G03X635645Y287257I-146J-137D01*
G02X635280Y289012I-1238J658D01*
G03X635852Y289090I249J313D01*
G02X637881Y287185I1133J-827D01*
G37*
G36*
G01X115528Y287963D02*
G03X115764Y288490I-135J377D01*
G02X117535Y287696I1299J526D01*
G03X117299Y287169I135J-377D01*
G02X117398Y286750I-1299J-528D01*
G03X117844Y286383I399J30D01*
G02X116610Y284884I164J-1392D01*
G03X116164Y285251I-399J-30D01*
G02X115528Y287963I-163J1392D01*
G37*
G36*
G01X663911Y283917D02*
G03X663289I-311J-252D01*
G02X660957Y285448I-1089J883D01*
G03X660742Y286007I-355J184D01*
G02X662475Y286673I490J1314D01*
G03X662690Y286114I355J-184D01*
G02X663289Y285683I-491J-1314D01*
G03X663911I311J252D01*
G02Y283917I1089J-883D01*
G37*
G36*
G01X1580115Y283805D02*
G03X1579560Y283799I-274J-291D01*
G02X1579539Y285819I-983J1000D01*
G03X1580094Y285825I274J291D01*
G02X1580115Y283805I983J-1000D01*
G37*
G36*
G01X1570790Y286064D02*
G03X1571021Y286576I-144J373D01*
G02X1573704Y286758I1315J487D01*
G03X1574027Y286277I391J-87D01*
G02X1572875Y283833I-237J-1382D01*
G03X1572321Y283802I-261J-303D01*
G02X1570790Y286064I-1028J953D01*
G37*
G36*
G01X560979Y284997D02*
G03X560608Y284565I28J-399D01*
G02X559116Y285846I-1397J-118D01*
G03X559487Y286278I-28J399D01*
G02X560979Y284997I1397J118D01*
G37*
G36*
G01X1315646Y285315D02*
G03X1315579Y284745I243J-318D01*
G02X1313636Y284974I-1089J-883D01*
G03X1313703Y285544I-243J318D01*
G02X1315646Y285315I1089J883D01*
G37*
G36*
G01X1399552Y283306D02*
G03X1399680Y282764I343J-205D01*
G02X1397721Y282299I-754J-1182D01*
G03X1397593Y282841I-343J205D01*
G02X1399552Y283306I754J1182D01*
G37*
G36*
G01X1097703Y279975D02*
G03X1098242I269J295D01*
G02X1098239Y277904I944J-1037D01*
G03X1097700I-269J-295D01*
G02X1097703Y279975I-944J1037D01*
G37*
G36*
G01X448798Y277912D02*
G03X448198I-300J-265D01*
G02Y279770I-1050J929D01*
G03X448798I300J265D01*
G02Y277912I1050J-929D01*
G37*
G36*
G01X1434372Y279771D02*
G03Y279217I288J-277D01*
G02X1432352I-1010J-973D01*
G03Y279771I-288J277D01*
G02X1434372I1010J973D01*
G37*
G36*
G01X662303Y279878D02*
G03X662721Y279485I400J6D01*
G02X661384Y278062I65J-1401D01*
G03X660966Y278455I-400J-6D01*
G02X662303Y279878I-65J1401D01*
G37*
G36*
G01X648422Y279263D02*
G03X648418Y278671I267J-298D01*
G02X646534Y278684I-949J-1032D01*
G03X646538Y279276I-267J298D01*
G02X648422Y279263I949J1032D01*
G37*
G36*
G01X1333680Y274524D02*
X1330171D01*
G02Y277546I0J1511D01*
G01X1333681D01*
G02X1335192Y276045I0J-1512D01*
G01Y275950D01*
X1335182Y275866D01*
G02X1333680Y274524I-1502J169D01*
G37*
G36*
G01X452389Y274629D02*
G03X451811I-289J-277D01*
G02Y276571I-1011J971D01*
G03X452389I289J277D01*
G02Y274629I1011J-971D01*
G37*
G36*
G01X778572Y275068D02*
G03X777973Y274913I-236J-323D01*
G02X777528Y276632I-1273J588D01*
G03X778127Y276787I236J323D01*
G02X778572Y275068I1273J-588D01*
G37*
G36*
G01X1637694Y276342D02*
G03Y275788I288J-277D01*
G02X1635674I-1010J-973D01*
G03Y276342I-288J277D01*
G02Y278288I1010J973D01*
G03Y278842I-288J277D01*
G02X1637694I1010J973D01*
G03Y278288I288J-277D01*
G02Y276342I-1010J-973D01*
G37*
G36*
G01X824279Y273987D02*
G03X823649I-315J-246D01*
G02X821368Y275937I-1185J923D01*
G03Y276483I-292J273D01*
G02Y278537I1096J1027D01*
G03Y279083I-292J273D01*
G02X823649Y281033I1096J1027D01*
G03X824279I315J246D01*
G02X826649I1185J-923D01*
G03X827279I315J246D01*
G02X829649I1185J-923D01*
G03X830279I315J246D01*
G02X832649I1185J-923D01*
G03X833279I315J246D01*
G02X835570Y281127I1185J-923D01*
G03X836158I294J270D01*
G02X838370I1106J-1017D01*
G03X838958I294J270D01*
G02X841160Y279083I1106J-1017D01*
G03Y278537I292J-273D01*
G02X838958Y276493I-1096J-1027D01*
G03X838370I-294J-270D01*
G02X838360Y276483I-1067J1056D01*
G03Y275937I292J-273D01*
G02X836158Y273893I-1096J-1027D01*
G03X835570I-294J-270D01*
G02X833279Y273987I-1106J1017D01*
G03X832649I-315J-246D01*
G02X830279I-1185J923D01*
G03X829649I-315J-246D01*
G02X827279I-1185J923D01*
G03X826649I-315J-246D01*
G02X824279I-1185J923D01*
G37*
G36*
G01X850197Y273504D02*
G03X849567I-315J-246D01*
G02X847286Y275454I-1185J923D01*
G03Y276000I-292J273D01*
G02X847324Y278093I1096J1027D01*
G03Y278661I-282J284D01*
G02X847286Y280754I1058J1066D01*
G03Y281300I-292J273D01*
G02X849567Y283250I1096J1027D01*
G03X850197I315J246D01*
G02X852567I1185J-923D01*
G03X853197I315J246D01*
G02X855567I1185J-923D01*
G03X856197I315J246D01*
G02X858478Y281300I1185J-923D01*
G03Y280754I292J-273D01*
G02X858440Y278661I-1096J-1027D01*
G03Y278093I282J-284D01*
G02X858478Y276000I-1058J-1066D01*
G03Y275454I292J-273D01*
G02X856197Y273504I-1096J-1027D01*
G03X855567I-315J-246D01*
G02X853197I-1185J923D01*
G03X852567I-315J-246D01*
G02X850197I-1185J923D01*
G37*
G36*
G01X1340248Y270244D02*
X1336448D01*
G02Y273266I0J1511D01*
G01X1340249D01*
G02X1341760Y271765I0J-1512D01*
G01Y271670D01*
X1341750Y271586D01*
G02X1340248Y270244I-1502J169D01*
G37*
G36*
G01X1412345Y270158D02*
G03X1412700Y269670I390J-90D01*
G02X1411213Y268588I-121J-1397D01*
G03X1410858Y269076I-390J90D01*
G02X1412345Y270158I121J1397D01*
G37*
G36*
G01X1010655Y269874D02*
G03X1011064Y269502I399J28D01*
G02X1009701Y268003I36J-1402D01*
G03X1009292Y268375I-399J-28D01*
G02X1007949Y269270I-36J1402D01*
G03X1007382Y269475I-373J-145D01*
G02X1005785Y271762I-682J1225D01*
G03X1005777Y272375I-261J303D01*
G02X1007580Y272398I888J1085D01*
G03X1007588Y271785I261J-303D01*
G02X1008007Y271207I-888J-1085D01*
G03X1008574Y271002I373J145D01*
G02X1010655Y269874I682J-1225D01*
G37*
G36*
G01X361047D02*
G03X361456Y269502I399J28D01*
G02X360093Y268003I36J-1402D01*
G03X359684Y268375I-399J-28D01*
G02X358341Y269270I-36J1402D01*
G03X357774Y269475I-373J-145D01*
G02X356177Y271762I-682J1225D01*
G03X356169Y272375I-261J303D01*
G02X357972Y272398I888J1085D01*
G03X357980Y271785I261J-303D01*
G02X358399Y271207I-888J-1085D01*
G03X358966Y271002I373J145D01*
G02X361047Y269874I682J-1225D01*
G37*
G36*
G01X1347468Y266584D02*
X1343668D01*
G02Y269606I0J1511D01*
G01X1347469D01*
G02X1348980Y268105I0J-1512D01*
G01Y268010D01*
X1348970Y267926D01*
G02X1347468Y266584I-1502J169D01*
G37*
G36*
G01X748148Y268571D02*
G03X748170Y269192I-241J319D01*
G02X749932Y269129I920J1058D01*
G03X749910Y268508I241J-319D01*
G02X748148Y268571I-920J-1058D01*
G37*
G36*
G01X773888Y267630D02*
G03X774434Y267508I335J218D01*
G02X774041Y265487I737J-1192D01*
G03X773489Y265578I-323J-237D01*
G02X771498Y265822I-859J1232D01*
G03X770869Y265788I-301J-263D01*
G02X769071Y268038I-1232J859D01*
G03X769249Y268636I-151J370D01*
G02X771051Y268098I1236J853D01*
G03X770873Y267500I151J-370D01*
G02X770919Y267430I-1232J-860D01*
G03X771271Y267449I171J104D01*
G02X773888Y267630I1359J-639D01*
G37*
G36*
G01X1452990Y267710D02*
G03X1453522Y267465I380J125D01*
G02X1452703Y265803I534J-1296D01*
G03X1452184Y266075I-386J-105D01*
G02X1452990Y267710I-431J1229D01*
G37*
G36*
G01X1356268Y264184D02*
X1352468D01*
G02Y267206I0J1511D01*
G01X1356269D01*
G02X1357780Y265705I0J-1512D01*
G01Y265610D01*
X1357770Y265526D01*
G02X1356268Y264184I-1502J170D01*
G37*
G36*
G01X1217244Y267082D02*
G03Y266528I288J-277D01*
G02X1215224I-1010J-973D01*
G03Y267082I-288J277D01*
G02X1217244I1010J973D01*
G37*
G36*
G01X567936D02*
G03Y266528I288J-277D01*
G02X565916I-1010J-973D01*
G03Y267082I-288J277D01*
G02X567936I1010J973D01*
G37*
G36*
G01X1381031Y264088D02*
X1377522D01*
G02Y267112I0J1512D01*
G01X1381032D01*
G02X1382542Y265610I-1J-1512D01*
G01Y265515D01*
X1382533Y265431D01*
G02X1381031Y264088I-1502J168D01*
G37*
G36*
G01X1362803Y267036D02*
X1366313D01*
G02X1367824Y265535I0J-1512D01*
G01Y265440D01*
X1367814Y265356D01*
G02X1366312Y264014I-1502J169D01*
G01X1362803D01*
G02Y267036I1J1511D01*
G37*
G36*
G01X406409Y263976D02*
G03X405779I-315J-246D01*
G02Y265822I-1185J923D01*
G03X406409I315J246D01*
G02Y263976I1185J-923D01*
G37*
G36*
G01X1074342Y265966D02*
G03X1074903Y265919I304J260D01*
G02X1074723Y263791I962J-1153D01*
G03X1074162Y263838I-304J-260D01*
G02X1072085Y263984I-963J1153D01*
G03X1071476Y263965I-296J-268D01*
G02X1071415Y265907I-1176J935D01*
G03X1072024Y265926I296J268D01*
G02X1074342Y265966I1175J-935D01*
G37*
G36*
G01X424803Y263696D02*
G03X424210Y263694I-296J-269D01*
G02X421878Y263812I-1118J1003D01*
G03X421268Y263855I-323J-235D01*
G02X419004Y263975I-1080J1044D01*
G03X418374I-315J-247D01*
G02X416005Y263977I-1184J924D01*
G03X415373I-316J-246D01*
G02X413003Y263976I-1185J922D01*
G03X412373I-315J-246D01*
G02Y265822I-1185J923D01*
G03X413003I315J246D01*
G02X415373Y265821I1185J-923D01*
G03X416005I316J246D01*
G02X418374Y265823I1185J-922D01*
G03X419004I315J247D01*
G02X421402Y265784I1184J-924D01*
G03X422012Y265741I323J235D01*
G02X424200Y265711I1080J-1044D01*
G03X424793Y265713I296J269D01*
G02X424803Y263696I1118J-1003D01*
G37*
G36*
G01X437497Y263882D02*
G03X437537Y263336I311J-252D01*
G02X435351Y263176I-1018J-1104D01*
G03X435311Y263722I-311J252D01*
G02X437497Y263882I1018J1104D01*
G37*
G36*
G01X1628763Y261318D02*
G03X1628481Y260782I90J-390D01*
G02X1626286Y261349I-1304J-515D01*
G03X1626299Y261955I-255J309D01*
G02X1628763Y261318I1843J2044D01*
G37*
G36*
G01X1160308Y261401D02*
G03X1160313Y260793I262J-302D01*
G02X1158492Y260779I-902J-1073D01*
G03X1158487Y261387I-262J302D01*
G02X1160308Y261401I902J1073D01*
G37*
G36*
G01X1455205Y261089D02*
G03X1455127Y260534I244J-317D01*
G02X1453298Y260914I-1127J-834D01*
G03X1453342Y261226I-100J173D01*
G02X1453256Y261323I1005J978D01*
G03X1452944I-156J-125D01*
G02X1452823Y263210I-1094J877D01*
G03X1453377I277J288D01*
G02X1455205Y261089I972J-1010D01*
G37*
G36*
G01X1226918Y260827D02*
G03Y260273I288J-277D01*
G02X1224898I-1010J-973D01*
G03Y260827I-288J277D01*
G02X1226918I1010J973D01*
G37*
G36*
G01X576610D02*
G03Y260273I288J-277D01*
G02X574590I-1010J-973D01*
G03Y260827I-288J277D01*
G02X576610I1010J973D01*
G37*
G36*
G01X510478Y259111D02*
G03X510102Y258672I22J-399D01*
G02X508630Y259932I-1395J-140D01*
G03X509006Y260371I-22J399D01*
G02X510478Y259111I1395J140D01*
G37*
G36*
G01X1494858Y254727D02*
G03X1494307Y254648I-235J-324D01*
G02X1494023Y256641I-1108J859D01*
G03X1494574Y256720I235J324D01*
G02X1494678Y256839I1106J-861D01*
G03X1494681Y257394I-287J279D01*
G02X1496700Y257383I1015J967D01*
G03X1496697Y256828I287J-279D01*
G02X1494858Y254727I-1015J-967D01*
G37*
G36*
G01X1465810Y255243D02*
G03X1465890Y254676I316J-244D01*
G02X1463781Y252976I-827J-1132D01*
G03X1463257Y253182I-366J-161D01*
G02X1462861Y255863I-553J1288D01*
G03X1463304Y256225I44J398D01*
G02X1465810Y255243I1396J-125D01*
G37*
G36*
G01X621974Y254930D02*
G03X621904Y254340I231J-327D01*
G02X620041Y254561I-1054J-924D01*
G03X620111Y255151I-231J327D01*
G02X621974Y254930I1054J924D01*
G37*
G36*
G01X1275468Y254991D02*
G03X1275795Y254508I390J-88D01*
G02X1274209Y253432I-218J-1385D01*
G03X1273882Y253915I-390J88D01*
G02X1275468Y254991I218J1385D01*
G37*
G36*
G01X116610Y252884D02*
G03X116164Y253251I-399J-30D01*
G02X115528Y255963I-163J1392D01*
G03X115764Y256490I-135J377D01*
G02X117535Y255696I1299J526D01*
G03X117299Y255169I135J-377D01*
G02X117398Y254750I-1299J-528D01*
G03X117844Y254383I399J30D01*
G02X116610Y252884I164J-1392D01*
G37*
G36*
G01X1469444Y253888D02*
G03X1469999Y253876I284J282D01*
G02X1469956Y251858I951J-1030D01*
G03X1469401Y251870I-284J-282D01*
G02X1469444Y253888I-951J1030D01*
G37*
G36*
G01X766693Y253259D02*
G03X766354Y252751I45J-397D01*
G02X764846Y253756I-1347J-388D01*
G03X765185Y254264I-45J397D01*
G02X765602Y255701I1347J388D01*
G03X765624Y256278I-266J299D01*
G02X767562Y256203I1008J974D01*
G03X767540Y255626I266J-299D01*
G02X766693Y253259I-1008J-974D01*
G37*
G36*
G01X1479777Y253333D02*
G03X1479666Y252778I222J-333D01*
G02X1477723Y253167I-1166J-778D01*
G03X1477834Y253722I-222J333D01*
G02X1477627Y254782I1166J778D01*
G03X1477271Y255261I-392J80D01*
G02X1478770Y256375I126J1396D01*
G03X1479126Y255896I392J-80D01*
G02X1479777Y253333I-126J-1396D01*
G37*
G36*
G01X1434852Y253400D02*
G03X1434985Y252823I328J-228D01*
G02X1433148Y252400I-686J-1223D01*
G03X1433015Y252977I-328J228D01*
G02X1434852Y253400I686J1223D01*
G37*
G36*
G01X1817282Y248886D02*
X1812281D01*
G02X1812282Y252110I1J1612D01*
G01X1817282D01*
G02X1818894Y250508I0J-1612D01*
G01Y250413D01*
X1818884Y250328D01*
G02X1817282Y248886I-1602J169D01*
G37*
G36*
G01X1798384D02*
X1793384D01*
G02Y252110I0J1612D01*
G01X1798385D01*
G02X1799996Y250508I-1J-1612D01*
G01Y250413D01*
X1799986Y250328D01*
G02X1798384Y248886I-1602J169D01*
G37*
G36*
G01X1825702Y251794D02*
G03X1826143Y251395I400J-1D01*
G02X1824885Y250006I144J-1395D01*
G03X1824444Y250405I-400J1D01*
G02X1825702Y251794I-144J1395D01*
G37*
G36*
G01X1736815Y249077D02*
G03X1736185I-315J-246D01*
G02Y250923I-1185J923D01*
G03X1736815I315J246D01*
G02X1739185I1185J-923D01*
G03X1739815I315J246D01*
G02Y249077I1185J-923D01*
G03X1739185I-315J-246D01*
G02X1736815I-1185J923D01*
G37*
G36*
G01X1690282Y249679D02*
G03X1689813Y249382I-80J-392D01*
G02X1687183Y249118I-1362J334D01*
G03X1686664Y249315I-362J-171D01*
G02X1685186Y249552I-551J1289D01*
G03X1684632Y249528I-265J-300D01*
G02X1684542Y251545I-1017J965D01*
G03X1685096Y251569I265J300D01*
G02X1687381Y251202I1017J-965D01*
G03X1687900Y251005I362J171D01*
G02X1688734Y251089I551J-1289D01*
G03X1689203Y251386I80J392D01*
G02X1690282Y249679I1362J-334D01*
G37*
G36*
G01X1597653Y247276D02*
G03X1598245Y247267I300J264D01*
G02X1598217Y245384I1025J-957D01*
G03X1597625Y245393I-300J-264D01*
G02X1597653Y247276I-1025J957D01*
G37*
G36*
G01X1468298Y245076D02*
G03X1467721Y244868I-201J-345D01*
G02X1467110Y246561I-1317J482D01*
G03X1467687Y246769I201J345D01*
G02X1470015Y247258I1317J-482D01*
G03X1470593I289J277D01*
G02Y245316I1011J-971D01*
G03X1470015I-289J-277D01*
G02X1468298Y245076I-1011J971D01*
G37*
G36*
G01X1510804Y246222D02*
G03X1510800Y245658I282J-284D01*
G02X1508810Y245669I-1000J-982D01*
G03X1508814Y246233I-282J284D01*
G02X1510804Y246222I1000J982D01*
G37*
G36*
G01X89773Y243304D02*
G03X89227I-273J-292D01*
G02X87277Y245585I-1027J1096D01*
G03Y246215I-246J315D01*
G02Y248585I923J1185D01*
G03Y249215I-246J315D01*
G02Y251585I923J1185D01*
G03Y252215I-246J315D01*
G02X87228Y254545I923J1185D01*
G03Y255155I-259J305D01*
G02X87104Y257327I972J1145D01*
G03Y257873I-292J273D01*
G02X89227Y259996I1096J1027D01*
G03X89773I273J292D01*
G02X91827I1027J-1096D01*
G03X92373I273J292D01*
G02X94427I1027J-1096D01*
G03X94973I273J292D01*
G02X97027I1027J-1096D01*
G03X97573I273J292D01*
G02X99696Y257873I1027J-1096D01*
G03Y257327I292J-273D01*
G02X99572Y255155I-1096J-1027D01*
G03Y254545I259J-305D01*
G02X99523Y252215I-972J-1145D01*
G03Y251585I246J-315D01*
G02Y249215I-923J-1185D01*
G03Y248585I246J-315D01*
G02Y246215I-923J-1185D01*
G03Y245585I246J-315D01*
G02X97573Y243304I-923J-1185D01*
G03X97027I-273J-292D01*
G02X94973I-1027J1096D01*
G03X94427I-273J-292D01*
G02X92373I-1027J1096D01*
G03X91827I-273J-292D01*
G02X89773I-1027J1096D01*
G37*
G36*
G01X1662588Y245377D02*
G03X1662981Y244984I400J7D01*
G02X1661554Y243557I-25J-1402D01*
G03X1661161Y243950I-400J-7D01*
G02X1662588Y245377I25J1402D01*
G37*
G36*
G01X1215804Y244399D02*
G03X1216413Y244396I306J258D01*
G02X1216404Y242579I1063J-914D01*
G03X1215795Y242582I-306J-258D01*
G02X1215804Y244399I-1063J914D01*
G37*
G36*
G01X569422Y242495D02*
G03X568860Y242491I-279J-286D01*
G02X566796Y242579I-992J991D01*
G03X566187Y242582I-306J-258D01*
G02X566196Y244399I-1063J914D01*
G03X566805Y244396I306J258D01*
G02X568846Y244487I1063J-914D01*
G03X569408Y244491I279J286D01*
G02X569422Y242495I992J-991D01*
G37*
G36*
G01X1548542Y245073D02*
G03X1548652Y244519I333J-222D01*
G02X1546702Y244133I-783J-1163D01*
G03X1546592Y244687I-333J222D01*
G02X1548542Y245073I783J1163D01*
G37*
G36*
G01X1515446Y244968D02*
G03X1515447Y244410I287J-278D01*
G02X1513296Y244409I-1075J-1049D01*
G03X1513295Y244967I-287J278D01*
G02X1513274Y247043I1075J1049D01*
G03X1513275Y247590I-291J274D01*
G02X1515468Y247589I1097J1026D01*
G03X1515467Y247042I291J-274D01*
G02X1515446Y244968I-1097J-1026D01*
G37*
G36*
G01X1626025Y242615D02*
G03X1626599Y242478I350J194D01*
G02X1625390Y240152I1543J-2279D01*
G03X1624948Y240543I-400J-7D01*
G02X1626025Y242615I-150J1394D01*
G37*
G36*
G01X1779451Y236100D02*
X1774450D01*
G02X1774451Y239324I1J1612D01*
G01X1779451D01*
G02X1781062Y237722I0J-1611D01*
G01Y237627D01*
X1781053Y237542D01*
G02X1779451Y236100I-1602J169D01*
G37*
G36*
G01X1760554D02*
X1755554D01*
G02Y239324I0J1612D01*
G01X1760555D01*
G02X1762166Y237722I-1J-1612D01*
G01Y237627D01*
X1762156Y237542D01*
G02X1760554Y236100I-1602J169D01*
G37*
G36*
G01X642637Y237601D02*
G03Y237055I292J-273D01*
G02X640445I-1096J-1027D01*
G03Y237601I-292J273D01*
G02Y239655I1096J1027D01*
G03Y240201I-292J273D01*
G02Y242255I1096J1027D01*
G03Y242801I-292J273D01*
G02X642637I1096J1027D01*
G03Y242255I292J-273D01*
G02Y240201I-1096J-1027D01*
G03Y239655I292J-273D01*
G02Y237601I-1096J-1027D01*
G37*
G36*
G01X1572141Y234659D02*
G03X1571596Y234427I-167J-363D01*
G02X1570861Y236161I-1324J462D01*
G03X1571406Y236393I167J363D01*
G02X1572753Y237333I1324J-462D01*
G03X1573159Y237717I6J400D01*
G02X1573165Y237800I1401J-60D01*
G03X1572933Y238017I-199J20D01*
G02X1572213Y238085I-233J1383D01*
G03X1571684Y237800I-139J-375D01*
G02X1570805Y239431I-1366J316D01*
G03X1571334Y239716I139J375D01*
G02X1573024Y240764I1366J-316D01*
G03X1573512Y241097I92J389D01*
G02X1574377Y239599I1388J-197D01*
G03X1574102Y239412I-75J-185D01*
G02X1574095Y239260I-1402J-12D01*
G03X1574327Y239043I199J-20D01*
G02X1574537Y236258I232J-1383D01*
G03X1574131Y235874I-6J-400D01*
G02X1572141Y234659I-1401J57D01*
G37*
G36*
G01X771881Y236329D02*
G03X771811Y235764I244J-317D01*
G02X769716Y236023I-1179J-931D01*
G03X769786Y236588I-244J317D01*
G02X769698Y236712I1179J930D01*
G03X769395Y236752I-168J-108D01*
G02X769546Y238811I-1013J1109D01*
G03X770089Y238739I310J253D01*
G02X772021Y238587I876J-1220D01*
G03X772617Y238625I281J285D01*
G02X772744Y236632I1183J-925D01*
G03X772148Y236594I-281J-285D01*
G02X771881Y236329I-1183J925D01*
G37*
G36*
G01X1844293Y237781D02*
G03X1844175Y237187I197J-348D01*
G02X1839851Y237383I-2246J-1757D01*
G03X1839724Y238022I-291J274D01*
G02X1841617Y238819I576J1278D01*
G03X1841985Y238281I376J-138D01*
G02X1842075Y238278I-50J-2851D01*
G03X1842275Y238543I11J200D01*
G02X1844293Y237781I1325J457D01*
G37*
G36*
G01X1682700Y234573D02*
G03X1683292Y234554I305J259D01*
G02X1683232Y232671I1008J-975D01*
G03X1682640Y232690I-305J-259D01*
G02X1682700Y234573I-1008J975D01*
G37*
G36*
G01X1767985Y232438D02*
G03X1767403Y232224I-204J-344D01*
G02X1766792Y233887I-1326J457D01*
G03X1767374Y234101I204J344D01*
G02X1767985Y232438I1326J-457D01*
G37*
G36*
G01X1804379Y233482D02*
G03X1805001Y233476I313J248D01*
G02X1804984Y231713I1082J-892D01*
G03X1804362Y231719I-313J-248D01*
G02X1804379Y233482I-1082J892D01*
G37*
G36*
G01X1794608Y234126D02*
G03X1794630Y233549I288J-278D01*
G02X1792692Y233474I-930J-1049D01*
G03X1792670Y234051I-288J278D01*
G02X1794608Y234126I930J1049D01*
G37*
G36*
G01X1883239Y233459D02*
G03X1883271Y232890I296J-269D01*
G02X1881306Y232778I-926J-1053D01*
G03X1881274Y233347I-296J269D01*
G02X1882924Y235600I926J1052D01*
G03X1883468Y235728I206J343D01*
G02X1883927Y233775I1183J-752D01*
G03X1883383Y233647I-206J-343D01*
G02X1883239Y233459I-1181J755D01*
G37*
G36*
G01X824285Y230658D02*
G03X823732Y230653I-274J-292D01*
G02X821586Y232754I-1050J1074D01*
G03Y233300I-292J273D01*
G02X821624Y235393I1096J1027D01*
G03Y235961I-282J284D01*
G02X821586Y238054I1058J1066D01*
G03Y238600I-292J273D01*
G02X823867Y240550I1096J1027D01*
G03X824497I315J246D01*
G02X826867I1185J-923D01*
G03X827497I315J246D01*
G02X829867I1185J-923D01*
G03X830497I315J246D01*
G02X832867I1185J-923D01*
G03X833497I315J246D01*
G02X835840Y240583I1185J-923D01*
G03X836433Y240557I308J255D01*
G02X838495Y238375I1068J-1056D01*
G03Y237775I265J-300D01*
G02X838596Y235623I-995J-1125D01*
G03Y235077I292J-273D01*
G02X838603Y235070I-1058J-1065D01*
G03X838915Y235092I147J135D01*
G02X839185Y233098I1240J-847D01*
G03X838627Y233057I-258J-305D01*
G02X836340Y233096I-1127J993D01*
G03X835751Y233127I-309J-254D01*
G02X833470Y233338I-1051J1073D01*
G03X832835Y233365I-328J-229D01*
G02X830497Y233404I-1153J962D01*
G03X829867I-315J-246D01*
G02X829550Y233101I-1185J923D01*
G03X829444Y232559I231J-327D01*
G02X827046Y230763I-1264J-811D01*
G03X826443Y230764I-302J-262D01*
G02X824285Y230658I-1130J989D01*
G37*
G36*
G01X175339Y230666D02*
G03X174685Y230622I-312J-251D01*
G02X172428Y232545I-1285J778D01*
G03Y233155I-259J305D01*
G02X172342Y235366I972J1145D01*
G03Y235934I-282J284D01*
G02X172428Y238145I1058J1066D01*
G03Y238755I-259J305D01*
G02X174585Y240823I972J1145D01*
G03X175215I315J246D01*
G02X177585I1185J-923D01*
G03X178215I315J246D01*
G02X180585I1185J-923D01*
G03X181215I315J246D01*
G02X183543Y240875I1185J-923D01*
G03X184142Y240864I304J259D01*
G02X186393Y240825I1108J-1014D01*
G03X186992Y240814I304J259D01*
G02X189062Y238646I1108J-1015D01*
G03X189083Y238015I256J-307D01*
G02X189255Y235731I-883J-1215D01*
G03X189276Y235142I281J-285D01*
G02X187023Y233210I-976J-1142D01*
G03X186381Y233262I-340J-211D01*
G02X184107Y233275I-1131J988D01*
G03X183508Y233286I-304J-259D01*
G02X181215Y233377I-1108J1014D01*
G03X180585I-315J-246D01*
G02X178215I-1185J923D01*
G03X177585I-315J-246D01*
G02X177503Y233280I-1187J920D01*
G03X177525Y232714I293J-272D01*
G02X175339Y230666I-1017J-1106D01*
G37*
G36*
G01X1926924Y232852D02*
G03X1926983Y232289I311J-252D01*
G02X1925011Y232083I-883J-1089D01*
G03X1924952Y232646I-311J252D01*
G02X1926924Y232852I883J1089D01*
G37*
G36*
G01X1499741Y233065D02*
G03X1499981Y232510I360J-174D01*
G02X1498296Y231783I-422J-1337D01*
G03X1498056Y232338I-360J174D01*
G02X1499741Y233065I422J1337D01*
G37*
G36*
G01X578805Y232720D02*
G03X578809Y232141I278J-288D01*
G02X576876Y232128I-960J-1022D01*
G03X576872Y232707I-278J288D01*
G02X578805Y232720I960J1022D01*
G37*
G36*
G01X1387761Y232456D02*
G03X1388231Y232161I388J96D01*
G02X1387157Y230451I287J-1372D01*
G03X1386687Y230746I-388J-96D01*
G02X1387761Y232456I-287J1372D01*
G37*
G36*
G01X571477Y230511D02*
G03X571449Y229950I270J-295D01*
G02X569455Y230047I-1045J-935D01*
G03X569483Y230608I-270J295D01*
G02X571477Y230511I1045J935D01*
G37*
G36*
G01X1939213Y229053D02*
G03X1939785Y229046I289J276D01*
G02X1939761Y226947I1062J-1062D01*
G03X1939189Y226954I-289J-276D01*
G02X1939213Y229053I-1062J1062D01*
G37*
G36*
G01X90173Y226354D02*
G03X89627I-273J-292D01*
G02X87677Y228635I-1027J1096D01*
G03Y229265I-246J315D01*
G02Y231635I923J1185D01*
G03Y232265I-246J315D01*
G02Y234635I923J1185D01*
G03Y235265I-246J315D01*
G02X89627Y237546I923J1185D01*
G03X90173I273J292D01*
G02X92227I1027J-1096D01*
G03X92773I273J292D01*
G02X94827I1027J-1096D01*
G03X95373I273J292D01*
G02X97427I1027J-1096D01*
G03X97973I273J292D01*
G02X99923Y235265I1027J-1096D01*
G03Y234635I246J-315D01*
G02Y232265I-923J-1185D01*
G03Y231635I246J-315D01*
G02Y229265I-923J-1185D01*
G03Y228635I246J-315D01*
G02X97973Y226354I-923J-1185D01*
G03X97427I-273J-292D01*
G02X95373I-1027J1096D01*
G03X94827I-273J-292D01*
G02X92773I-1027J1096D01*
G03X92227I-273J-292D01*
G02X90173I-1027J1096D01*
G37*
G36*
G01X703380Y225694D02*
G03X702770I-305J-259D01*
G02Y227506I-1070J906D01*
G03X703380I305J259D01*
G02Y225694I1070J-906D01*
G37*
G36*
G01X1253531Y228169D02*
G03X1253880Y227627I374J-143D01*
G02X1252796Y225241I-89J-1399D01*
G03X1252264Y225273I-284J-282D01*
G02X1250295Y225504I-869J1100D01*
G03X1249691Y225531I-314J-248D01*
G02X1249772Y227363I-1019J963D01*
G03X1250376Y227336I314J248D01*
G02X1250745Y227615I1018J-963D01*
G03X1250929Y228125I-185J355D01*
G02X1253531Y228169I1292J543D01*
G37*
G36*
G01X1945635Y227689D02*
G03X1945738Y227143I334J-220D01*
G02X1943753Y226770I-813J-1142D01*
G03X1943650Y227316I-334J220D01*
G02X1945635Y227689I813J1142D01*
G37*
G36*
G01X1627679Y224282D02*
G03X1627124Y224267I-270J-295D01*
G02X1627069Y226286I-1000J983D01*
G03X1627624Y226301I270J295D01*
G02X1627679Y224282I1000J-983D01*
G37*
G36*
G01X1883427Y223090D02*
G03X1882873I-277J-288D01*
G02Y225110I-973J1010D01*
G03X1883427I277J288D01*
G02Y223090I973J-1010D01*
G37*
G36*
G01X1401311Y222717D02*
G03X1400689I-311J-252D01*
G02Y224483I-1089J883D01*
G03X1401311I311J252D01*
G02Y222717I1089J-883D01*
G37*
G36*
G01X1622167Y224930D02*
G03Y224372I286J-279D01*
G02X1620161I-1003J-980D01*
G03Y224930I-286J279D01*
G02X1622167I1003J980D01*
G37*
G36*
G01X1245144Y223407D02*
G03X1244700Y223029I-44J-398D01*
G02X1243456Y224493I-1400J71D01*
G03X1243900Y224871I44J398D01*
G02X1245144Y223407I1400J-71D01*
G37*
G36*
G01X767662Y224140D02*
G03X767640Y223563I266J-299D01*
G02X765702Y223638I-1008J-974D01*
G03X765724Y224215I-266J299D01*
G02X767662Y224140I1008J974D01*
G37*
G36*
G01X638097Y223710D02*
G03Y223164I292J-273D01*
G02X635905I-1096J-1027D01*
G03Y223710I-292J273D01*
G02Y225764I1096J1027D01*
G03Y226310I-292J273D01*
G02Y228364I1096J1027D01*
G03Y228910I-292J273D01*
G02X638097I1096J1027D01*
G03Y228364I292J-273D01*
G02Y226310I-1096J-1027D01*
G03Y225764I292J-273D01*
G02Y223710I-1096J-1027D01*
G37*
G36*
G01X714708Y223170D02*
G03X714730Y222593I288J-278D01*
G02X712792Y222518I-930J-1049D01*
G03X712770Y223095I-288J278D01*
G02X714708Y223170I930J1049D01*
G37*
G36*
G01X115652Y224178D02*
G03X115823Y224709I-187J353D01*
G02X117738Y224092I1257J621D01*
G03X117567Y223561I187J-353D01*
G02X117707Y222824I-1257J-621D01*
G03X118084Y222391I399J-34D01*
G02X116611Y221107I-76J-1400D01*
G03X116234Y221540I-399J34D01*
G02X115652Y224178I76J1400D01*
G37*
G36*
G01X1911301Y222317D02*
G03X1911312Y221751I288J-278D01*
G02X1909279Y221657I-972J-1010D01*
G03X1909237Y222221I-303J261D01*
G02X1909148Y224412I982J1137D01*
G03X1909135Y224986I-285J281D01*
G02X1911224Y225036I1019J1104D01*
G03X1911237Y224462I285J-281D01*
G02X1911301Y222317I-1018J-1104D01*
G37*
G36*
G01X1627988Y218701D02*
G03X1628578Y218690I300J264D01*
G02X1628542Y216799I1017J-965D01*
G03X1627952Y216810I-300J-264D01*
G02X1627988Y218701I-1017J965D01*
G37*
G36*
G01X94077Y218891D02*
G03X94053Y219509I-266J299D01*
G02X93755Y219794I1088J1436D01*
G03X93150Y219805I-307J-256D01*
G02X90389Y219899I-1341J1204D01*
G03X89779Y219922I-315J-247D01*
G02X87038Y220013I-1332J1214D01*
G03X86446Y220050I-313J-249D01*
G02X86597Y222464I-1258J1290D01*
G03X87189Y222427I313J249D01*
G02X89867Y222246I1258J-1291D01*
G03X90477Y222223I315J247D01*
G02X93194Y222161I1332J-1214D01*
G03X93799Y222150I307J256D01*
G02X96338Y219600I1341J-1204D01*
G03X96362Y218982I266J-299D01*
G02X94077Y218891I-1087J-1437D01*
G37*
G36*
G01X1592264Y213948D02*
G03X1591703Y213814I-216J-337D01*
G02X1589500Y215513I-1208J711D01*
G03X1589507Y216069I-284J282D01*
G02X1590941Y218372I1018J964D01*
G03X1591421Y218583I118J382D01*
G02X1593973Y216738I1449J-683D01*
G03X1593975Y216155I275J-291D01*
G02X1592264Y213948I-955J-1026D01*
G37*
G36*
G01X1898421Y215540D02*
G03Y214962I277J-289D01*
G02X1896479I-971J-1011D01*
G03Y215540I-277J289D01*
G02X1898421I971J1011D01*
G37*
G36*
G01X1612670Y215183D02*
G03Y214574I260J-305D01*
G02X1610852I-909J-1067D01*
G03Y215183I-260J304D01*
G02X1612670I909J1067D01*
G37*
G36*
G01X715613Y215122D02*
G03X715771Y214575I349J-196D01*
G02X713878Y214031I-671J-1231D01*
G03X713720Y214578I-349J196D01*
G02X714134Y217187I671J1231D01*
G03X714431Y217733I-73J393D01*
G02X715984Y216889I1296J534D01*
G03X715687Y216343I73J-393D01*
G02X715613Y215122I-1296J-534D01*
G37*
G36*
G01X591383Y214711D02*
G03Y214089I252J-311D01*
G02X589617I-883J-1089D01*
G03Y214711I-252J311D01*
G02X591383I883J1089D01*
G37*
G36*
G01X824103Y213363D02*
G03X823732Y212838I9J-400D01*
G02X821128Y212989I-1332J-438D01*
G03X820912Y213529I-363J168D01*
G02X820541Y216108I554J1396D01*
G03X820606Y216674I-247J315D01*
G02X822886Y218628I1169J943D01*
G03X823448Y218598I296J269D01*
G02X825597Y218441I998J-1122D01*
G03X826202Y218431I307J257D01*
G02X828681Y216791I1120J-1001D01*
G03X829103Y216225I362J-170D01*
G02X830487Y215694I224J-1485D01*
G03X831107Y215697I309J254D01*
G02X831116Y213800I1169J-943D01*
G03X830496Y213797I-309J-254D01*
G02X828264Y213679I-1169J943D01*
G03X827712Y213692I-283J-283D01*
G02X825636Y213742I-1012J1110D01*
G03X825084Y213755I-283J-283D01*
G02X824103Y213363I-1012J1110D01*
G37*
G36*
G01X1814125Y210720D02*
X1809125D01*
G02Y213742I0J1511D01*
G01X1814126D01*
G02X1815636Y212241I-1J-1511D01*
G01Y212146D01*
X1815627Y212062D01*
G02X1814125Y210720I-1502J169D01*
G37*
G36*
G01X1801526D02*
X1796526D01*
G02Y213742I0J1511D01*
G01X1801527D01*
G02X1803038Y212241I0J-1512D01*
G01Y212146D01*
X1803028Y212062D01*
G02X1801526Y210720I-1502J169D01*
G37*
G36*
G01X1826685Y210650D02*
X1821685D01*
G02Y213672I0J1511D01*
G01X1826686D01*
G02X1828196Y212171I-1J-1511D01*
G01Y212076D01*
X1828187Y211992D01*
G02X1826685Y210650I-1502J169D01*
G37*
G36*
G01X778862Y211127D02*
G03X778252I-305J-259D01*
G02Y212939I-1070J906D01*
G03X778862I305J259D01*
G02Y211127I1070J-906D01*
G37*
G36*
G01X129393Y210985D02*
G03X128822Y210945I-266J-299D01*
G02X128685Y212901I-1068J908D01*
G03X129256Y212941I266J299D01*
G02X129393Y210985I1068J-908D01*
G37*
G36*
G01X1788925Y210120D02*
X1783925D01*
G02Y213142I0J1511D01*
G01X1788926D01*
G02X1790436Y211641I-1J-1511D01*
G01Y211546D01*
X1790427Y211462D01*
G02X1788925Y210120I-1502J169D01*
G37*
G36*
G01X1776325D02*
X1771325D01*
G02Y213142I0J1511D01*
G01X1776326D01*
G02X1777836Y211641I-1J-1511D01*
G01Y211546D01*
X1777827Y211462D01*
G02X1776325Y210120I-1502J169D01*
G37*
G36*
G01X1763725D02*
X1758725D01*
G02Y213142I0J1511D01*
G01X1763726D01*
G02X1765236Y211641I-1J-1511D01*
G01Y211546D01*
X1765227Y211462D01*
G02X1763725Y210120I-1502J169D01*
G37*
G36*
G01X1751125D02*
X1746125D01*
G02Y213142I0J1511D01*
G01X1751126D01*
G02X1752636Y211641I-1J-1511D01*
G01Y211546D01*
X1752627Y211462D01*
G02X1751125Y210120I-1502J169D01*
G37*
G36*
G01X1738484D02*
X1733484D01*
G02Y213142I0J1511D01*
G01X1738485D01*
G02X1739996Y211641I0J-1512D01*
G01Y211546D01*
X1739986Y211462D01*
G02X1738484Y210120I-1502J169D01*
G37*
G36*
G01X1863263Y210799D02*
G03X1862670Y210713I-259J-305D01*
G02X1860096Y211423I-1173J768D01*
G03X1859676Y211806I-400J-16D01*
G02X1861005Y213264I-72J1400D01*
G03X1861425Y212881I400J16D01*
G02X1862404Y212551I73J-1400D01*
G03X1862997Y212637I259J305D01*
G02X1863263Y210799I1173J-769D01*
G37*
G36*
G01X1726494Y210283D02*
G03X1725906I-294J-270D01*
G02Y212317I-1106J1017D01*
G03X1726494I294J270D01*
G02Y210283I1106J-1017D01*
G37*
G36*
G01X89628Y210958D02*
G03X89293Y210468I54J-396D01*
G02X85796Y210488I-1751J-425D01*
G03X85362Y210984I-388J99D01*
G02X83439Y213322I-206J1790D01*
G03X83114Y213840I-381J122D01*
G02X85083Y215076I252J1784D01*
G03X85408Y214558I381J-122D01*
G02X85527Y214537I-253J-1784D01*
G03X85753Y214810I41J196D01*
G02X89158Y215043I1663J694D01*
G03X89516Y214541I387J-103D01*
G02X89697Y214519I-127J-1797D01*
G03X89921Y214781I35J197D01*
G02X91562Y213563I1705J583D01*
G03X91155Y213087I-14J-400D01*
G02X89628Y210958I-1769J-343D01*
G37*
G36*
G01X1358537Y208181D02*
G03X1357965Y208159I-275J-290D01*
G02X1357889Y210119I-1039J941D01*
G03X1358461Y210141I275J290D01*
G02X1360432Y210247I1039J-941D01*
G03X1360987Y210269I266J299D01*
G02X1361068Y208253I1013J-969D01*
G03X1360513Y208231I-266J-299D01*
G02X1358537Y208181I-1013J969D01*
G37*
G36*
G01X1227826Y209464D02*
G03X1227844Y208909I297J-268D01*
G02X1225826Y208843I-977J-1005D01*
G03X1225808Y209398I-297J268D01*
G02X1225814Y211414I977J1005D01*
G03Y211992I-277J289D01*
G02X1225978Y214149I971J1011D01*
G03X1226070Y214713I-230J327D01*
G02X1228007Y214397I1130J830D01*
G03X1227915Y213833I230J-327D01*
G02X1227756Y211992I-1130J-830D01*
G03Y211414I277J-289D01*
G02X1227826Y209464I-971J-1011D01*
G37*
G36*
G01X1475934Y208720D02*
G03X1475721Y208189I153J-369D01*
G02X1473906Y208918I-1282J-568D01*
G03X1474119Y209449I-153J369D01*
G02X1475934Y208720I1282J568D01*
G37*
G36*
G01X1479760Y208891D02*
G03X1479846Y208343I328J-229D01*
G02X1477851Y208029I-846J-1118D01*
G03X1477765Y208577I-328J229D01*
G02X1479760Y208891I846J1118D01*
G37*
G36*
G01X617675Y205984D02*
G03X617121I-277J-288D01*
G02Y208004I-973J1010D01*
G03X617675I277J288D01*
G02X617771Y208088I970J-1012D01*
G03Y208400I-125J156D01*
G02X619658Y208521I877J1094D01*
G03Y207967I288J-277D01*
G02X619742Y207871I-1012J-970D01*
G03X620054I156J125D01*
G02X622121Y208004I1094J-877D01*
G03X622675I277J288D01*
G02X622771Y208088I970J-1012D01*
G03Y208400I-125J156D01*
G02X622638Y210467I877J1094D01*
G03Y211021I-288J277D01*
G02X622554Y211117I1012J970D01*
G03X622242I-156J-125D01*
G02X622121Y213004I-1094J877D01*
G03X622675I277J288D01*
G02X622771Y213088I970J-1012D01*
G03Y213400I-125J156D01*
G02X622638Y215467I877J1094D01*
G03Y216021I-288J277D01*
G02X622554Y216117I1012J970D01*
G03X622242I-156J-125D01*
G02X622121Y218004I-1094J877D01*
G03X622675I277J288D01*
G02X622771Y218088I970J-1012D01*
G03Y218400I-125J156D01*
G02X622638Y220467I877J1094D01*
G03Y221021I-288J277D01*
G02X622554Y221117I1012J970D01*
G03X622242I-156J-125D01*
G02X622121Y223004I-1094J877D01*
G03X622675I277J288D01*
G02X622771Y223088I970J-1012D01*
G03Y223400I-125J156D01*
G02X622638Y225467I877J1094D01*
G03Y226021I-288J277D01*
G02X622554Y226117I1012J970D01*
G03X622242I-156J-125D01*
G02X620175Y225984I-1094J877D01*
G03X619621I-277J-288D01*
G02X619525Y225900I-970J1012D01*
G03Y225588I125J-156D01*
G02X617638Y225467I-877J-1094D01*
G03Y226021I-288J277D01*
G02X617554Y226117I1012J970D01*
G03X617242I-156J-125D01*
G02X615175Y225984I-1094J877D01*
G03X614621I-277J-288D01*
G02X614525Y225900I-970J1012D01*
G03Y225588I125J-156D01*
G02X614658Y223521I-877J-1094D01*
G03Y222967I288J-277D01*
G02X614742Y222871I-1012J-970D01*
G03X615054I156J125D01*
G02X615175Y220984I1094J-877D01*
G03X614621I-277J-288D01*
G02X614525Y220900I-970J1012D01*
G03Y220588I125J-156D01*
G02X614658Y218521I-877J-1094D01*
G03Y217967I288J-277D01*
G02X614742Y217871I-1012J-970D01*
G03X615054I156J125D01*
G02X615175Y215984I1094J-877D01*
G03X614621I-277J-288D01*
G02X614525Y215900I-970J1012D01*
G03Y215588I125J-156D01*
G02X614658Y213521I-877J-1094D01*
G03Y212967I288J-277D01*
G02X614742Y212871I-1012J-970D01*
G03X615054I156J125D01*
G02X615175Y210984I1094J-877D01*
G03X614621I-277J-288D01*
G02X614525Y210900I-970J1012D01*
G03Y210588I125J-156D01*
G02X612638Y210467I-877J-1094D01*
G03Y211021I-288J277D01*
G02Y212967I1010J973D01*
G03Y213521I-288J277D01*
G02Y215467I1010J973D01*
G03Y216021I-288J277D01*
G02Y217967I1010J973D01*
G03Y218521I-288J277D01*
G02Y220467I1010J973D01*
G03Y221021I-288J277D01*
G02X612554Y221117I1012J970D01*
G03X612242I-156J-125D01*
G02X610138Y222967I-1094J877D01*
G03Y223521I-288J277D01*
G02X610054Y223617I1012J970D01*
G03X609742I-156J-125D01*
G02X607638Y225467I-1094J877D01*
G03Y226021I-288J277D01*
G02X609658I1010J973D01*
G03Y225467I288J-277D01*
G02X609742Y225371I-1012J-970D01*
G03X610054I156J125D01*
G02X612121Y225504I1094J-877D01*
G03X612675I277J288D01*
G02X612771Y225588I970J-1012D01*
G03Y225900I-125J156D01*
G02X612638Y227967I877J1094D01*
G03Y228521I-288J277D01*
G02X612554Y228617I1012J970D01*
G03X612242I-156J-125D01*
G02X612121Y230504I-1094J877D01*
G03X612675I277J288D01*
G02X614658Y228521I973J-1010D01*
G03Y227967I288J-277D01*
G02X614742Y227871I-1012J-970D01*
G03X615054I156J125D01*
G02X617121Y228004I1094J-877D01*
G03X617675I277J288D01*
G02X617771Y228088I970J-1012D01*
G03Y228400I-125J156D01*
G02X619621Y230504I877J1094D01*
G03X620175I277J288D01*
G02X622158Y228521I973J-1010D01*
G03Y227967I288J-277D01*
G02X622242Y227871I-1012J-970D01*
G03X622554I156J125D01*
G02X624658Y226021I1094J-877D01*
G03Y225467I288J-277D01*
G02Y223521I-1010J-973D01*
G03Y222967I288J-277D01*
G02Y221021I-1010J-973D01*
G03Y220467I288J-277D01*
G02Y218521I-1010J-973D01*
G03Y217967I288J-277D01*
G02Y216021I-1010J-973D01*
G03Y215467I288J-277D01*
G02Y213521I-1010J-973D01*
G03Y212967I288J-277D01*
G02Y211021I-1010J-973D01*
G03Y210467I288J-277D01*
G02Y208521I-1010J-973D01*
G03Y207967I288J-277D01*
G02X622675Y205984I-1010J-973D01*
G03X622121I-277J-288D01*
G02X620175I-973J1010D01*
G03X619621I-277J-288D01*
G02X617675I-973J1010D01*
G37*
G36*
G01X1856789Y207274D02*
G03X1857411Y207253I319J241D01*
G02X1857351Y205491I1059J-918D01*
G03X1856729Y205512I-319J-241D01*
G02X1856789Y207274I-1059J918D01*
G37*
G36*
G01X1222271Y206989D02*
G03Y206411I277J-289D01*
G02X1220329I-971J-1011D01*
G03Y206989I-277J289D01*
G02X1222271I971J1011D01*
G37*
G36*
G01X1517619Y204557D02*
G03X1517615Y204002I286J-280D01*
G02X1515595Y204017I-1017J-965D01*
G03X1515599Y204572I-286J280D01*
G02X1517619Y204557I1017J965D01*
G37*
G36*
G01X708189Y200329D02*
G03X707611I-289J-277D01*
G02X705762Y202424I-1011J971D01*
G03X705753Y203071I-240J320D01*
G02X707678Y205064I808J1146D01*
G03X708260Y205004I319J241D01*
G02X710479Y204479I922J-1056D01*
G03X711061Y204291I370J152D01*
G02X711171Y201847I739J-1191D01*
G03X710594Y201447I-179J-358D01*
G02X708189Y200329I-1394J-147D01*
G37*
G36*
G01X1884247Y201333D02*
G03X1884271Y201009I128J-153D01*
G02X1882499Y200753I-732J-1196D01*
G03X1882457Y201329I-297J268D01*
G02X1884491Y203224I893J1081D01*
G03X1885100Y203174I326J232D01*
G02X1884952Y201370I993J-990D01*
G03X1884343Y201420I-326J-232D01*
G02X1884247Y201333I-988J994D01*
G37*
G36*
G01X1227471Y201389D02*
G03Y200811I277J-289D01*
G02X1225529I-971J-1011D01*
G03Y201389I-277J289D01*
G02X1227471I971J1011D01*
G37*
G36*
G01X1546924Y199009D02*
G03X1546944Y198437I289J-276D01*
G02X1544986Y198368I-944J-1037D01*
G03X1544966Y198940I-289J276D01*
G02X1546924Y199009I944J1037D01*
G37*
G36*
G01X1763668Y195332D02*
X1758668D01*
G02Y198354I0J1511D01*
G01X1763669D01*
G02X1765180Y196853I0J-1512D01*
G01Y196758D01*
X1765170Y196674D01*
G02X1763668Y195332I-1502J169D01*
G37*
G36*
G01X1751082D02*
X1746082D01*
G02Y198354I0J1511D01*
G01X1751083D01*
G02X1752594Y196853I0J-1512D01*
G01Y196758D01*
X1752584Y196674D01*
G02X1751082Y195332I-1502J169D01*
G37*
G36*
G01X1826682Y195330D02*
X1821682D01*
G02Y198352I0J1511D01*
G01X1826683D01*
G02X1828194Y196851I0J-1512D01*
G01Y196756D01*
X1828184Y196672D01*
G02X1826682Y195330I-1502J169D01*
G37*
G36*
G01X1814041D02*
X1809041D01*
G02Y198352I0J1511D01*
G01X1814042D01*
G02X1815552Y196851I-1J-1511D01*
G01Y196756D01*
X1815543Y196672D01*
G02X1814041Y195330I-1502J169D01*
G37*
G36*
G01X1801441D02*
X1796441D01*
G02Y198352I0J1511D01*
G01X1801442D01*
G02X1802952Y196851I-1J-1511D01*
G01Y196756D01*
X1802943Y196672D01*
G02X1801441Y195330I-1502J169D01*
G37*
G36*
G01X1788841D02*
X1783841D01*
G02Y198352I0J1511D01*
G01X1788842D01*
G02X1790352Y196851I-1J-1511D01*
G01Y196756D01*
X1790343Y196672D01*
G02X1788841Y195330I-1502J169D01*
G37*
G36*
G01X1776241D02*
X1771241D01*
G02Y198352I0J1511D01*
G01X1776242D01*
G02X1777752Y196851I-1J-1511D01*
G01Y196756D01*
X1777743Y196672D01*
G02X1776241Y195330I-1502J169D01*
G37*
G36*
G01X720641Y196447D02*
G03X721181Y196442I273J293D01*
G02X721162Y194373I936J-1043D01*
G03X720622Y194378I-273J-293D01*
G02X720641Y196447I-936J1043D01*
G37*
G36*
G01X1638880Y196604D02*
G03Y196050I288J-277D01*
G02X1636860I-1010J-973D01*
G03Y196604I-288J277D01*
G02X1638880I1010J973D01*
G37*
G36*
G01X1708794Y193293D02*
G02X1712894Y191735I3218J2294D01*
G02X1708794Y193293I-882J3852D01*
G37*
G36*
G01X1209145Y193611D02*
G03X1209161Y194233I-243J317D01*
G02X1210925Y194189I909J1067D01*
G03X1210909Y193567I243J-317D01*
G02X1209145Y193611I-909J-1067D01*
G37*
G36*
G01X1621217Y184110D02*
G03X1620607Y184084I-294J-271D01*
G02X1620531Y185894I-1107J860D01*
G03X1621141Y185920I294J271D01*
G02X1621217Y184110I1107J-860D01*
G37*
G36*
G01X1609625Y183827D02*
G03X1609071Y183803I-265J-300D01*
G02X1608985Y185821I-1015J968D01*
G03X1609539Y185845I265J300D01*
G02X1611497Y185914I1014J-968D01*
G03X1612052Y185930I269J296D01*
G02X1614042Y185943I1001J-981D01*
G03X1614597Y185934I282J283D01*
G02X1614564Y183914I956J-1026D01*
G03X1614009Y183923I-282J-283D01*
G02X1612110Y183912I-955J1026D01*
G03X1611555Y183896I-269J-296D01*
G02X1609625Y183827I-1001J981D01*
G37*
G36*
G01X1682294Y182678D02*
G03X1681795Y182531I-164J-365D01*
G02X1679261Y184475I-1345J870D01*
G03X1679252Y184752I-148J134D01*
G02X1681967Y186024I1118J1148D01*
G03X1682483Y185672I399J31D01*
G02X1682294Y182678I467J-1532D01*
G37*
G36*
G01X1656005Y183496D02*
G03X1656044Y182887I277J-288D01*
G02X1654235Y182770I-835J-1126D01*
G03X1654196Y183379I-277J288D01*
G02X1656005Y183496I835J1126D01*
G37*
G36*
G01X1493491Y178427D02*
G03X1493498Y177872I291J-274D01*
G02X1491478Y177847I-998J-985D01*
G03X1491471Y178402I-291J274D01*
G02X1493491Y178427I998J985D01*
G37*
G36*
G01X1615377Y178062D02*
G03X1615891Y177756I393J75D01*
G02X1615021Y176207I395J-1241D01*
G03X1614492Y176487I-389J-94D01*
G02X1615377Y178062I-492J1313D01*
G37*
G36*
G01X1820382Y175014D02*
X1815382D01*
G02Y178036I0J1511D01*
G01X1820383D01*
G02X1821894Y176535I0J-1512D01*
G01Y176440D01*
X1821884Y176356D01*
G02X1820382Y175014I-1502J169D01*
G37*
G36*
G01X1807784D02*
X1802784D01*
G02Y178036I0J1511D01*
G01X1807785D01*
G02X1809296Y176535I0J-1512D01*
G01Y176440D01*
X1809286Y176356D01*
G02X1807784Y175014I-1502J169D01*
G37*
G36*
G01X1795185D02*
X1790185D01*
G02Y178036I0J1511D01*
G01X1795185D01*
G02X1796696Y176535I0J-1511D01*
G01Y176440D01*
X1796687Y176356D01*
G02X1795185Y175014I-1502J169D01*
G37*
G36*
G01X1782587D02*
X1777587D01*
G02Y178036I0J1511D01*
G01X1782588D01*
G02X1784098Y176535I-1J-1511D01*
G01Y176440D01*
X1784089Y176356D01*
G02X1782587Y175014I-1502J169D01*
G37*
G36*
G01X1764988Y178036D02*
X1769989D01*
G02X1771500Y176535I0J-1512D01*
G01Y176440D01*
X1771490Y176356D01*
G02X1769988Y175014I-1502J169D01*
G01X1764987D01*
G02X1764988Y178036I1J1511D01*
G37*
G36*
G01X1739792D02*
X1744793D01*
G02X1746304Y176535I0J-1512D01*
G01Y176440D01*
X1746294Y176356D01*
G02X1744792Y175014I-1502J169D01*
G01X1739792D01*
G02Y178036I1J1511D01*
G37*
G36*
G01X1732193Y175014D02*
X1727193D01*
G02Y178036I1J1511D01*
G01X1732193D01*
G02X1733704Y176535I0J-1511D01*
G01Y176440D01*
X1733695Y176356D01*
G02X1732193Y175014I-1502J169D01*
G37*
G36*
G01X1254266Y174954D02*
G03X1253734I-266J-298D01*
G02Y177046I-934J1046D01*
G03X1254266I266J298D01*
G02Y174954I934J-1046D01*
G37*
G36*
G01X1856427Y174890D02*
G03X1855873I-277J-288D01*
G02Y176910I-973J1010D01*
G03X1856427I277J288D01*
G02Y174890I973J-1010D01*
G37*
G36*
G01X1876467Y175734D02*
G03X1876859Y175321I400J-13D01*
G02X1875431Y173967I-27J-1402D01*
G03X1875039Y174380I-400J13D01*
G02X1876467Y175734I27J1402D01*
G37*
G36*
G01X1472924Y172703D02*
G03X1472369Y172698I-275J-290D01*
G02X1472352Y174718I-981J1002D01*
G03X1472907Y174723I275J290D01*
G02X1472924Y172703I981J-1002D01*
G37*
G36*
G01X1245937Y172140D02*
G03X1245383I-277J-288D01*
G02X1243022Y173350I-973J1010D01*
G03X1242665Y173805I-396J57D01*
G02X1244188Y175000I135J1395D01*
G03X1244545Y174545I396J-57D01*
G02X1245383Y174160I-134J-1396D01*
G03X1245937I277J288D01*
G02Y172140I973J-1010D01*
G37*
G36*
G01X1614863Y174222D02*
G03X1615392Y173999I373J145D01*
G02X1614687Y172328I508J-1199D01*
G03X1614158Y172551I-373J-145D01*
G02X1613179Y172536I-508J1199D01*
G03X1612674Y172336I-144J-373D01*
G02X1610429Y172159I-1174J564D01*
G03X1609894Y172274I-329J-228D01*
G02X1610293Y174130I-672J1115D01*
G03X1610828Y174015I329J228D01*
G02X1611971Y174114I672J-1115D01*
G03X1612476Y174314I144J373D01*
G02X1614863Y174222I1174J-564D01*
G37*
G36*
G01X1596648Y171344D02*
G03X1596036I-306J-258D01*
G02Y173024I-994J840D01*
G03X1596648I306J258D01*
G02Y171344I994J-840D01*
G37*
G36*
G01X1887371Y171589D02*
G03Y171011I277J-289D01*
G02X1885429I-971J-1011D01*
G03Y171589I-277J289D01*
G02X1887371I971J1011D01*
G37*
G36*
G01X1701968Y162401D02*
G03X1702523Y162390I283J283D01*
G02X1702478Y160081I1087J-1176D01*
G03X1701923Y160092I-283J-283D01*
G02X1701968Y162401I-1087J1176D01*
G37*
G36*
G01X1840909Y158413D02*
G03X1840924Y157858I295J-270D01*
G02X1838905Y157803I-983J-1000D01*
G03X1838890Y158358I-295J270D01*
G02X1840909Y158413I983J1000D01*
G37*
G36*
G01X1531912Y157489D02*
G03X1532143Y156930I358J-179D01*
G02X1530362Y155182I-443J-1330D01*
G03X1529807Y155424I-382J-119D01*
G02X1531912Y157489I-1963J4107D01*
G37*
G36*
G01X20473Y158250D02*
G03X21740Y158653I-2J2199D01*
G02X21756Y154015I1488J-2314D01*
G03X20502Y154428I-1283J-1786D01*
G01X20471D01*
G03X19204Y154025I2J-2199D01*
G02X19188Y158663I-1488J2314D01*
G03X20442Y158250I1283J1786D01*
G01X20473D01*
G37*
G36*
G01X3938D02*
G03X5205Y158653I-2J2199D01*
G02X5221Y154015I1488J-2314D01*
G03X3967Y154428I-1283J-1786D01*
G01X3936D01*
G03X2669Y154025I2J-2199D01*
G02X2653Y158663I-1488J2314D01*
G03X3907Y158250I1283J1786D01*
G01X3938D01*
G37*
G36*
G01X-12598D02*
G03X-11331Y158653I-2J2199D01*
G02X-11315Y154015I1488J-2314D01*
G03X-12569Y154428I-1283J-1786D01*
G01X-12599D01*
G03X-13866Y154025I2J-2199D01*
G02X-13882Y158663I-1488J2314D01*
G03X-12628Y158250I1283J1786D01*
G01X-12598D01*
G37*
G36*
G01X51309Y152844D02*
X47309D01*
G02Y155868I0J1512D01*
G01X51310D01*
G02X52820Y154366I-1J-1512D01*
G01Y154271D01*
X52811Y154187D01*
G02X51309Y152844I-1502J168D01*
G37*
G36*
G01X1788818Y155649D02*
G03X1789375Y155428I376J136D01*
G02X1788550Y153595I725J-1428D01*
G03X1788016Y153866I-387J-101D01*
G02X1788818Y155649I-516J1304D01*
G37*
G36*
G01X1700076Y154255D02*
G03X1700357Y154249I144J140D01*
G02X1700306Y151967I1098J-1166D01*
G03X1700025Y151973I-144J-140D01*
G02X1700076Y154255I-1098J1166D01*
G37*
G36*
G01X1876493Y153833D02*
G03X1877086Y153815I305J259D01*
G02X1877028Y151935I1010J-972D01*
G03X1876435Y151953I-305J-259D01*
G02X1876493Y153833I-1010J972D01*
G37*
G36*
G01X1913160Y153727D02*
G03X1913765Y153634I342J208D01*
G02X1913491Y151853I925J-1054D01*
G03X1912886Y151946I-342J-208D01*
G02X1913160Y153727I-925J1054D01*
G37*
G36*
G01X1514888Y153600D02*
G03X1515300Y153144I396J-57D01*
G02X1513970Y151943I58J-1401D01*
G03X1513558Y152399I-396J57D01*
G02X1514888Y153600I-58J1401D01*
G37*
G36*
G01X1885299Y154911D02*
G03X1885233Y155526I-285J280D01*
G02X1887000Y155717I767J1174D01*
G03X1887066Y155102I285J-280D01*
G02X1887203Y152857I-767J-1173D01*
G03X1887148Y152303I258J-305D01*
G02X1885146Y152502I-1098J-872D01*
G03X1885201Y153056I-258J305D01*
G02X1885299Y154911I1098J872D01*
G37*
G36*
G01X68098Y149962D02*
X63098D01*
G02Y152984I0J1511D01*
G01X68099D01*
G02X69610Y151483I0J-1512D01*
G01Y151388D01*
X69600Y151304D01*
G02X68098Y149962I-1502J169D01*
G37*
G36*
G01X1265136Y151576D02*
G03X1265691Y151567I282J284D01*
G02X1265656Y149548I955J-1026D01*
G03X1265101Y149557I-282J-284D01*
G02X1263135Y149613I-955J1027D01*
G03X1262557I-289J-277D01*
G02Y151555I-1011J971D01*
G03X1263135I289J277D01*
G02X1265136Y151576I1011J-971D01*
G37*
G36*
G01X1574971Y151089D02*
G03Y150511I277J-289D01*
G02X1573029I-971J-1011D01*
G03Y151089I-277J289D01*
G02X1574971I971J1011D01*
G37*
G36*
G01X1945607Y150725D02*
G03X1945609Y150166I287J-278D01*
G02X1943602Y150159I-1000J-982D01*
G03X1943600Y150718I-287J278D01*
G02X1945607Y150725I1000J982D01*
G37*
G36*
G01X1295155Y148431D02*
G03X1294732Y148064I-24J-400D01*
G02X1291935Y148249I-1397J113D01*
G03X1291580Y148668I-400J21D01*
G02X1291742Y151463I156J1393D01*
G03X1292143Y151839I2J400D01*
G02X1292145Y151862I1398J-110D01*
G03X1291752Y152292I-399J30D01*
G02X1293170Y153588I20J1402D01*
G03X1293563Y153158I399J-30D01*
G02X1293594Y153157I-30J-1402D01*
G03X1293797Y153396I7J200D01*
G02X1295303Y152274I1375J274D01*
G03X1294942Y151849I38J-398D01*
G02Y151657I-1399J-96D01*
G03X1295318Y151230I399J-28D01*
G02X1295155Y148431I-78J-1400D01*
G37*
G36*
G01X1496967Y149755D02*
G03X1497034Y149203I319J-241D01*
G02X1495031Y148960I-884J-1088D01*
G03X1494964Y149512I-319J241D01*
G02X1496967Y149755I884J1088D01*
G37*
G36*
G01X1964194Y149150D02*
G03X1964545Y148710I398J-43D01*
G02X1962988Y147468I-163J-1392D01*
G03X1962637Y147908I-398J43D01*
G02X1964194Y149150I163J1392D01*
G37*
G36*
G01X25591Y150376D02*
G03X26858Y150779I-2J2199D01*
G02X26874Y146141I1488J-2314D01*
G03X25620Y146554I-1283J-1786D01*
G01X25590D01*
G03X24323Y146151I2J-2199D01*
G02X24307Y150789I-1488J2314D01*
G03X25561Y150376I1283J1786D01*
G01X25591D01*
G37*
G36*
G01X9056D02*
G03X10323Y150779I-2J2199D01*
G02X10339Y146141I1488J-2314D01*
G03X9085Y146554I-1283J-1786D01*
G01X9054D01*
G03X7787Y146151I2J-2199D01*
G02X7771Y150789I-1488J2314D01*
G03X9025Y150376I1283J1786D01*
G01X9056D01*
G37*
G36*
G01X-7480D02*
G03X-6213Y150779I-2J2199D01*
G02X-6197Y146141I1488J-2314D01*
G03X-7451Y146554I-1283J-1786D01*
G01X-7481D01*
G03X-8748Y146151I2J-2199D01*
G02X-8764Y150789I-1488J2314D01*
G03X-7510Y150376I1283J1786D01*
G01X-7480D01*
G37*
G36*
G01X1278933Y147438D02*
G03X1278927Y146832I258J-306D01*
G02X1277097Y146852I-927J-1052D01*
G03X1277103Y147458I-258J306D01*
G02X1278933Y147438I927J1052D01*
G37*
G36*
G01X1490661Y145218D02*
G03X1490195Y144863I-68J-394D01*
G02X1489039Y146382I-1395J138D01*
G03X1489505Y146737I68J394D01*
G02X1490661Y145218I1395J-138D01*
G37*
G36*
G01X1533237Y146370D02*
G03X1533446Y145819I358J-180D01*
G02X1531671Y145148I-523J-1301D01*
G03X1531462Y145699I-358J180D01*
G02X1533237Y146370I523J1301D01*
G37*
G36*
G01X1849616Y143180D02*
G03X1849627Y142581I270J-295D01*
G02X1847506Y142540I-1037J-1221D01*
G03X1847495Y143139I-270J295D01*
G02X1849616Y143180I1037J1221D01*
G37*
G36*
G01X1267743Y140626D02*
G03X1267208Y140322I-141J-375D01*
G02X1266321Y141880I-1380J246D01*
G03X1266856Y142184I141J375D01*
G02X1267743Y140626I1380J-246D01*
G37*
G36*
G01X48412Y144760D02*
Y139665D01*
X48402Y139581D01*
G02X45388Y139750I-1502J169D01*
G01Y144750D01*
G02X48412Y144760I1512J0D01*
G37*
G36*
G01X3938Y142502D02*
G03X5205Y142905I-2J2199D01*
G02X5221Y138267I1488J-2314D01*
G03X3967Y138680I-1283J-1786D01*
G01X3936D01*
G03X2669Y138277I2J-2199D01*
G02X2653Y142915I-1488J2314D01*
G03X3907Y142502I1283J1786D01*
G01X3938D01*
G37*
G36*
G01X-12598D02*
G03X-11331Y142905I-2J2199D01*
G02X-11315Y138267I1488J-2314D01*
G03X-12569Y138680I-1283J-1786D01*
G01X-12599D01*
G03X-13866Y138277I2J-2199D01*
G02X-13882Y142915I-1488J2314D01*
G03X-12628Y142502I1283J1786D01*
G01X-12598D01*
G37*
G36*
G01X1452354Y140426D02*
G03X1452435Y139869I322J-238D01*
G02X1450464Y139585I-845J-1119D01*
G03X1450383Y140142I-322J238D01*
G02X1450207Y142221I845J1118D01*
G03X1450200Y142776I-292J274D01*
G02X1450259Y144802I998J985D01*
G03X1450267Y145389I-268J297D01*
G02X1452172Y145364I966J1016D01*
G03X1452164Y144777I268J-297D01*
G02X1452219Y142801I-966J-1016D01*
G03X1452226Y142246I292J-274D01*
G02X1452354Y140426I-998J-985D01*
G37*
G36*
G01X1856050Y137539D02*
G03X1855450I-300J-265D01*
G02Y139661I-1200J1061D01*
G03X1856050I300J265D01*
G02Y137539I1200J-1061D01*
G37*
G36*
G01X1846743Y136086D02*
G03X1847327Y135919I364J167D01*
G02X1846826Y134164I773J-1170D01*
G03X1846242Y134331I-364J-167D01*
G02X1846743Y136086I-773J1170D01*
G37*
G36*
G01X67198Y137760D02*
Y132665D01*
X67189Y132581D01*
G02X64176Y132750I-1502J169D01*
G01Y137750D01*
G02X67198Y137760I1511J0D01*
G37*
G36*
G01X53080D02*
Y132665D01*
X53071Y132581D01*
G02X50058Y132750I-1502J169D01*
G01Y137751D01*
G02X53080Y137760I1511J-1D01*
G37*
G36*
G01X1920235Y133456D02*
G03X1920306Y132858I297J-268D01*
G02X1918474Y132641I-792J-1157D01*
G03X1918403Y133239I-297J268D01*
G02X1920235Y133456I792J1157D01*
G37*
G36*
G01X25591Y134628D02*
G03X26858Y135031I-2J2199D01*
G02X26874Y130393I1488J-2314D01*
G03X25620Y130806I-1283J-1786D01*
G01X25590D01*
G03X24323Y130403I2J-2199D01*
G02X24307Y135041I-1488J2314D01*
G03X25561Y134628I1283J1786D01*
G01X25591D01*
G37*
G36*
G01X1855539Y132335D02*
G03X1855351Y131782I165J-364D01*
G02X1853538Y132399I-1236J-661D01*
G03X1853726Y132952I-165J364D01*
G02X1855539Y132335I1236J661D01*
G37*
G36*
G01X1580308Y130140D02*
G03X1580312Y129585I290J-275D01*
G02X1578292Y129568I-1002J-981D01*
G03X1578288Y130123I-290J275D01*
G02X1580308Y130140I1002J981D01*
G37*
G36*
G01X1469569Y130197D02*
G03X1469606Y129592I279J-287D01*
G02X1467776Y129481I-851J-1114D01*
G03X1467739Y130086I-279J287D01*
G02X1469569Y130197I851J1114D01*
G37*
G36*
G01X1920681Y127497D02*
G03Y126924I279J-287D01*
G02X1918723I-979J-1004D01*
G03Y127497I-279J286D01*
G02X1920681I979J1004D01*
G37*
G36*
G01X48412Y130760D02*
Y125665D01*
X48402Y125581D01*
G02X45388Y125750I-1502J169D01*
G01Y130750D01*
G02X48412Y130760I1512J0D01*
G37*
G36*
G01X-12598Y126754D02*
G03X-11331Y127157I-2J2199D01*
G02X-11315Y122519I1488J-2314D01*
G03X-12569Y122932I-1283J-1786D01*
G01X-12599D01*
G03X-13866Y122529I2J-2199D01*
G02X-13882Y127167I-1488J2314D01*
G03X-12628Y126754I1283J1786D01*
G01X-12598D01*
G37*
G36*
G01X1270489Y121529D02*
G03X1269911I-289J-277D01*
G02Y123471I-1011J971D01*
G03X1270489I289J277D01*
G02Y121529I1011J-971D01*
G37*
G36*
G01X1543504Y120435D02*
G03X1543326Y119880I172J-361D01*
G02X1541496Y120465I-1226J-680D01*
G03X1541674Y121020I-172J361D01*
G02X1543504Y120435I1226J680D01*
G37*
G36*
G01X1760020Y118137D02*
G03X1759380I-320J-240D01*
G02Y120063I-1280J963D01*
G03X1760020I320J240D01*
G02Y118137I1280J-963D01*
G37*
G36*
G01X53080Y123760D02*
Y118665D01*
X53071Y118581D01*
G02X50058Y118750I-1502J169D01*
G01Y123751D01*
G02X53080Y123760I1511J-1D01*
G37*
G36*
G01X63894Y123731D02*
G02X66916Y123740I1511J-1D01*
G01Y118730D01*
X66917D01*
X66916Y118645D01*
X66907Y118561D01*
G02X63894Y118730I-1502J169D01*
G01Y123731D01*
G37*
G36*
G01X1474064Y119985D02*
G03X1474087Y119386I276J-289D01*
G02X1472232Y119314I-887J-1086D01*
G03X1472209Y119913I-276J289D01*
G02X1471986Y121856I887J1086D01*
G03X1471854Y122456I-316J245D01*
G02X1473610Y122843I646J1244D01*
G03X1473742Y122243I316J-245D01*
G02X1474064Y119985I-646J-1244D01*
G37*
G36*
G01X1528024Y120779D02*
Y115684D01*
X1528015Y115600D01*
G02X1525002Y115769I-1502J169D01*
G01Y120769D01*
G02X1528024Y120779I1511J0D01*
G37*
G36*
G01X25591Y118880D02*
G03X26858Y119283I-2J2199D01*
G02X26874Y114645I1488J-2314D01*
G03X25620Y115058I-1283J-1786D01*
G01X25590D01*
G03X24323Y114655I2J-2199D01*
G02X24307Y119293I-1488J2314D01*
G03X25561Y118880I1283J1786D01*
G01X25591D01*
G37*
G36*
G01X9054Y115058D02*
G03X7787Y114655I2J-2199D01*
G02X7771Y119293I-1488J2314D01*
G03X9025Y118880I1283J1786D01*
G01X9056D01*
G03X10323Y119283I-2J2199D01*
G02X10339Y114645I1488J-2314D01*
G03X9085Y115058I-1283J-1786D01*
G01X9054D01*
G37*
G36*
G01X1907363Y116972D02*
G03X1907375Y116373I271J-294D01*
G02X1905518Y116337I-908J-1068D01*
G03X1905506Y116936I-271J294D01*
G02X1907363Y116972I908J1068D01*
G37*
G36*
G01X1303475Y113289D02*
G03Y112711I277J-289D01*
G02X1301533I-971J-1011D01*
G03Y113289I-277J289D01*
G02X1301458Y115234I971J1011D01*
G03Y115766I-298J266D01*
G02X1301467Y117644I1046J934D01*
G03X1301472Y118177I-295J269D01*
G02X1303563Y118158I1054J925D01*
G03X1303558Y117625I295J-269D01*
G02X1303550Y115766I-1054J-925D01*
G03Y115234I298J-266D01*
G02X1303475Y113289I-1046J-934D01*
G37*
G36*
G01X62212Y116760D02*
Y111665D01*
X62202Y111581D01*
G02X59242Y111351I-1502J169D01*
G01X59202Y111498D01*
X53698D01*
Y113502D01*
X59188D01*
Y114998D01*
X53698D01*
Y117002D01*
X59202D01*
X59242Y117149D01*
G02X62212Y116760I1458J-398D01*
G37*
G36*
G01X48412D02*
Y111665D01*
X48402Y111581D01*
G02X45388Y111750I-1502J169D01*
G01Y116750D01*
G02X48412Y116760I1512J0D01*
G37*
G36*
G01X1599633Y109786D02*
G03X1599093Y109773I-263J-301D01*
G02X1599047Y111691I-903J938D01*
G03X1599587Y111704I263J301D01*
G02X1599633Y109786I903J-938D01*
G37*
G36*
G01X1188924Y109493D02*
G03X1188929Y108905I274J-292D01*
G02X1187028Y108886I-940J-1040D01*
G03X1187023Y109474I-274J292D01*
G02X1188924Y109493I940J1040D01*
G37*
G36*
G01X1152113D02*
G03X1152118Y108905I274J-292D01*
G02X1150217Y108886I-940J-1040D01*
G03X1150212Y109474I-274J292D01*
G02X1152113Y109493I940J1040D01*
G37*
G36*
G01X934593D02*
G03X934598Y108905I274J-292D01*
G02X932697Y108886I-940J-1040D01*
G03X932692Y109474I-274J292D01*
G02X934593Y109493I940J1040D01*
G37*
G36*
G01X897782D02*
G03X897787Y108905I274J-292D01*
G02X895886Y108886I-940J-1040D01*
G03X895881Y109474I-274J292D01*
G02X897782Y109493I940J1040D01*
G37*
G36*
G01X539316D02*
G03X539321Y108905I274J-292D01*
G02X537420Y108886I-940J-1040D01*
G03X537415Y109474I-274J292D01*
G02X539316Y109493I940J1040D01*
G37*
G36*
G01X502505D02*
G03X502510Y108905I274J-292D01*
G02X500609Y108886I-940J-1040D01*
G03X500604Y109474I-274J292D01*
G02X502505Y109493I940J1040D01*
G37*
G36*
G01X284985D02*
G03X284990Y108905I274J-292D01*
G02X283089Y108886I-940J-1040D01*
G03X283084Y109474I-274J292D01*
G02X284985Y109493I940J1040D01*
G37*
G36*
G01X248174D02*
G03X248179Y108905I274J-292D01*
G02X246278Y108886I-940J-1040D01*
G03X246273Y109474I-274J292D01*
G02X248174Y109493I940J1040D01*
G37*
G36*
G01X20473Y111006D02*
G03X21740Y111409I-2J2199D01*
G02X21756Y106771I1488J-2314D01*
G03X20502Y107184I-1283J-1786D01*
G01X20471D01*
G03X19204Y106781I2J-2199D01*
G02X19188Y111419I-1488J2314D01*
G03X20442Y111006I1283J1786D01*
G01X20473D01*
G37*
G36*
G01X3936Y107184D02*
G03X2669Y106781I2J-2199D01*
G02X2653Y111419I-1488J2314D01*
G03X3907Y111006I1283J1786D01*
G01X3938D01*
G03X5205Y111409I-2J2199D01*
G02X5221Y106771I1488J-2314D01*
G03X3967Y107184I-1283J-1786D01*
G01X3936D01*
G37*
G36*
G01X-12598Y111006D02*
G03X-11331Y111409I-2J2199D01*
G02X-11315Y106771I1488J-2314D01*
G03X-12569Y107184I-1283J-1786D01*
G01X-12599D01*
G03X-13866Y106781I2J-2199D01*
G02X-13882Y111419I-1488J2314D01*
G03X-12628Y111006I1283J1786D01*
G01X-12598D01*
G37*
G36*
G01X1194046Y109239D02*
G03X1194040Y108660I273J-292D01*
G02X1192106Y108680I-977J-1005D01*
G03X1192112Y109259I-273J292D01*
G02X1194046Y109239I977J1005D01*
G37*
G36*
G01X1157235D02*
G03X1157229Y108660I273J-292D01*
G02X1155295Y108680I-977J-1005D01*
G03X1155301Y109259I-273J292D01*
G02X1157235Y109239I977J1005D01*
G37*
G36*
G01X939715D02*
G03X939709Y108660I273J-292D01*
G02X937775Y108680I-977J-1005D01*
G03X937781Y109259I-273J292D01*
G02X939715Y109239I977J1005D01*
G37*
G36*
G01X902904D02*
G03X902898Y108660I273J-292D01*
G02X900964Y108680I-977J-1005D01*
G03X900970Y109259I-273J292D01*
G02X902904Y109239I977J1005D01*
G37*
G36*
G01X544438D02*
G03X544432Y108660I273J-292D01*
G02X542498Y108680I-977J-1005D01*
G03X542504Y109259I-273J292D01*
G02X544438Y109239I977J1005D01*
G37*
G36*
G01X507627D02*
G03X507621Y108660I273J-292D01*
G02X505687Y108680I-977J-1005D01*
G03X505693Y109259I-273J292D01*
G02X507627Y109239I977J1005D01*
G37*
G36*
G01X290107D02*
G03X290101Y108660I273J-292D01*
G02X288167Y108680I-977J-1005D01*
G03X288173Y109259I-273J292D01*
G02X290107Y109239I977J1005D01*
G37*
G36*
G01X253296D02*
G03X253290Y108660I273J-292D01*
G02X251356Y108680I-977J-1005D01*
G03X251362Y109259I-273J292D01*
G02X253296Y109239I977J1005D01*
G37*
G36*
G01X1853181Y106802D02*
G03X1852743Y106393I-38J-398D01*
G02X1851477Y107753I-1402J-35D01*
G03X1851915Y108162I38J398D01*
G02X1853181Y106802I1402J35D01*
G37*
G36*
G01X66896Y109760D02*
Y104665D01*
X66886Y104581D01*
G02X63872Y104750I-1502J169D01*
G01Y109751D01*
G02X66896Y109760I1512J-1D01*
G37*
G36*
G01X52892D02*
Y104665D01*
X52883Y104581D01*
G02X49870Y104750I-1502J169D01*
G01Y109750D01*
G02X52892Y109760I1511J0D01*
G37*
G36*
G01X1512424Y108332D02*
G02X1515446Y108342I1511J0D01*
G01Y104447D01*
X1515437Y104363D01*
G02X1512424Y104532I-1502J169D01*
G01Y108332D01*
G37*
G36*
G01X1811259Y105468D02*
G03X1811814Y105445I289J276D01*
G02X1811729Y103427I929J-1050D01*
G03X1811174Y103450I-289J-276D01*
G02X1811259Y105468I-929J1050D01*
G37*
G36*
G01X1525004Y103876D02*
X1524995Y104048D01*
X1524994D01*
X1525295Y109060D01*
X1525327Y109232D01*
G02X1528314Y109136I1486J-275D01*
G01X1528335Y108960D01*
X1528378D01*
X1528498Y108816D01*
X1528246Y107442D01*
X1528032Y103868D01*
X1528031Y103867D01*
X1528027Y103788D01*
X1528015Y103789D01*
G02X1525004Y103876I-1502J168D01*
G37*
G36*
G01X1490430Y104578D02*
G03X1490268Y104024I185J-355D01*
G02X1488403Y104567I-1215J-699D01*
G03X1488565Y105121I-185J355D01*
G02X1490430Y104578I1215J699D01*
G37*
G36*
G01X700017Y103801D02*
G03X699840Y103255I176J-359D01*
G02X697587Y101631I-1240J-655D01*
G03X697032Y101653I-289J-277D01*
G02X694970Y101870I-932J1047D01*
G03X694415Y101959I-323J-236D01*
G02X692290Y103599I-815J1141D01*
G03X691892Y104140I-374J142D01*
G02X692897Y106425I-82J1400D01*
G03X693485Y106390I310J253D01*
G02X695554Y106258I974J-1008D01*
G03X696081Y106170I312J249D01*
G02X697803Y105998I751J-1184D01*
G03X698373Y106014I277J288D01*
G02X700454Y105984I1027J-954D01*
G03X701021Y105949I301J264D01*
G02X703095Y105716I932J-1047D01*
G03X703642Y105615I326J232D01*
G02X703277Y103634I777J-1167D01*
G03X702730Y103735I-326J-232D01*
G02X700899Y103978I-777J1167D01*
G03X700332Y104013I-301J-264D01*
G02X700017Y103801I-933J1046D01*
G37*
G36*
G01X743520Y101574D02*
G03X742965Y101396I-194J-350D01*
G02X742380Y103226I-1265J604D01*
G03X742935Y103404I194J350D01*
G02X744736Y104095I1265J-604D01*
G03X745269Y104340I153J370D01*
G02X746064Y102605I1331J-440D01*
G03X745531Y102360I-153J-370D01*
G02X743520Y101574I-1331J440D01*
G37*
G36*
G01X25591Y103132D02*
G03X26858Y103535I-2J2199D01*
G02X26874Y98897I1488J-2314D01*
G03X25620Y99310I-1283J-1786D01*
G01X25590D01*
G03X24323Y98907I2J-2199D01*
G02X24307Y103545I-1488J2314D01*
G03X25561Y103132I1283J1786D01*
G01X25591D01*
G37*
G36*
G01X9054Y99310D02*
G03X7787Y98907I2J-2199D01*
G02X7771Y103545I-1488J2314D01*
G03X9025Y103132I1283J1786D01*
G01X9056D01*
G03X10323Y103535I-2J2199D01*
G02X10339Y98897I1488J-2314D01*
G03X9085Y99310I-1283J-1786D01*
G01X9054D01*
G37*
G36*
G01X-7480Y103132D02*
G03X-6213Y103535I-2J2199D01*
G02X-6197Y98897I1488J-2314D01*
G03X-7451Y99310I-1283J-1786D01*
G01X-7481D01*
G03X-8748Y98907I2J-2199D01*
G02X-8764Y103545I-1488J2314D01*
G03X-7510Y103132I1283J1786D01*
G01X-7480D01*
G37*
G36*
G01X1500216Y99529D02*
G02X1497194Y99501I-1511J-7D01*
G01X1497149Y102725D01*
G02X1500161Y102924I1511J21D01*
G01X1500169Y102860D01*
X1500171Y102795D01*
G02X1500172Y102767I-1510J-68D01*
G01Y102746D01*
X1500216Y99544D01*
G02Y99529I-1511J-8D01*
G37*
G36*
G01X757771Y100989D02*
G03Y100411I277J-289D01*
G02X755829I-971J-1011D01*
G03Y100989I-277J289D01*
G02X757771I971J1011D01*
G37*
G36*
G01X1375685Y100772D02*
G03Y100460I125J-156D01*
G02X1373798Y100339I-877J-1094D01*
G03Y100893I-288J277D01*
G02Y102839I1010J973D01*
G03Y103393I-288J277D01*
G02Y105339I1010J973D01*
G03Y105893I-288J277D01*
G02X1375781Y107876I1010J973D01*
G03X1376335I277J288D01*
G02X1378318Y105893I973J-1010D01*
G03Y105339I288J-277D01*
G02Y103393I-1010J-973D01*
G03Y102839I288J-277D01*
G02X1376335Y100856I-1010J-973D01*
G03X1375781I-277J-288D01*
G02X1375685Y100772I-970J1012D01*
G37*
G36*
G01X1687931Y99885D02*
G03X1688484Y99838I301J264D01*
G02X1688313Y97827I884J-1088D01*
G03X1687760Y97874I-301J-264D01*
G02X1687931Y99885I-884J1088D01*
G37*
G36*
G01X1659322Y99975D02*
G03X1659840Y99785I359J177D01*
G02X1659108Y97957I560J-1285D01*
G03X1658601Y98177I-369J-155D01*
G02X1659322Y99975I-447J1223D01*
G37*
G36*
G01X48412Y102760D02*
Y97665D01*
X48402Y97581D01*
G02X45388Y97750I-1502J169D01*
G01Y102751D01*
G02X48412Y102760I1512J-1D01*
G37*
G36*
G01X1542883Y98810D02*
G03X1542905Y98277I309J-254D01*
G02X1540817Y98190I-1005J-977D01*
G03X1540795Y98723I-309J254D01*
G02X1542883Y98810I1005J977D01*
G37*
G36*
G01X763520Y94433D02*
G03X762998Y94166I-137J-376D01*
G02X762130Y95867I-1348J384D01*
G03X762652Y96134I137J376D01*
G02X763520Y94433I1348J-384D01*
G37*
G36*
G01X1525232Y98265D02*
G02X1528256Y98275I1512J0D01*
G01Y93180D01*
X1528246Y93096D01*
G02X1525232Y93265I-1502J169D01*
G01Y98265D01*
G37*
G36*
G01X1405579Y90903D02*
G03X1404913I-333J-222D01*
G02X1403448Y93050I-1167J777D01*
G03X1403759Y93494I-85J391D01*
G02X1406205Y94601I1390J185D01*
G03X1406829Y94628I301J263D01*
G02X1408382Y92463I1131J-828D01*
G03X1408113Y91993I121J-381D01*
G02X1405579Y90903I-1367J-313D01*
G37*
G36*
G01X35367Y93038D02*
G03X35733Y92550I390J-89D01*
G02X34283Y91462I-83J-1400D01*
G03X33917Y91950I-390J89D01*
G02X35367Y93038I83J1400D01*
G37*
G36*
G01X1908421Y92839D02*
G03X1908430Y92252I276J-289D01*
G02X1906392Y92220I-1002J-1119D01*
G03X1906383Y92807I-276J289D01*
G02X1906348Y92840I1013J1109D01*
G03X1905778Y92823I-277J-289D01*
G02X1903649Y94939I-1100J1022D01*
G03X1903662Y95508I-274J291D01*
G02X1905786Y97632I1080J1044D01*
G03X1906355Y97645I278J288D01*
G02X1908485Y95528I1092J-1031D01*
G03X1908472Y94963I276J-289D01*
G02X1908421Y92839I-1087J-1037D01*
G37*
G36*
G01X68725Y89388D02*
X63724D01*
G02X63725Y92412I1J1512D01*
G01X68725D01*
G02X70236Y90910I-1J-1512D01*
G01Y90815D01*
X70227Y90731D01*
G02X68725Y89388I-1502J168D01*
G37*
G36*
G01X52892Y95760D02*
Y90665D01*
X52883Y90581D01*
G02X49870Y90750I-1502J169D01*
G01Y95750D01*
G02X52892Y95760I1511J0D01*
G37*
G36*
G01X1676372Y91718D02*
G03X1676946Y91514I374J142D01*
G02X1676339Y89802I703J-1213D01*
G03X1675765Y90006I-374J-142D01*
G02X1676372Y91718I-703J1213D01*
G37*
G36*
G01X733655Y89330D02*
G03X734242Y89312I302J263D01*
G02X734185Y87407I999J-983D01*
G03X733598Y87425I-302J-263D01*
G02X731603Y87422I-999J983D01*
G03X731034I-284J-282D01*
G02Y89394I-996J986D01*
G03X731603I285J282D01*
G02X733655Y89330I996J-986D01*
G37*
G36*
G01X1542878Y89123D02*
G03X1542807Y88580I253J-309D01*
G02X1540780Y88844I-1137J-820D01*
G03X1540851Y89387I-253J309D01*
G02X1540978Y91180I1137J820D01*
G03Y91734I-288J277D01*
G02X1543287Y93234I1010J973D01*
G03X1543774Y93002I371J151D01*
G02X1543857Y90296I406J-1342D01*
G03X1543370Y89973I-92J-389D01*
G02X1542878Y89123I-1383J233D01*
G37*
G36*
G01X1230845Y89103D02*
G03Y88525I277J-289D01*
G02X1228903I-971J-1011D01*
G03Y89103I-277J289D01*
G02X1230845I971J1011D01*
G37*
G36*
G01X1194034D02*
G03Y88525I277J-289D01*
G02X1192092I-971J-1011D01*
G03Y89103I-277J289D01*
G02X1194034I971J1011D01*
G37*
G36*
G01X1157223D02*
G03Y88525I277J-289D01*
G02X1155281I-971J-1011D01*
G03Y89103I-277J289D01*
G02X1157223I971J1011D01*
G37*
G36*
G01X1120411D02*
G03Y88525I277J-289D01*
G02X1118469I-971J-1011D01*
G03Y89103I-277J289D01*
G02X1120411I971J1011D01*
G37*
G36*
G01X939703D02*
G03Y88525I277J-289D01*
G02X937761I-971J-1011D01*
G03Y89103I-277J289D01*
G02X939703I971J1011D01*
G37*
G36*
G01X902892D02*
G03Y88525I277J-289D01*
G02X900950I-971J-1011D01*
G03Y89103I-277J289D01*
G02X902892I971J1011D01*
G37*
G36*
G01X866081D02*
G03Y88525I277J-289D01*
G02X864139I-971J-1011D01*
G03Y89103I-277J289D01*
G02X866081I971J1011D01*
G37*
G36*
G01X829270D02*
G03Y88525I277J-289D01*
G02X827328I-971J-1011D01*
G03Y89103I-277J289D01*
G02X829270I971J1011D01*
G37*
G36*
G01X792459D02*
G03Y88525I277J-289D01*
G02X790517I-971J-1011D01*
G03Y89103I-277J289D01*
G02X792459I971J1011D01*
G37*
G36*
G01X581237D02*
G03Y88525I277J-289D01*
G02X579295I-971J-1011D01*
G03Y89103I-277J289D01*
G02X581237I971J1011D01*
G37*
G36*
G01X544426D02*
G03Y88525I277J-289D01*
G02X542484I-971J-1011D01*
G03Y89103I-277J289D01*
G02X544426I971J1011D01*
G37*
G36*
G01X507615D02*
G03Y88525I277J-289D01*
G02X505673I-971J-1011D01*
G03Y89103I-277J289D01*
G02X507615I971J1011D01*
G37*
G36*
G01X470803D02*
G03Y88525I277J-289D01*
G02X468861I-971J-1011D01*
G03Y89103I-277J289D01*
G02X470803I971J1011D01*
G37*
G36*
G01X290095D02*
G03Y88525I277J-289D01*
G02X288153I-971J-1011D01*
G03Y89103I-277J289D01*
G02X290095I971J1011D01*
G37*
G36*
G01X253284D02*
G03Y88525I277J-289D01*
G02X251342I-971J-1011D01*
G03Y89103I-277J289D01*
G02X253284I971J1011D01*
G37*
G36*
G01X216473D02*
G03Y88525I277J-289D01*
G02X214531I-971J-1011D01*
G03Y89103I-277J289D01*
G02X216473I971J1011D01*
G37*
G36*
G01X179662D02*
G03Y88525I277J-289D01*
G02X177720I-971J-1011D01*
G03Y89103I-277J289D01*
G02X179662I971J1011D01*
G37*
G36*
G01X142851D02*
G03Y88525I277J-289D01*
G02X140909I-971J-1011D01*
G03Y89103I-277J289D01*
G02X142851I971J1011D01*
G37*
G36*
G01X1225745Y88889D02*
G03Y88311I277J-289D01*
G02X1223803I-971J-1011D01*
G03Y88889I-277J289D01*
G02X1225745I971J1011D01*
G37*
G36*
G01X1188934D02*
G03Y88311I277J-289D01*
G02X1186992I-971J-1011D01*
G03Y88889I-277J289D01*
G02X1188934I971J1011D01*
G37*
G36*
G01X1152123D02*
G03Y88311I277J-289D01*
G02X1150181I-971J-1011D01*
G03Y88889I-277J289D01*
G02X1152123I971J1011D01*
G37*
G36*
G01X1115311D02*
G03Y88311I277J-289D01*
G02X1113369I-971J-1011D01*
G03Y88889I-277J289D01*
G02X1115311I971J1011D01*
G37*
G36*
G01X934603D02*
G03Y88311I277J-289D01*
G02X932661I-971J-1011D01*
G03Y88889I-277J289D01*
G02X934603I971J1011D01*
G37*
G36*
G01X897792D02*
G03Y88311I277J-289D01*
G02X895850I-971J-1011D01*
G03Y88889I-277J289D01*
G02X897792I971J1011D01*
G37*
G36*
G01X860981D02*
G03Y88311I277J-289D01*
G02X859039I-971J-1011D01*
G03Y88889I-277J289D01*
G02X860981I971J1011D01*
G37*
G36*
G01X824170D02*
G03Y88311I277J-289D01*
G02X822228I-971J-1011D01*
G03Y88889I-277J289D01*
G02X824170I971J1011D01*
G37*
G36*
G01X787359D02*
G03Y88311I277J-289D01*
G02X785417I-971J-1011D01*
G03Y88889I-277J289D01*
G02X787359I971J1011D01*
G37*
G36*
G01X576137D02*
G03Y88311I277J-289D01*
G02X574195I-971J-1011D01*
G03Y88889I-277J289D01*
G02X576137I971J1011D01*
G37*
G36*
G01X539326D02*
G03Y88311I277J-289D01*
G02X537384I-971J-1011D01*
G03Y88889I-277J289D01*
G02X539326I971J1011D01*
G37*
G36*
G01X502515D02*
G03Y88311I277J-289D01*
G02X500573I-971J-1011D01*
G03Y88889I-277J289D01*
G02X502515I971J1011D01*
G37*
G36*
G01X465703D02*
G03Y88311I277J-289D01*
G02X463761I-971J-1011D01*
G03Y88889I-277J289D01*
G02X465703I971J1011D01*
G37*
G36*
G01X284995D02*
G03Y88311I277J-289D01*
G02X283053I-971J-1011D01*
G03Y88889I-277J289D01*
G02X284995I971J1011D01*
G37*
G36*
G01X248184D02*
G03Y88311I277J-289D01*
G02X246242I-971J-1011D01*
G03Y88889I-277J289D01*
G02X248184I971J1011D01*
G37*
G36*
G01X211373D02*
G03Y88311I277J-289D01*
G02X209431I-971J-1011D01*
G03Y88889I-277J289D01*
G02X211373I971J1011D01*
G37*
G36*
G01X174562D02*
G03Y88311I277J-289D01*
G02X172620I-971J-1011D01*
G03Y88889I-277J289D01*
G02X174562I971J1011D01*
G37*
G36*
G01X137751D02*
G03Y88311I277J-289D01*
G02X135809I-971J-1011D01*
G03Y88889I-277J289D01*
G02X137751I971J1011D01*
G37*
G36*
G01X1810901Y85810D02*
G03X1810333I-284J-282D01*
G02X1808171Y87895I-1065J1059D01*
G03Y88441I-292J273D01*
G02X1808209Y90534I1096J1027D01*
G03Y91102I-282J284D01*
G02Y93234I1058J1066D01*
G03Y93802I-282J284D01*
G02X1810333Y95926I1058J1066D01*
G03X1810901I284J282D01*
G02X1813033I1066J-1058D01*
G03X1813601I284J282D01*
G02X1815725Y93802I1066J-1058D01*
G03Y93234I282J-284D01*
G02Y91102I-1058J-1066D01*
G03Y90534I282J-284D01*
G02X1815763Y88441I-1058J-1066D01*
G03Y87895I292J-273D01*
G02X1813601Y85810I-1097J-1026D01*
G03X1813033I-284J-282D01*
G02X1810901I-1066J1058D01*
G37*
G36*
G01X1501386Y90491D02*
Y86596D01*
X1501377Y86512D01*
G02X1498364Y86681I-1502J169D01*
G01Y90481D01*
G02X1501386Y90491I1511J0D01*
G37*
G36*
G01X1598489Y83529D02*
G03X1597911I-289J-277D01*
G02Y85471I-1011J971D01*
G03X1598489I289J277D01*
G02X1600473Y85510I1011J-971D01*
G03X1601027I277J288D01*
G02Y83490I973J-1010D01*
G03X1600473I-277J-288D01*
G02X1598489Y83529I-973J1010D01*
G37*
G36*
G01X1953132Y85697D02*
G03X1953664Y85419I388J95D01*
G02X1952807Y83777I505J-1308D01*
G03X1952275Y84055I-388J-95D01*
G02X1950797Y84353I-505J1308D01*
G03X1950243I-277J-288D01*
G02X1948259Y84392I-973J1010D01*
G03X1947681I-289J-277D01*
G02X1945660Y86336I-1010J972D01*
G03Y86890I-288J277D01*
G02X1945623Y88795I1010J972D01*
G03X1945601Y89350I-299J266D01*
G02X1945560Y91336I969J1013D01*
G03Y91890I-288J277D01*
G02X1947581Y93834I1011J972D01*
G03X1948159I289J277D01*
G02X1948419Y94047I1012J-970D01*
G03X1948517Y94635I-214J338D01*
G02X1950583Y96523I1092J879D01*
G03X1951137I277J288D01*
G02X1953293Y96265I973J-1010D01*
G03X1953904Y96187I338J214D01*
G02X1955834Y96173I958J-1024D01*
G03X1956388I277J288D01*
G02X1958096Y93969I972J-1010D01*
G03X1957992Y93381I210J-340D01*
G02X1955918Y91503I-1100J-869D01*
G03X1955364I-277J-288D01*
G02X1953216Y91747I-973J1010D01*
G03X1952613Y91825I-335J-218D01*
G02X1952547Y91769I-940J1041D01*
G03Y91457I125J-156D01*
G02X1952717Y89431I-877J-1094D01*
G03X1952739Y88876I299J-266D01*
G02X1952780Y86890I-969J-1013D01*
G03Y86336I288J-277D01*
G02X1953132Y85697I-1010J-973D01*
G37*
G36*
G01X753559Y85177D02*
G03X753577Y84578I274J-292D01*
G02X751721Y84523I-897J-1078D01*
G03X751703Y85122I-274J292D01*
G02X753559Y85177I897J1078D01*
G37*
G36*
G01X1491579Y84665D02*
G03X1491783Y84181I380J-125D01*
G02X1489789Y83197I-619J-1258D01*
G03X1489529Y83653I-392J78D01*
G02X1491579Y84665I528J1512D01*
G37*
G36*
G01X1664527Y80590D02*
G03X1663973I-277J-288D01*
G02Y82610I-973J1010D01*
G03X1664527I277J288D01*
G02X1666473I973J-1010D01*
G03X1667027I277J288D01*
G02X1668973I973J-1010D01*
G03X1669527I277J288D01*
G02X1671473I973J-1010D01*
G03X1672027I277J288D01*
G02X1673973I973J-1010D01*
G03X1674527I277J288D01*
G02X1676473I973J-1010D01*
G03X1677027I277J288D01*
G02Y80590I973J-1010D01*
G03X1676473I-277J-288D01*
G02X1674527I-973J1010D01*
G03X1673973I-277J-288D01*
G02X1672027I-973J1010D01*
G03X1671473I-277J-288D01*
G02X1669527I-973J1010D01*
G03X1668973I-277J-288D01*
G02X1667027I-973J1010D01*
G03X1666473I-277J-288D01*
G02X1664527I-973J1010D01*
G37*
G36*
G01X1540631Y78303D02*
G03X1540043Y78212I-253J-310D01*
G02X1539759Y80064I-1173J768D01*
G03X1540347Y80155I253J310D01*
G02X1540631Y78303I1173J-768D01*
G37*
G36*
G01X1695009Y79103D02*
G03X1695533Y79134I244J317D01*
G02Y76848I1122J-1143D01*
G03X1695009Y76879I-280J-286D01*
G02X1693182Y76981I-854J1112D01*
G03X1692628I-277J-288D01*
G02X1690682I-973J1010D01*
G03X1690128I-277J-288D01*
G02Y79001I-973J1010D01*
G03X1690682I277J288D01*
G02X1692628I973J-1010D01*
G03X1693182I277J288D01*
G02X1695009Y79103I973J-1010D01*
G37*
G36*
G01X1822089Y76271D02*
G03X1821521I-284J-282D01*
G02X1819377Y78375I-1065J1059D01*
G03X1819384Y78925I-287J279D01*
G02X1821554Y81001I1104J1018D01*
G03X1822122I284J282D01*
G02X1824266Y78897I1065J-1059D01*
G03X1824259Y78347I287J-279D01*
G02X1822089Y76271I-1104J-1018D01*
G37*
G36*
G01X1394060Y75160D02*
G03X1393524I-268J-297D01*
G02X1391612Y77211I-940J1040D01*
G03Y77787I-277J288D01*
G02X1393523Y79839I972J1011D01*
G03X1394059Y79840I267J297D01*
G02X1395934Y79846I941J-1040D01*
G03X1396466I266J298D01*
G02X1398371Y77789I934J-1045D01*
G03Y77211I277J-289D01*
G02X1396466Y75154I-971J-1012D01*
G03X1395934I-266J-298D01*
G02X1394060Y75160I-934J1046D01*
G37*
G36*
G01X1581396Y74870D02*
G03X1580818I-289J-277D01*
G02Y76812I-1011J971D01*
G03X1581396I289J277D01*
G02Y74870I1011J-971D01*
G37*
G36*
G01X1571535Y76354D02*
G03X1572104Y76339I292J273D01*
G02X1572052Y74370I972J-1011D01*
G03X1571483Y74385I-292J-273D01*
G02X1571535Y76354I-972J1011D01*
G37*
G36*
G01X732634Y74469D02*
G03X732024Y74447I-296J-270D01*
G02X731960Y76258I-1101J868D01*
G03X732570Y76280I296J270D01*
G02X732634Y74469I1101J-868D01*
G37*
G36*
G01X1622583Y74541D02*
G03X1622036Y74329I-175J-359D01*
G02X1621350Y76106I-1303J518D01*
G03X1621897Y76318I175J359D01*
G02X1622583Y74541I1303J-518D01*
G37*
G36*
G01X1675015Y75899D02*
G03X1675598Y75776I347J200D01*
G02X1675213Y73947I830J-1130D01*
G03X1674630Y74070I-347J-200D01*
G02X1675015Y75899I-830J1130D01*
G37*
G36*
G01X1680934Y75447D02*
G03X1681488Y75412I295J270D01*
G02X1681362Y73397I908J-1068D01*
G03X1680808Y73432I-295J-270D01*
G02X1680934Y75447I-908J1068D01*
G37*
G36*
G01X62027Y72990D02*
G03X61473I-277J-288D01*
G02X59490Y74973I-973J1010D01*
G03Y75527I-288J277D01*
G02Y77473I1010J973D01*
G03Y78027I-288J277D01*
G02Y79973I1010J973D01*
G03Y80527I-288J277D01*
G02X61473Y82510I1010J973D01*
G03X62027I277J288D01*
G02X64010Y80527I973J-1010D01*
G03Y79973I288J-277D01*
G02Y78027I-1010J-973D01*
G03Y77473I288J-277D01*
G02Y75527I-1010J-973D01*
G03Y74973I288J-277D01*
G02X62027Y72990I-1010J-973D01*
G37*
G36*
G01X1454277Y74673D02*
G03X1454869Y74662I301J263D01*
G02X1454833Y72777I1020J-962D01*
G03X1454241Y72788I-301J-263D01*
G02X1454277Y74673I-1020J962D01*
G37*
G36*
G01X1563646Y75326D02*
G03X1563707Y74752I306J-258D01*
G02X1561779Y74547I-857J-1110D01*
G03X1561718Y75121I-306J258D01*
G02X1563646Y75326I857J1110D01*
G37*
G36*
G01X1895824Y72653D02*
G03X1895156Y72632I-327J-230D01*
G02X1893701Y74743I-1195J733D01*
G03X1894010Y75250I-74J393D01*
G02X1896722Y75344I1344J400D01*
G03X1897081Y74858I390J-87D01*
G02X1895824Y72653I-111J-1398D01*
G37*
G36*
G01X76473Y71510D02*
G03X77027I277J288D01*
G02X77776Y71884I972J-1010D01*
G03X78109Y72328I-64J395D01*
G02X79724Y71116I1391J172D01*
G03X79391Y70672I64J-395D01*
G02X77027Y69490I-1391J-172D01*
G03X76473I-277J-288D01*
G02X74527I-973J1010D01*
G03X73973I-277J-288D01*
G02X72027I-973J1010D01*
G03X71473I-277J-288D01*
G02X69527I-973J1010D01*
G03X68973I-277J-288D01*
G02X67027I-973J1010D01*
G03X66473I-277J-288D01*
G02X64527I-973J1010D01*
G03X63973I-277J-288D01*
G02X62027I-973J1010D01*
G03X61473I-277J-288D01*
G02Y71510I-973J1010D01*
G03X62027I277J288D01*
G02X63973I973J-1010D01*
G03X64527I277J288D01*
G02X66473I973J-1010D01*
G03X67027I277J288D01*
G02X68973I973J-1010D01*
G03X69527I277J288D01*
G02X71473I973J-1010D01*
G03X72027I277J288D01*
G02X73973I973J-1010D01*
G03X74527I277J288D01*
G02X76473I973J-1010D01*
G37*
G36*
G01X1825029Y71312D02*
G03X1825054Y70681I258J-306D01*
G02X1823028Y68497I-873J-1222D01*
G03X1822416Y68499I-307J-257D01*
G02X1820278Y70598I-1146J971D01*
G03X1820236Y71231I-264J300D01*
G02X1822257Y73401I834J1249D01*
G03X1822886Y73396I316J245D01*
G02X1825029Y71312I1175J-936D01*
G37*
G36*
G01X1795700Y70821D02*
G03X1796100Y70402I400J-19D01*
G01X1796101D01*
G02X1794500Y68877I-1J-1602D01*
G03X1794100Y69296I-400J19D01*
G01X1794099D01*
G02X1795700Y70821I1J1602D01*
G37*
G36*
G01X1225735Y70178D02*
G03X1225740Y69590I274J-292D01*
G02X1223839Y69571I-940J-1040D01*
G03X1223834Y70159I-274J292D01*
G02X1225735Y70178I940J1040D01*
G37*
G36*
G01X1188924D02*
G03X1188929Y69590I274J-292D01*
G02X1187028Y69571I-940J-1040D01*
G03X1187023Y70159I-274J292D01*
G02X1188924Y70178I940J1040D01*
G37*
G36*
G01X1152113D02*
G03X1152118Y69590I274J-292D01*
G02X1150217Y69571I-940J-1040D01*
G03X1150212Y70159I-274J292D01*
G02X1152113Y70178I940J1040D01*
G37*
G36*
G01X1115301D02*
G03X1115306Y69590I274J-292D01*
G02X1113405Y69571I-940J-1040D01*
G03X1113400Y70159I-274J292D01*
G02X1115301Y70178I940J1040D01*
G37*
G36*
G01X934593D02*
G03X934598Y69590I274J-292D01*
G02X932697Y69571I-940J-1040D01*
G03X932692Y70159I-274J292D01*
G02X934593Y70178I940J1040D01*
G37*
G36*
G01X897782D02*
G03X897787Y69590I274J-292D01*
G02X895886Y69571I-940J-1040D01*
G03X895881Y70159I-274J292D01*
G02X897782Y70178I940J1040D01*
G37*
G36*
G01X860971D02*
G03X860976Y69590I274J-292D01*
G02X859075Y69571I-940J-1040D01*
G03X859070Y70159I-274J292D01*
G02X860971Y70178I940J1040D01*
G37*
G36*
G01X824160D02*
G03X824165Y69590I274J-292D01*
G02X822264Y69571I-940J-1040D01*
G03X822259Y70159I-274J292D01*
G02X824160Y70178I940J1040D01*
G37*
G36*
G01X787349D02*
G03X787354Y69590I274J-292D01*
G02X785453Y69571I-940J-1040D01*
G03X785448Y70159I-274J292D01*
G02X787349Y70178I940J1040D01*
G37*
G36*
G01X576127D02*
G03X576132Y69590I274J-292D01*
G02X574231Y69571I-940J-1040D01*
G03X574226Y70159I-274J292D01*
G02X576127Y70178I940J1040D01*
G37*
G36*
G01X539316D02*
G03X539321Y69590I274J-292D01*
G02X537420Y69571I-940J-1040D01*
G03X537415Y70159I-274J292D01*
G02X539316Y70178I940J1040D01*
G37*
G36*
G01X502505D02*
G03X502510Y69590I274J-292D01*
G02X500609Y69571I-940J-1040D01*
G03X500604Y70159I-274J292D01*
G02X502505Y70178I940J1040D01*
G37*
G36*
G01X465693D02*
G03X465698Y69590I274J-292D01*
G02X463797Y69571I-940J-1040D01*
G03X463792Y70159I-274J292D01*
G02X465693Y70178I940J1040D01*
G37*
G36*
G01X284985D02*
G03X284990Y69590I274J-292D01*
G02X283089Y69571I-940J-1040D01*
G03X283084Y70159I-274J292D01*
G02X284985Y70178I940J1040D01*
G37*
G36*
G01X248174D02*
G03X248179Y69590I274J-292D01*
G02X246278Y69571I-940J-1040D01*
G03X246273Y70159I-274J292D01*
G02X248174Y70178I940J1040D01*
G37*
G36*
G01X211363D02*
G03X211368Y69590I274J-292D01*
G02X209467Y69571I-940J-1040D01*
G03X209462Y70159I-274J292D01*
G02X211363Y70178I940J1040D01*
G37*
G36*
G01X174552D02*
G03X174557Y69590I274J-292D01*
G02X172656Y69571I-940J-1040D01*
G03X172651Y70159I-274J292D01*
G02X174552Y70178I940J1040D01*
G37*
G36*
G01X137741D02*
G03X137746Y69590I274J-292D01*
G02X135845Y69571I-940J-1040D01*
G03X135840Y70159I-274J292D01*
G02X137741Y70178I940J1040D01*
G37*
G36*
G01X1230841Y69934D02*
G03Y69355I276J-289D01*
G02X1228907I-967J-1015D01*
G03Y69934I-276J290D01*
G02X1230841I967J1015D01*
G37*
G36*
G01X1194030D02*
G03Y69355I276J-289D01*
G02X1192096I-967J-1015D01*
G03Y69934I-276J290D01*
G02X1194030I967J1015D01*
G37*
G36*
G01X1157219D02*
G03Y69355I276J-289D01*
G02X1155285I-967J-1015D01*
G03Y69934I-276J290D01*
G02X1157219I967J1015D01*
G37*
G36*
G01X1120407D02*
G03Y69355I276J-289D01*
G02X1118473I-967J-1015D01*
G03Y69934I-276J290D01*
G02X1120407I967J1015D01*
G37*
G36*
G01X939699D02*
G03Y69355I276J-289D01*
G02X937765I-967J-1015D01*
G03Y69934I-276J290D01*
G02X939699I967J1015D01*
G37*
G36*
G01X902888D02*
G03Y69355I276J-289D01*
G02X900954I-967J-1015D01*
G03Y69934I-276J290D01*
G02X902888I967J1015D01*
G37*
G36*
G01X866077D02*
G03Y69355I276J-289D01*
G02X864143I-967J-1015D01*
G03Y69934I-276J290D01*
G02X866077I967J1015D01*
G37*
G36*
G01X829266D02*
G03Y69355I276J-289D01*
G02X827332I-967J-1015D01*
G03Y69934I-276J290D01*
G02X829266I967J1015D01*
G37*
G36*
G01X792455D02*
G03Y69355I276J-289D01*
G02X790521I-967J-1015D01*
G03Y69934I-276J290D01*
G02X792455I967J1015D01*
G37*
G36*
G01X581233D02*
G03Y69355I276J-289D01*
G02X579299I-967J-1015D01*
G03Y69934I-276J290D01*
G02X581233I967J1015D01*
G37*
G36*
G01X544422D02*
G03Y69355I276J-289D01*
G02X542488I-967J-1015D01*
G03Y69934I-276J290D01*
G02X544422I967J1015D01*
G37*
G36*
G01X507611D02*
G03Y69355I276J-289D01*
G02X505677I-967J-1015D01*
G03Y69934I-276J290D01*
G02X507611I967J1015D01*
G37*
G36*
G01X470799D02*
G03Y69355I276J-289D01*
G02X468865I-967J-1015D01*
G03Y69934I-276J290D01*
G02X470799I967J1015D01*
G37*
G36*
G01X290091D02*
G03Y69355I276J-289D01*
G02X288157I-967J-1015D01*
G03Y69934I-276J290D01*
G02X290091I967J1015D01*
G37*
G36*
G01X253280D02*
G03Y69355I276J-289D01*
G02X251346I-967J-1015D01*
G03Y69934I-276J290D01*
G02X253280I967J1015D01*
G37*
G36*
G01X216469D02*
G03Y69355I276J-289D01*
G02X214535I-967J-1015D01*
G03Y69934I-276J290D01*
G02X216469I967J1015D01*
G37*
G36*
G01X179658D02*
G03Y69355I276J-289D01*
G02X177724I-967J-1015D01*
G03Y69934I-276J290D01*
G02X179658I967J1015D01*
G37*
G36*
G01X142847D02*
G03Y69355I276J-289D01*
G02X140913I-967J-1015D01*
G03Y69934I-276J290D01*
G02X142847I967J1015D01*
G37*
G36*
G01X1733Y66210D02*
G03X1351Y66698I-390J88D01*
G02X2749Y67790I31J1402D01*
G03X3131Y67302I390J-88D01*
G02X1733Y66210I-31J-1402D01*
G37*
G36*
G01X1328429Y66950D02*
G03Y66350I265J-300D01*
G02X1326571I-929J-1050D01*
G03Y66950I-265J300D01*
G02X1326598Y69073I929J1050D01*
G03X1326591Y69692I-257J307D01*
G02X1328369Y69713I876J1094D01*
G03X1328376Y69094I257J-307D01*
G02X1328429Y66950I-876J-1094D01*
G37*
G36*
G01X1649871Y64260D02*
G03X1649293Y64256I-287J-279D01*
G02X1649281Y66198I-1017J965D01*
G03X1649859Y66202I287J279D01*
G02X1649871Y64260I1017J-965D01*
G37*
G36*
G01X734722Y65252D02*
G03X734742Y64719I308J-255D01*
G02X732775Y62723I-1010J-972D01*
G03X732242Y62735I-273J-292D01*
G02X730252Y64695I-910J1067D01*
G03X730232Y65228I-308J255D01*
G02X730180Y67115I1010J972D01*
G03X730171Y67648I-303J261D01*
G02X732157Y69624I1029J952D01*
G03X732690Y69612I273J292D01*
G02X734662Y67631I909J-1067D01*
G03X734671Y67098I303J-261D01*
G02X734722Y65252I-1029J-952D01*
G37*
G36*
G01X1785725Y65065D02*
G03X1786169Y64732I395J64D01*
G02X1784957Y63117I172J-1391D01*
G03X1784513Y63450I-395J-64D01*
G02X1785725Y65065I-172J1391D01*
G37*
G36*
G01X1610284Y62579D02*
G03X1609752Y62364I-162J-365D01*
G02X1607065Y63094I-1300J526D01*
G03X1606698Y63551I-396J58D01*
G02X1608184Y64745I99J1398D01*
G03X1608551Y64288I396J-58D01*
G02X1609021Y64172I-96J-1399D01*
G03X1609553Y64387I162J365D01*
G02X1610284Y62579I1300J-526D01*
G37*
G36*
G01X1734177Y57140D02*
G03X1733623I-277J-288D01*
G02X1731640Y59123I-973J1010D01*
G03Y59677I-288J277D01*
G02X1733660I1010J973D01*
G03Y59123I288J-277D01*
G02X1733744Y59027I-1012J-970D01*
G03X1734056I156J125D01*
G02X1734177Y57140I1094J-877D01*
G37*
G36*
G01X15614Y55240D02*
G03X15036I-289J-277D01*
G02Y57182I-1011J971D01*
G03X15614I289J277D01*
G02Y55240I1011J-971D01*
G37*
G36*
G01X60527Y54990D02*
G03X59973I-277J-288D01*
G02X57990Y56973I-973J1010D01*
G03Y57527I-288J277D01*
G02Y59473I1010J973D01*
G03Y60027I-288J277D01*
G02X59973Y62010I1010J973D01*
G03X60527I277J288D01*
G02X62510Y60027I973J-1010D01*
G03Y59473I288J-277D01*
G02Y57527I-1010J-973D01*
G03Y56973I288J-277D01*
G02X60527Y54990I-1010J-973D01*
G37*
G36*
G01X1816718Y55668D02*
G03X1817330Y55663I308J255D01*
G02X1817315Y53859I1066J-911D01*
G03X1816703Y53864I-308J-255D01*
G02X1816718Y55668I-1066J911D01*
G37*
G36*
G01X1825763Y54670D02*
G03X1825948Y54402I188J-68D01*
G02X1824461Y53215I-18J-1502D01*
G03X1824129Y53694I-391J84D01*
G02X1823379Y56326I221J1486D01*
G03X1823392Y56926I-258J306D01*
G02X1823160Y58862I1018J1104D01*
G03X1823038Y59424I-333J222D01*
G02X1825080Y59868I792J1276D01*
G03X1825202Y59306I333J-222D01*
G02X1825897Y58245I-792J-1277D01*
G03X1826420Y57923I396J57D01*
G02X1826346Y55104I480J-1423D01*
G03X1825810Y54826I-147J-372D01*
G02X1825763Y54670I-1460J355D01*
G37*
G36*
G01X1668527Y50490D02*
G03X1667973I-277J-288D01*
G02Y52510I-973J1010D01*
G03X1668527I277J288D01*
G02Y50490I973J-1010D01*
G37*
G36*
G01X1230845Y51303D02*
G03Y50725I277J-289D01*
G02X1228903I-971J-1011D01*
G03Y51303I-277J289D01*
G02X1230845I971J1011D01*
G37*
G36*
G01X1194034D02*
G03Y50725I277J-289D01*
G02X1192092I-971J-1011D01*
G03Y51303I-277J289D01*
G02X1194034I971J1011D01*
G37*
G36*
G01X1157222D02*
G03Y50725I277J-289D01*
G02X1155280I-971J-1011D01*
G03Y51303I-277J289D01*
G02X1157222I971J1011D01*
G37*
G36*
G01X1120411D02*
G03Y50725I277J-289D01*
G02X1118469I-971J-1011D01*
G03Y51303I-277J289D01*
G02X1120411I971J1011D01*
G37*
G36*
G01X939703D02*
G03Y50725I277J-289D01*
G02X937761I-971J-1011D01*
G03Y51303I-277J289D01*
G02X939703I971J1011D01*
G37*
G36*
G01X902892D02*
G03Y50725I277J-289D01*
G02X900950I-971J-1011D01*
G03Y51303I-277J289D01*
G02X902892I971J1011D01*
G37*
G36*
G01X866081D02*
G03Y50725I277J-289D01*
G02X864139I-971J-1011D01*
G03Y51303I-277J289D01*
G02X866081I971J1011D01*
G37*
G36*
G01X829270D02*
G03Y50725I277J-289D01*
G02X827328I-971J-1011D01*
G03Y51303I-277J289D01*
G02X829270I971J1011D01*
G37*
G36*
G01X792459D02*
G03Y50725I277J-289D01*
G02X790517I-971J-1011D01*
G03Y51303I-277J289D01*
G02X792459I971J1011D01*
G37*
G36*
G01X581237D02*
G03Y50725I277J-289D01*
G02X579295I-971J-1011D01*
G03Y51303I-277J289D01*
G02X581237I971J1011D01*
G37*
G36*
G01X544426D02*
G03Y50725I277J-289D01*
G02X542484I-971J-1011D01*
G03Y51303I-277J289D01*
G02X544426I971J1011D01*
G37*
G36*
G01X507614D02*
G03Y50725I277J-289D01*
G02X505672I-971J-1011D01*
G03Y51303I-277J289D01*
G02X507614I971J1011D01*
G37*
G36*
G01X470803D02*
G03Y50725I277J-289D01*
G02X468861I-971J-1011D01*
G03Y51303I-277J289D01*
G02X470803I971J1011D01*
G37*
G36*
G01X290095D02*
G03Y50725I277J-289D01*
G02X288153I-971J-1011D01*
G03Y51303I-277J289D01*
G02X290095I971J1011D01*
G37*
G36*
G01X253284D02*
G03Y50725I277J-289D01*
G02X251342I-971J-1011D01*
G03Y51303I-277J289D01*
G02X253284I971J1011D01*
G37*
G36*
G01X216473D02*
G03Y50725I277J-289D01*
G02X214531I-971J-1011D01*
G03Y51303I-277J289D01*
G02X216473I971J1011D01*
G37*
G36*
G01X179662D02*
G03Y50725I277J-289D01*
G02X177720I-971J-1011D01*
G03Y51303I-277J289D01*
G02X179662I971J1011D01*
G37*
G36*
G01X142851D02*
G03Y50725I277J-289D01*
G02X140909I-971J-1011D01*
G03Y51303I-277J289D01*
G02X142851I971J1011D01*
G37*
G36*
G01X1225745Y51089D02*
G03Y50511I277J-289D01*
G02X1223803I-971J-1011D01*
G03Y51089I-277J289D01*
G02X1225745I971J1011D01*
G37*
G36*
G01X1188934D02*
G03Y50511I277J-289D01*
G02X1186992I-971J-1011D01*
G03Y51089I-277J289D01*
G02X1188934I971J1011D01*
G37*
G36*
G01X1152122D02*
G03Y50511I277J-289D01*
G02X1150180I-971J-1011D01*
G03Y51089I-277J289D01*
G02X1152122I971J1011D01*
G37*
G36*
G01X1115311D02*
G03Y50511I277J-289D01*
G02X1113369I-971J-1011D01*
G03Y51089I-277J289D01*
G02X1115311I971J1011D01*
G37*
G36*
G01X934603D02*
G03Y50511I277J-289D01*
G02X932661I-971J-1011D01*
G03Y51089I-277J289D01*
G02X934603I971J1011D01*
G37*
G36*
G01X897792D02*
G03Y50511I277J-289D01*
G02X895850I-971J-1011D01*
G03Y51089I-277J289D01*
G02X897792I971J1011D01*
G37*
G36*
G01X860981D02*
G03Y50511I277J-289D01*
G02X859039I-971J-1011D01*
G03Y51089I-277J289D01*
G02X860981I971J1011D01*
G37*
G36*
G01X824170D02*
G03Y50511I277J-289D01*
G02X822228I-971J-1011D01*
G03Y51089I-277J289D01*
G02X824170I971J1011D01*
G37*
G36*
G01X787359D02*
G03Y50511I277J-289D01*
G02X785417I-971J-1011D01*
G03Y51089I-277J289D01*
G02X787359I971J1011D01*
G37*
G36*
G01X576137D02*
G03Y50511I277J-289D01*
G02X574195I-971J-1011D01*
G03Y51089I-277J289D01*
G02X576137I971J1011D01*
G37*
G36*
G01X539326D02*
G03Y50511I277J-289D01*
G02X537384I-971J-1011D01*
G03Y51089I-277J289D01*
G02X539326I971J1011D01*
G37*
G36*
G01X502514D02*
G03Y50511I277J-289D01*
G02X500572I-971J-1011D01*
G03Y51089I-277J289D01*
G02X502514I971J1011D01*
G37*
G36*
G01X465703D02*
G03Y50511I277J-289D01*
G02X463761I-971J-1011D01*
G03Y51089I-277J289D01*
G02X465703I971J1011D01*
G37*
G36*
G01X284995D02*
G03Y50511I277J-289D01*
G02X283053I-971J-1011D01*
G03Y51089I-277J289D01*
G02X284995I971J1011D01*
G37*
G36*
G01X248184D02*
G03Y50511I277J-289D01*
G02X246242I-971J-1011D01*
G03Y51089I-277J289D01*
G02X248184I971J1011D01*
G37*
G36*
G01X211373D02*
G03Y50511I277J-289D01*
G02X209431I-971J-1011D01*
G03Y51089I-277J289D01*
G02X211373I971J1011D01*
G37*
G36*
G01X174562D02*
G03Y50511I277J-289D01*
G02X172620I-971J-1011D01*
G03Y51089I-277J289D01*
G02X174562I971J1011D01*
G37*
G36*
G01X137751D02*
G03Y50511I277J-289D01*
G02X135809I-971J-1011D01*
G03Y51089I-277J289D01*
G02X137751I971J1011D01*
G37*
G36*
G01X1744121Y46096D02*
G03X1743567I-277J-288D01*
G02Y48116I-973J1010D01*
G03X1744121I277J288D01*
G02Y46096I973J-1010D01*
G37*
G36*
G01X1363531Y44948D02*
G03X1363481Y44361I244J-316D01*
G02X1361591Y44523I-1033J-948D01*
G03X1361641Y45110I-244J316D01*
G02X1363531Y44948I1033J948D01*
G37*
G36*
G01X1309627Y40490D02*
G03X1309073I-277J-288D01*
G02Y42510I-973J1010D01*
G03X1309627I277J288D01*
G02Y40490I973J-1010D01*
G37*
G36*
G01X1324989Y40468D02*
G03X1324411I-289J-277D01*
G02X1322354Y42373I-1012J971D01*
G03Y42905I-298J266D01*
G02X1324392Y44829I1047J933D01*
G03X1324982Y44855I283J283D01*
G02X1327038Y42954I1076J-898D01*
G03X1327025Y42395I280J-286D01*
G02X1324989Y40468I-1025J-956D01*
G37*
G36*
G01X1721758Y38368D02*
X1717958D01*
G02Y41392I0J1512D01*
G01X1721759D01*
G02X1723270Y39890I-1J-1512D01*
G01Y39795D01*
X1723260Y39711D01*
G02X1721758Y38368I-1502J169D01*
G37*
G36*
G01X1703073Y38168D02*
X1699273D01*
G02Y41190I0J1511D01*
G01X1703074D01*
G02X1704584Y39689I-1J-1511D01*
G01Y39594D01*
X1704575Y39510D01*
G02X1703073Y38168I-1502J169D01*
G37*
G36*
G01X1740556Y37975D02*
Y37965D01*
X1736654Y38080D01*
X1736483Y38104D01*
G02X1736742Y41111I217J1496D01*
G01Y41121D01*
X1740642Y41006D01*
X1740650Y40998D01*
X1740723Y40992D01*
G02X1742110Y39496I-125J-1506D01*
G01Y39401D01*
X1742100Y39317D01*
G02X1740556Y37975I-1502J169D01*
G37*
G36*
G01X1731183Y37954D02*
X1727383D01*
G02Y40976I0J1511D01*
G01X1731183D01*
G02X1732694Y39475I0J-1511D01*
G01Y39380D01*
X1732685Y39296D01*
G02X1731183Y37954I-1502J169D01*
G37*
G36*
G01X1694098Y37950D02*
X1689098D01*
G02Y40974I0J1512D01*
G01X1694098D01*
G02X1695610Y39472I0J-1512D01*
G01Y39377D01*
X1695600Y39293D01*
G02X1694098Y37950I-1502J169D01*
G37*
G36*
G01X1684648D02*
X1679648D01*
G02Y40974I0J1512D01*
G01X1684649D01*
G02X1686160Y39472I-1J-1512D01*
G01Y39377D01*
X1686150Y39293D01*
G02X1684648Y37950I-1502J169D01*
G37*
G36*
G01X1675198D02*
X1670198D01*
G02Y40974I0J1512D01*
G01X1675199D01*
G02X1676710Y39472I-1J-1512D01*
G01Y39377D01*
X1676700Y39293D01*
G02X1675198Y37950I-1502J169D01*
G37*
G36*
G01X1646848D02*
X1641848D01*
G02Y40974I0J1512D01*
G01X1646849D01*
G02X1648360Y39472I-1J-1512D01*
G01Y39377D01*
X1648350Y39293D01*
G02X1646848Y37950I-1502J169D01*
G37*
G36*
G01X1712308Y37838D02*
X1708508D01*
G02Y40862I0J1512D01*
G01X1712309D01*
G02X1713820Y39360I-1J-1512D01*
G01Y39265D01*
X1713810Y39181D01*
G02X1712308Y37838I-1502J168D01*
G37*
G36*
G01X1368689Y36829D02*
G03X1368111I-289J-277D01*
G02Y38771I-1011J971D01*
G03X1368689I289J277D01*
G02Y36829I1011J-971D01*
G37*
G36*
G01X1660748Y40974D02*
X1665749D01*
G02X1667260Y39472I-1J-1512D01*
G01Y39377D01*
X1667250Y39293D01*
G02X1665748Y37950I-1502J169D01*
G01X1662563D01*
G03X1662204Y37375I1J-400D01*
G02X1659887Y37682I-1260J-614D01*
G03X1659829Y38262I-302J263D01*
G02X1660748Y40974I919J1200D01*
G37*
G36*
G01X1651297D02*
X1656299D01*
G02X1657810Y39472I-1J-1512D01*
G01Y39377D01*
X1657800Y39293D01*
G02X1656298Y37950I-1502J169D01*
G01X1652864D01*
G03X1652506Y37373I0J-400D01*
G02X1650282Y37764I-1256J-623D01*
G03X1650276Y38348I-276J289D01*
G02X1651297Y40974I1022J1114D01*
G37*
G36*
G01X1847503Y35441D02*
G03X1848058Y35439I279J287D01*
G02X1848051Y33420I969J-1013D01*
G03X1847496Y33422I-279J-287D01*
G02X1847503Y35441I-969J1013D01*
G37*
G36*
G01X655725Y30405D02*
G03X655151Y30327I-250J-312D01*
G02X652986Y30199I-1135J823D01*
G03X652415Y30215I-293J-272D01*
G02X650428Y30257I-973J1010D01*
G03X649856Y30264I-289J-276D01*
G02X649881Y32226I-989J994D01*
G03X650453Y32219I289J276D01*
G02X652472Y32176I989J-994D01*
G03X653043Y32160I293J272D01*
G02X654891Y32245I972J-1010D01*
G03X655465Y32323I250J312D01*
G02X655725Y30405I1135J-823D01*
G37*
G36*
G01X1225735Y32378D02*
G03X1225740Y31790I274J-292D01*
G02X1223839Y31771I-940J-1040D01*
G03X1223834Y32359I-274J292D01*
G02X1225735Y32378I940J1040D01*
G37*
G36*
G01X1188924D02*
G03X1188929Y31790I274J-292D01*
G02X1187028Y31771I-940J-1040D01*
G03X1187023Y32359I-274J292D01*
G02X1188924Y32378I940J1040D01*
G37*
G36*
G01X1152112D02*
G03X1152117Y31790I274J-292D01*
G02X1150216Y31771I-940J-1040D01*
G03X1150211Y32359I-274J292D01*
G02X1152112Y32378I940J1040D01*
G37*
G36*
G01X1115301D02*
G03X1115306Y31790I274J-292D01*
G02X1113405Y31771I-940J-1040D01*
G03X1113400Y32359I-274J292D01*
G02X1115301Y32378I940J1040D01*
G37*
G36*
G01X934593D02*
G03X934598Y31790I274J-292D01*
G02X932697Y31771I-940J-1040D01*
G03X932692Y32359I-274J292D01*
G02X934593Y32378I940J1040D01*
G37*
G36*
G01X897782D02*
G03X897787Y31790I274J-292D01*
G02X895886Y31771I-940J-1040D01*
G03X895881Y32359I-274J292D01*
G02X897782Y32378I940J1040D01*
G37*
G36*
G01X860971D02*
G03X860976Y31790I274J-292D01*
G02X859075Y31771I-940J-1040D01*
G03X859070Y32359I-274J292D01*
G02X860971Y32378I940J1040D01*
G37*
G36*
G01X824160D02*
G03X824165Y31790I274J-292D01*
G02X822264Y31771I-940J-1040D01*
G03X822259Y32359I-274J292D01*
G02X824160Y32378I940J1040D01*
G37*
G36*
G01X787349D02*
G03X787354Y31790I274J-292D01*
G02X785453Y31771I-940J-1040D01*
G03X785448Y32359I-274J292D01*
G02X787349Y32378I940J1040D01*
G37*
G36*
G01X576127D02*
G03X576132Y31790I274J-292D01*
G02X574231Y31771I-940J-1040D01*
G03X574226Y32359I-274J292D01*
G02X576127Y32378I940J1040D01*
G37*
G36*
G01X539316D02*
G03X539321Y31790I274J-292D01*
G02X537420Y31771I-940J-1040D01*
G03X537415Y32359I-274J292D01*
G02X539316Y32378I940J1040D01*
G37*
G36*
G01X502504D02*
G03X502509Y31790I274J-292D01*
G02X500608Y31771I-940J-1040D01*
G03X500603Y32359I-274J292D01*
G02X502504Y32378I940J1040D01*
G37*
G36*
G01X465693D02*
G03X465698Y31790I274J-292D01*
G02X463797Y31771I-940J-1040D01*
G03X463792Y32359I-274J292D01*
G02X465693Y32378I940J1040D01*
G37*
G36*
G01X284985D02*
G03X284990Y31790I274J-292D01*
G02X283089Y31771I-940J-1040D01*
G03X283084Y32359I-274J292D01*
G02X284985Y32378I940J1040D01*
G37*
G36*
G01X248174D02*
G03X248179Y31790I274J-292D01*
G02X246278Y31771I-940J-1040D01*
G03X246273Y32359I-274J292D01*
G02X248174Y32378I940J1040D01*
G37*
G36*
G01X211363D02*
G03X211368Y31790I274J-292D01*
G02X209467Y31771I-940J-1040D01*
G03X209462Y32359I-274J292D01*
G02X211363Y32378I940J1040D01*
G37*
G36*
G01X174552D02*
G03X174557Y31790I274J-292D01*
G02X172656Y31771I-940J-1040D01*
G03X172651Y32359I-274J292D01*
G02X174552Y32378I940J1040D01*
G37*
G36*
G01X137741D02*
G03X137746Y31790I274J-292D01*
G02X135845Y31771I-940J-1040D01*
G03X135840Y32359I-274J292D01*
G02X137741Y32378I940J1040D01*
G37*
G36*
G01X1311586Y30712D02*
G03X1311131Y30400I-64J-395D01*
G02X1309983Y32075I-1371J291D01*
G03X1310438Y32387I64J395D01*
G02X1313179Y32393I1371J-292D01*
G03X1313653Y32086I391J84D01*
G02X1314428Y32029I289J-1372D01*
G03X1314952Y32295I139J375D01*
G02X1317220Y32969I1348J-384D01*
G03X1317752Y32976I262J302D01*
G02X1319816Y32791I948J-1033D01*
G03X1320427Y32760I319J242D01*
G02X1320336Y30955I1025J-956D01*
G03X1319725Y30986I-319J-242D01*
G02X1317780Y30885I-1025J957D01*
G03X1317248Y30878I-262J-302D01*
G02X1315814Y30596I-948J1033D01*
G03X1315290Y30330I-139J-375D01*
G02X1312572Y30417I-1348J384D01*
G03X1312098Y30724I-391J-84D01*
G02X1311586Y30712I-288J1372D01*
G37*
G36*
G01X1230841Y32134D02*
G03Y31555I276J-289D01*
G02X1228907I-967J-1015D01*
G03Y32134I-276J289D01*
G02X1230841I967J1015D01*
G37*
G36*
G01X1194030D02*
G03Y31555I276J-289D01*
G02X1192096I-967J-1015D01*
G03Y32134I-276J289D01*
G02X1194030I967J1015D01*
G37*
G36*
G01X1157218D02*
G03Y31555I276J-289D01*
G02X1155284I-967J-1015D01*
G03Y32134I-276J289D01*
G02X1157218I967J1015D01*
G37*
G36*
G01X1120407D02*
G03Y31555I276J-289D01*
G02X1118473I-967J-1015D01*
G03Y32134I-276J289D01*
G02X1120407I967J1015D01*
G37*
G36*
G01X939699D02*
G03Y31555I276J-289D01*
G02X937765I-967J-1015D01*
G03Y32134I-276J289D01*
G02X939699I967J1015D01*
G37*
G36*
G01X902888D02*
G03Y31555I276J-289D01*
G02X900954I-967J-1015D01*
G03Y32134I-276J289D01*
G02X902888I967J1015D01*
G37*
G36*
G01X866077D02*
G03Y31555I276J-289D01*
G02X864143I-967J-1015D01*
G03Y32134I-276J289D01*
G02X866077I967J1015D01*
G37*
G36*
G01X829266D02*
G03Y31555I276J-289D01*
G02X827332I-967J-1015D01*
G03Y32134I-276J289D01*
G02X829266I967J1015D01*
G37*
G36*
G01X792455D02*
G03Y31555I276J-289D01*
G02X790521I-967J-1015D01*
G03Y32134I-276J289D01*
G02X792455I967J1015D01*
G37*
G36*
G01X581233D02*
G03Y31555I276J-289D01*
G02X579299I-967J-1015D01*
G03Y32134I-276J289D01*
G02X581233I967J1015D01*
G37*
G36*
G01X544422D02*
G03Y31555I276J-289D01*
G02X542488I-967J-1015D01*
G03Y32134I-276J289D01*
G02X544422I967J1015D01*
G37*
G36*
G01X507610D02*
G03Y31555I276J-289D01*
G02X505676I-967J-1015D01*
G03Y32134I-276J289D01*
G02X507610I967J1015D01*
G37*
G36*
G01X470799D02*
G03Y31555I276J-289D01*
G02X468865I-967J-1015D01*
G03Y32134I-276J289D01*
G02X470799I967J1015D01*
G37*
G36*
G01X290091D02*
G03Y31555I276J-289D01*
G02X288157I-967J-1015D01*
G03Y32134I-276J289D01*
G02X290091I967J1015D01*
G37*
G36*
G01X253280D02*
G03Y31555I276J-289D01*
G02X251346I-967J-1015D01*
G03Y32134I-276J289D01*
G02X253280I967J1015D01*
G37*
G36*
G01X216469D02*
G03Y31555I276J-289D01*
G02X214535I-967J-1015D01*
G03Y32134I-276J289D01*
G02X216469I967J1015D01*
G37*
G36*
G01X179658D02*
G03Y31555I276J-289D01*
G02X177724I-967J-1015D01*
G03Y32134I-276J289D01*
G02X179658I967J1015D01*
G37*
G36*
G01X142847D02*
G03Y31555I276J-289D01*
G02X140913I-967J-1015D01*
G03Y32134I-276J289D01*
G02X142847I967J1015D01*
G37*
G36*
G01X1758406Y34262D02*
Y30367D01*
X1758397Y30283D01*
G02X1755384Y30452I-1502J169D01*
G01Y34252D01*
G02X1758406Y34262I1511J0D01*
G37*
G36*
G01X1523780Y27567D02*
G03X1523280Y27252I-106J-386D01*
G02X1522274Y28851I-1380J248D01*
G03X1522774Y29166I106J386D01*
G02X1523780Y27567I1380J-248D01*
G37*
G36*
G01X1509078Y30563D02*
G03X1508559Y30154I-120J-381D01*
G02X1507596Y32459I-3893J-273D01*
G03X1508253Y32540I301J264D01*
G02X1509078Y30563I1247J-640D01*
G37*
G36*
G01X1808288Y27703D02*
G03X1808887Y27629I332J224D01*
G02X1808661Y25800I935J-1044D01*
G03X1808062Y25874I-332J-224D01*
G02X1808288Y27703I-935J1044D01*
G37*
G36*
G01X1380536Y27426D02*
G03X1381078Y27181I381J121D01*
G02X1380306Y25472I564J-1284D01*
G03X1379764Y25717I-381J-121D01*
G02X1380536Y27426I-564J1284D01*
G37*
G36*
G01X678507Y41042D02*
X678508Y41054D01*
Y41903D01*
X679618Y43012D01*
X683687D01*
X683710Y43186D01*
G02X686490I1390J-186D01*
G01X686513Y43012D01*
X701485D01*
X702502Y41996D01*
Y39001D01*
X703502Y38001D01*
Y31999D01*
X702402Y31299D01*
Y25292D01*
X701311Y24202D01*
X700998D01*
X700995Y24198D01*
X690099D01*
X687899Y26398D01*
X680899D01*
X677098Y30199D01*
Y35701D01*
X678498Y37101D01*
Y40884D01*
G02X678507Y41042I1402J-1D01*
G37*
G36*
G01X14801Y25749D02*
G03X15397Y25723I310J253D01*
G02X15315Y23856I1003J-979D01*
G03X14719Y23882I-310J-253D01*
G02X14801Y25749I-1003J979D01*
G37*
G36*
G01X1767069Y22498D02*
X1763360D01*
G02Y25522I0J1512D01*
G01X1767069D01*
G02X1768580Y24020I-1J-1512D01*
G01Y23925D01*
X1768571Y23841D01*
G02X1767069Y22498I-1502J169D01*
G37*
G36*
G01X1550861Y22846D02*
G03X1550307I-277J-288D01*
G02Y24866I-973J1010D01*
G03X1550861I277J288D01*
G02X1552845Y24827I973J-1010D01*
G03X1553423I289J277D01*
G02Y22885I1011J-971D01*
G03X1552845I-289J-277D01*
G02X1550861Y22846I-1011J971D01*
G37*
G36*
G01X1748152Y21686D02*
X1743152D01*
G02Y24708I0J1511D01*
G01X1748153D01*
G02X1749664Y23207I0J-1512D01*
G01Y23112D01*
X1749654Y23028D01*
G02X1748152Y21686I-1502J169D01*
G37*
G36*
G01X655327Y21790D02*
G03X654773I-277J-288D01*
G02Y23810I-973J1010D01*
G03X655327I277J288D01*
G02Y21790I973J-1010D01*
G37*
G36*
G01X1738168Y20800D02*
X1733168D01*
G02Y23824I0J1512D01*
G01X1738169D01*
G02X1739680Y22322I-1J-1512D01*
G01Y22227D01*
X1739670Y22143D01*
G02X1738168Y20800I-1502J169D01*
G37*
G36*
G01X1532430Y23307D02*
G02Y24629I3693J661D01*
G02Y23307I3693J-661D01*
G37*
G36*
G01X1824343Y22637D02*
G03X1824913Y22612I297J267D01*
G02X1824827Y20650I957J-1025D01*
G03X1824257Y20675I-297J-267D01*
G02X1824343Y22637I-957J1025D01*
G37*
G36*
G01X691427Y19790D02*
G03X690873I-277J-288D01*
G02Y21810I-973J1010D01*
G03X691427I277J288D01*
G02Y19790I973J-1010D01*
G37*
G36*
G01X1760709Y18534D02*
X1757009Y18496D01*
G02X1756976Y21518I-16J1511D01*
G01X1760677Y21556D01*
G02X1762198Y20189I16J-1511D01*
G01X1762204Y20130D01*
X1762205Y20071D01*
G02Y20019I-1512J-26D01*
G01X1762204Y20017D01*
Y20007D01*
G02X1760709Y18534I-1511J38D01*
G37*
G36*
G01X1375911Y14137D02*
G03X1375375Y14134I-266J-299D01*
G02X1373356Y14269I-945J1036D01*
G03X1372795Y14321I-307J-256D01*
G02X1370854Y16334I-895J1079D01*
G03Y16866I-298J266D01*
G02X1370874Y18755I1046J934D01*
G03X1370885Y19288I-293J273D01*
G02X1370907Y21136I1065J911D01*
G03X1370905Y21673I-298J267D01*
G02X1372984Y21681I1036J944D01*
G03X1372986Y21144I298J-267D01*
G02X1372976Y19245I-1036J-944D01*
G03X1372965Y18712I293J-273D01*
G02X1372946Y16866I-1065J-912D01*
G03Y16334I298J-266D01*
G02X1372975Y16301I-1039J-942D01*
G03X1373536Y16249I307J256D01*
G02X1375362Y16218I895J-1079D01*
G03X1375898Y16221I266J299D01*
G02X1375911Y14137I944J-1036D01*
G37*
G36*
G01X1577048Y10994D02*
X1573048D01*
G02Y14018I0J1512D01*
G01X1577049D01*
G02X1578560Y12516I-1J-1512D01*
G01Y12421D01*
X1578550Y12337D01*
G02X1577048Y10994I-1502J169D01*
G37*
G36*
G01X1567498D02*
X1563498D01*
G02Y14018I0J1512D01*
G01X1567499D01*
G02X1569010Y12516I-1J-1512D01*
G01Y12421D01*
X1569000Y12337D01*
G02X1567498Y10994I-1502J169D01*
G37*
G36*
G01X1548698D02*
X1544698D01*
G02Y14018I0J1512D01*
G01X1548699D01*
G02X1550210Y12516I-1J-1512D01*
G01Y12421D01*
X1550200Y12337D01*
G02X1548698Y10994I-1502J169D01*
G37*
G36*
G01X1554148Y13818D02*
X1558148D01*
G02X1559660Y12316I0J-1512D01*
G01Y12221D01*
X1559650Y12137D01*
G02X1558148Y10794I-1502J169D01*
G01X1554148D01*
G02Y13818I0J1512D01*
G37*
G36*
G01X1230845Y13503D02*
G03Y12925I277J-289D01*
G02X1228903I-971J-1011D01*
G03Y13503I-277J289D01*
G02X1230845I971J1011D01*
G37*
G36*
G01X1194034D02*
G03Y12925I277J-289D01*
G02X1192092I-971J-1011D01*
G03Y13503I-277J289D01*
G02X1194034I971J1011D01*
G37*
G36*
G01X1157223D02*
G03Y12925I277J-289D01*
G02X1155281I-971J-1011D01*
G03Y13503I-277J289D01*
G02X1157223I971J1011D01*
G37*
G36*
G01X1120411D02*
G03Y12925I277J-289D01*
G02X1118469I-971J-1011D01*
G03Y13503I-277J289D01*
G02X1120411I971J1011D01*
G37*
G36*
G01X939703D02*
G03Y12925I277J-289D01*
G02X937761I-971J-1011D01*
G03Y13503I-277J289D01*
G02X939703I971J1011D01*
G37*
G36*
G01X902892D02*
G03Y12925I277J-289D01*
G02X900950I-971J-1011D01*
G03Y13503I-277J289D01*
G02X902892I971J1011D01*
G37*
G36*
G01X866081D02*
G03Y12925I277J-289D01*
G02X864139I-971J-1011D01*
G03Y13503I-277J289D01*
G02X866081I971J1011D01*
G37*
G36*
G01X829270D02*
G03Y12925I277J-289D01*
G02X827328I-971J-1011D01*
G03Y13503I-277J289D01*
G02X829270I971J1011D01*
G37*
G36*
G01X792459D02*
G03Y12925I277J-289D01*
G02X790517I-971J-1011D01*
G03Y13503I-277J289D01*
G02X792459I971J1011D01*
G37*
G36*
G01X581237D02*
G03Y12925I277J-289D01*
G02X579295I-971J-1011D01*
G03Y13503I-277J289D01*
G02X581237I971J1011D01*
G37*
G36*
G01X544426D02*
G03Y12925I277J-289D01*
G02X542484I-971J-1011D01*
G03Y13503I-277J289D01*
G02X544426I971J1011D01*
G37*
G36*
G01X507615D02*
G03Y12925I277J-289D01*
G02X505673I-971J-1011D01*
G03Y13503I-277J289D01*
G02X507615I971J1011D01*
G37*
G36*
G01X470803D02*
G03Y12925I277J-289D01*
G02X468861I-971J-1011D01*
G03Y13503I-277J289D01*
G02X470803I971J1011D01*
G37*
G36*
G01X290095D02*
G03Y12925I277J-289D01*
G02X288153I-971J-1011D01*
G03Y13503I-277J289D01*
G02X290095I971J1011D01*
G37*
G36*
G01X253284D02*
G03Y12925I277J-289D01*
G02X251342I-971J-1011D01*
G03Y13503I-277J289D01*
G02X253284I971J1011D01*
G37*
G36*
G01X216473D02*
G03Y12925I277J-289D01*
G02X214531I-971J-1011D01*
G03Y13503I-277J289D01*
G02X216473I971J1011D01*
G37*
G36*
G01X179662D02*
G03Y12925I277J-289D01*
G02X177720I-971J-1011D01*
G03Y13503I-277J289D01*
G02X179662I971J1011D01*
G37*
G36*
G01X142851D02*
G03Y12925I277J-289D01*
G02X140909I-971J-1011D01*
G03Y13503I-277J289D01*
G02X142851I971J1011D01*
G37*
G36*
G01X1225745Y13289D02*
G03Y12711I277J-289D01*
G02X1223803I-971J-1011D01*
G03Y13289I-277J289D01*
G02X1225745I971J1011D01*
G37*
G36*
G01X1188934D02*
G03Y12711I277J-289D01*
G02X1186992I-971J-1011D01*
G03Y13289I-277J289D01*
G02X1188934I971J1011D01*
G37*
G36*
G01X1152123D02*
G03Y12711I277J-289D01*
G02X1150181I-971J-1011D01*
G03Y13289I-277J289D01*
G02X1152123I971J1011D01*
G37*
G36*
G01X1115311D02*
G03Y12711I277J-289D01*
G02X1113369I-971J-1011D01*
G03Y13289I-277J289D01*
G02X1115311I971J1011D01*
G37*
G36*
G01X934603D02*
G03Y12711I277J-289D01*
G02X932661I-971J-1011D01*
G03Y13289I-277J289D01*
G02X934603I971J1011D01*
G37*
G36*
G01X897792D02*
G03Y12711I277J-289D01*
G02X895850I-971J-1011D01*
G03Y13289I-277J289D01*
G02X897792I971J1011D01*
G37*
G36*
G01X860981D02*
G03Y12711I277J-289D01*
G02X859039I-971J-1011D01*
G03Y13289I-277J289D01*
G02X860981I971J1011D01*
G37*
G36*
G01X824170D02*
G03Y12711I277J-289D01*
G02X822228I-971J-1011D01*
G03Y13289I-277J289D01*
G02X824170I971J1011D01*
G37*
G36*
G01X787359D02*
G03Y12711I277J-289D01*
G02X785417I-971J-1011D01*
G03Y13289I-277J289D01*
G02X787359I971J1011D01*
G37*
G36*
G01X576137D02*
G03Y12711I277J-289D01*
G02X574195I-971J-1011D01*
G03Y13289I-277J289D01*
G02X576137I971J1011D01*
G37*
G36*
G01X539326D02*
G03Y12711I277J-289D01*
G02X537384I-971J-1011D01*
G03Y13289I-277J289D01*
G02X539326I971J1011D01*
G37*
G36*
G01X502515D02*
G03Y12711I277J-289D01*
G02X500573I-971J-1011D01*
G03Y13289I-277J289D01*
G02X502515I971J1011D01*
G37*
G36*
G01X465703D02*
G03Y12711I277J-289D01*
G02X463761I-971J-1011D01*
G03Y13289I-277J289D01*
G02X465703I971J1011D01*
G37*
G36*
G01X284995D02*
G03Y12711I277J-289D01*
G02X283053I-971J-1011D01*
G03Y13289I-277J289D01*
G02X284995I971J1011D01*
G37*
G36*
G01X248184D02*
G03Y12711I277J-289D01*
G02X246242I-971J-1011D01*
G03Y13289I-277J289D01*
G02X248184I971J1011D01*
G37*
G36*
G01X211373D02*
G03Y12711I277J-289D01*
G02X209431I-971J-1011D01*
G03Y13289I-277J289D01*
G02X211373I971J1011D01*
G37*
G36*
G01X174562D02*
G03Y12711I277J-289D01*
G02X172620I-971J-1011D01*
G03Y13289I-277J289D01*
G02X174562I971J1011D01*
G37*
G36*
G01X137751D02*
G03Y12711I277J-289D01*
G02X135809I-971J-1011D01*
G03Y13289I-277J289D01*
G02X137751I971J1011D01*
G37*
G36*
G01X1484135Y10052D02*
X1479135D01*
G02Y13074I0J1511D01*
G01X1484136D01*
G02X1485646Y11573I-1J-1511D01*
G01Y11478D01*
X1485637Y11394D01*
G02X1484135Y10052I-1502J169D01*
G37*
G36*
G01X1465237D02*
X1460237D01*
G02Y13074I0J1511D01*
G01X1465238D01*
G02X1466748Y11573I-1J-1511D01*
G01Y11478D01*
X1466739Y11394D01*
G02X1465237Y10052I-1502J169D01*
G37*
G36*
G01X1441340Y13074D02*
X1446341D01*
G02X1447852Y11573I0J-1512D01*
G01Y11478D01*
X1447842Y11394D01*
G02X1446340Y10052I-1502J169D01*
G01X1441340D01*
G02Y13074I1J1511D01*
G37*
G36*
G01X1427442Y10052D02*
X1422442D01*
G02Y13074I0J1511D01*
G01X1427443D01*
G02X1428954Y11573I0J-1512D01*
G01Y11478D01*
X1428944Y11394D01*
G02X1427442Y10052I-1502J169D01*
G37*
G36*
G01X1728678Y9870D02*
X1723678D01*
G02Y12892I0J1511D01*
G01X1728679D01*
G02X1730190Y11391I0J-1512D01*
G01Y11296D01*
X1730180Y11212D01*
G02X1728678Y9870I-1502J169D01*
G37*
G36*
G01X1681428D02*
X1676428D01*
G02Y12892I0J1511D01*
G01X1681429D01*
G02X1682940Y11391I0J-1512D01*
G01Y11296D01*
X1682930Y11212D01*
G02X1681428Y9870I-1502J169D01*
G37*
G36*
G01X1605898Y9844D02*
X1600898D01*
G02Y12866I0J1511D01*
G01X1605899D01*
G02X1607410Y11365I0J-1512D01*
G01Y11270D01*
X1607400Y11186D01*
G02X1605898Y9844I-1502J169D01*
G37*
G36*
G01X1586998D02*
X1581998D01*
G02Y12866I0J1511D01*
G01X1586999D01*
G02X1588510Y11365I0J-1512D01*
G01Y11270D01*
X1588500Y11186D01*
G02X1586998Y9844I-1502J169D01*
G37*
G36*
G01X1700200Y9806D02*
X1695200D01*
G02Y12828I0J1511D01*
G01X1700201D01*
G02X1701712Y11327I0J-1512D01*
G01Y11232D01*
X1701702Y11148D01*
G02X1700200Y9806I-1502J170D01*
G37*
G36*
G01X1709771Y9750D02*
X1704771D01*
G02Y12772I0J1511D01*
G01X1709772D01*
G02X1711282Y11271I-1J-1511D01*
G01Y11176D01*
X1711273Y11092D01*
G02X1709771Y9750I-1502J169D01*
G37*
G36*
G01X1719297Y9668D02*
X1714297D01*
G02Y12692I0J1512D01*
G01X1719298D01*
G02X1720808Y11190I-1J-1512D01*
G01Y11095D01*
X1720799Y11011D01*
G02X1719297Y9668I-1502J169D01*
G37*
G36*
G01X1643865Y9594D02*
X1638865D01*
G02Y12616I0J1511D01*
G01X1643866D01*
G02X1645376Y11115I-1J-1511D01*
G01Y11020D01*
X1645367Y10936D01*
G02X1643865Y9594I-1502J169D01*
G37*
G36*
G01X1690948Y9214D02*
X1685948D01*
G02Y12236I0J1511D01*
G01X1690949D01*
G02X1692460Y10735I0J-1512D01*
G01Y10640D01*
X1692450Y10556D01*
G02X1690948Y9214I-1502J169D01*
G37*
G36*
G01X1302990Y9175D02*
G03X1302368I-311J-252D01*
G02X1300259Y11020I-1089J883D01*
G03X1300242Y11587I-291J275D01*
G02X1300225Y13618I958J1024D01*
G03Y14192I-278J287D01*
G02X1302289Y16083I976J1007D01*
G03X1302911I311J252D01*
G02X1305089I1089J-883D01*
G03X1305711I311J252D01*
G02X1307775Y14192I1088J-884D01*
G03Y13618I278J-287D01*
G02X1307820Y11648I-975J-1008D01*
G03X1307837Y11081I291J-275D01*
G02X1305790Y9175I-957J-1024D01*
G03X1305168I-311J-252D01*
G02X1302990I-1089J883D01*
G37*
G36*
G01X1663884Y10164D02*
Y10069D01*
X1663875Y9985D01*
G02X1662342Y8643I-1502J169D01*
G01X1657338Y8747D01*
G02X1657400Y11769I31J1511D01*
G01X1662403Y11665D01*
G02X1663884Y10164I-30J-1511D01*
G37*
G36*
G01X1401627Y8990D02*
G03X1401073I-277J-288D01*
G02Y11010I-973J1010D01*
G03X1401627I277J288D01*
G02X1403573I973J-1010D01*
G03X1404127I277J288D01*
G02Y8990I973J-1010D01*
G03X1403573I-277J-288D01*
G02X1401627I-973J1010D01*
G37*
G36*
G01X665011Y9117D02*
G03X664389I-311J-252D01*
G02Y10883I-1089J883D01*
G03X665011I311J252D01*
G02Y9117I1089J-883D01*
G37*
G36*
G01X82642Y10684D02*
G03X82629Y10122I278J-288D01*
G02X80364Y8516I-1019J-963D01*
G03X79806Y8677I-355J-184D01*
G02X78085Y10857I-710J1209D01*
G03X78089Y11406I-289J277D01*
G02X78229Y13446I1027J954D01*
G03X78285Y14009I-253J309D01*
G02X80652Y15467I1087J886D01*
G03X81238Y15297I365J164D01*
G02X82894Y13038I775J-1168D01*
G03X82817Y12497I251J-312D01*
G02X82642Y10684I-1148J-804D01*
G37*
G36*
G01X1259473Y10130D02*
G03X1260036Y10118I288J278D01*
G02X1259991Y8127I964J-1018D01*
G03X1259428Y8139I-288J-278D01*
G02X1259473Y10130I-964J1018D01*
G37*
G36*
G01X1754065Y10273D02*
G03X1754640Y10183I330J226D01*
G02X1754343Y8284I860J-1107D01*
G03X1753768Y8374I-330J-226D01*
G02X1754065Y10273I-860J1107D01*
G37*
G36*
G01X1591848Y12918D02*
X1595849D01*
G02X1597360Y11416I-1J-1512D01*
G01Y11321D01*
X1597350Y11237D01*
G02X1595848Y9894I-1502J169D01*
G01X1593957D01*
G03X1593623Y9274I0J-400D01*
G02X1591378Y9402I-1170J-772D01*
G03X1591234Y10025I-306J257D01*
G02X1591848Y12918I614J1381D01*
G37*
G36*
G01X1436025Y6244D02*
X1431025D01*
G02Y9268I0J1512D01*
G01X1436026D01*
G02X1437536Y7766I-1J-1512D01*
G01Y7671D01*
X1437527Y7587D01*
G02X1436025Y6244I-1502J169D01*
G37*
G36*
G01X1493770Y5398D02*
X1488770D01*
G02Y8420I0J1511D01*
G01X1493771D01*
G02X1495282Y6919I0J-1512D01*
G01Y6824D01*
X1495272Y6740D01*
G02X1493770Y5398I-1502J169D01*
G37*
G36*
G01X1634148Y5314D02*
X1629148D01*
G02Y8336I0J1511D01*
G01X1634149D01*
G02X1635660Y6835I0J-1512D01*
G01Y6740D01*
X1635650Y6656D01*
G02X1634148Y5314I-1502J169D01*
G37*
G36*
G01X1653748Y4814D02*
X1648748D01*
G02Y7836I0J1511D01*
G01X1653749D01*
G02X1655260Y6335I0J-1512D01*
G01Y6240D01*
X1655250Y6156D01*
G02X1653748Y4814I-1502J169D01*
G37*
G36*
G01X1671979Y4724D02*
X1666979D01*
G02Y7748I0J1512D01*
G01X1671979D01*
G02X1673490Y6246I-1J-1512D01*
G01Y6151D01*
X1673481Y6067D01*
G02X1671979Y4724I-1502J168D01*
G37*
G36*
G01X1368378Y4805D02*
G03X1367800I-289J-277D01*
G02Y6747I-1011J971D01*
G03X1368378I289J277D01*
G02Y4805I1011J-971D01*
G37*
G36*
G01X1474388Y4078D02*
X1469388D01*
G02Y7100I0J1511D01*
G01X1474389D01*
G02X1475900Y5599I0J-1512D01*
G01Y5504D01*
X1475890Y5420D01*
G02X1474388Y4078I-1502J169D01*
G37*
G36*
G01X1454991D02*
X1449991D01*
G02Y7100I0J1511D01*
G01X1454992D01*
G02X1456502Y5599I-1J-1511D01*
G01Y5504D01*
X1456493Y5420D01*
G02X1454991Y4078I-1502J169D01*
G37*
G36*
G01X1614833Y3914D02*
X1609833D01*
G02Y6936I0J1511D01*
G01X1614834D01*
G02X1616344Y5435I-1J-1511D01*
G01Y5340D01*
X1616335Y5256D01*
G02X1614833Y3914I-1502J169D01*
G37*
G36*
G01X665442Y3406D02*
G03X664944Y3216I-143J-374D01*
G02X664199Y5171I-1245J645D01*
G03X664697Y5361I143J374D01*
G02X665442Y3406I1245J-645D01*
G37*
G36*
G01X115022Y5064D02*
G03X115000Y4483I263J-301D01*
G02X113078Y4556I-1000J-983D01*
G03X113100Y5137I-263J301D01*
G02X115022Y5064I1000J983D01*
G37*
G36*
G01X1381205Y4584D02*
G03X1381223Y3999I282J-284D01*
G02X1379314Y3941I-923J-1055D01*
G03X1379296Y4526I-282J284D01*
G02X1381205Y4584I923J1055D01*
G37*
G36*
G01X1328965Y4380D02*
G03X1329273Y3898I389J-91D01*
G02X1327952Y1579I-286J-1373D01*
G03X1327378Y1596I-295J-270D01*
G02X1325311Y1717I-978J1004D01*
G03X1324689I-311J-252D01*
G02X1322511I-1089J883D01*
G03X1321889I-311J-252D01*
G02X1319672Y1768I-1089J883D01*
G03X1319028I-322J-238D01*
G02X1316783Y1753I-1128J832D01*
G03X1316140Y1745I-319J-242D01*
G02X1313907Y1694I-1136J822D01*
G03X1313306Y1724I-314J-248D01*
G02X1311211Y1817I-1006J976D01*
G03X1310589I-311J-252D01*
G02X1308411I-1089J883D01*
G03X1307789I-311J-252D01*
G02X1305611I-1089J883D01*
G03X1304989I-311J-252D01*
G02X1302811I-1089J883D01*
G03X1302189I-311J-252D01*
G02X1300664Y4033I-1089J883D01*
G03X1300931Y4499I-124J380D01*
G02X1303389Y5683I1369J301D01*
G03X1304011I311J252D01*
G02X1306189I1089J-883D01*
G03X1306811I311J252D01*
G02X1308989I1089J-883D01*
G03X1309611I311J252D01*
G02X1311789I1089J-883D01*
G03X1312411I311J252D01*
G02X1314621Y5642I1089J-883D01*
G03X1315242Y5620I319J241D01*
G02X1317428Y5532I1058J-920D01*
G03X1318072I322J238D01*
G02X1320289Y5583I1128J-832D01*
G03X1320911I311J252D01*
G02X1323089I1089J-883D01*
G03X1323711I311J252D01*
G02X1325889I1089J-883D01*
G03X1326511I311J252D01*
G02X1328965Y4380I1089J-883D01*
G37*
G36*
G01X1825803Y2785D02*
G03X1825972Y2243I354J-187D01*
G02X1824085Y1656I-648J-1243D01*
G03X1823916Y2198I-354J187D01*
G02X1825803Y2785I648J1243D01*
G37*
G36*
G01X752985Y1288D02*
G03X753584Y1266I309J254D01*
G02X753515Y-588I1016J-966D01*
G03X752916Y-566I-309J-254D01*
G02X752985Y1288I-1016J966D01*
G37*
G36*
G01X1600129Y-1610D02*
G03X1599575I-277J-288D01*
G02Y410I-973J1010D01*
G03X1600129I277J288D01*
G02Y-1610I973J-1010D01*
G37*
G36*
G01X63074Y-533D02*
G03X63194Y-1141I308J-255D01*
G02X61456Y-1484I-659J-1238D01*
G03X61336Y-876I-308J255D01*
G02X63074Y-533I659J1238D01*
G37*
G36*
G01X1381410Y-3782D02*
G03X1381885Y-4168I400J7D01*
G02X1380749Y-5568I266J-1377D01*
G03X1380274Y-5182I-400J-7D01*
G02X1381410Y-3782I-266J1377D01*
G37*
G36*
G01X718771Y-5838D02*
G03X718316Y-6193I-57J-396D01*
G02X717125Y-4661I-1395J145D01*
G03X717580Y-4306I57J396D01*
G02X718771Y-5838I1395J-145D01*
G37*
G36*
G01X1225735Y-5422D02*
G03X1225740Y-6010I274J-292D01*
G02X1223839Y-6029I-940J-1040D01*
G03X1223834Y-5441I-274J292D01*
G02X1225735Y-5422I940J1040D01*
G37*
G36*
G01X1188924D02*
G03X1188929Y-6010I274J-292D01*
G02X1187028Y-6029I-940J-1040D01*
G03X1187023Y-5441I-274J292D01*
G02X1188924Y-5422I940J1040D01*
G37*
G36*
G01X1152113D02*
G03X1152118Y-6010I274J-292D01*
G02X1150217Y-6029I-940J-1040D01*
G03X1150212Y-5441I-274J292D01*
G02X1152113Y-5422I940J1040D01*
G37*
G36*
G01X1115301D02*
G03X1115306Y-6010I274J-292D01*
G02X1113405Y-6029I-940J-1040D01*
G03X1113400Y-5441I-274J292D01*
G02X1115301Y-5422I940J1040D01*
G37*
G36*
G01X934593D02*
G03X934598Y-6010I274J-292D01*
G02X932697Y-6029I-940J-1040D01*
G03X932692Y-5441I-274J292D01*
G02X934593Y-5422I940J1040D01*
G37*
G36*
G01X897782D02*
G03X897787Y-6010I274J-292D01*
G02X895886Y-6029I-940J-1040D01*
G03X895881Y-5441I-274J292D01*
G02X897782Y-5422I940J1040D01*
G37*
G36*
G01X860971D02*
G03X860976Y-6010I274J-292D01*
G02X859075Y-6029I-940J-1040D01*
G03X859070Y-5441I-274J292D01*
G02X860971Y-5422I940J1040D01*
G37*
G36*
G01X824160D02*
G03X824165Y-6010I274J-292D01*
G02X822264Y-6029I-940J-1040D01*
G03X822259Y-5441I-274J292D01*
G02X824160Y-5422I940J1040D01*
G37*
G36*
G01X787349D02*
G03X787354Y-6010I274J-292D01*
G02X785453Y-6029I-940J-1040D01*
G03X785448Y-5441I-274J292D01*
G02X787349Y-5422I940J1040D01*
G37*
G36*
G01X576127D02*
G03X576132Y-6010I274J-292D01*
G02X574231Y-6029I-940J-1040D01*
G03X574226Y-5441I-274J292D01*
G02X576127Y-5422I940J1040D01*
G37*
G36*
G01X539316D02*
G03X539321Y-6010I274J-292D01*
G02X537420Y-6029I-940J-1040D01*
G03X537415Y-5441I-274J292D01*
G02X539316Y-5422I940J1040D01*
G37*
G36*
G01X502505D02*
G03X502510Y-6010I274J-292D01*
G02X500609Y-6029I-940J-1040D01*
G03X500604Y-5441I-274J292D01*
G02X502505Y-5422I940J1040D01*
G37*
G36*
G01X465693D02*
G03X465698Y-6010I274J-292D01*
G02X463797Y-6029I-940J-1040D01*
G03X463792Y-5441I-274J292D01*
G02X465693Y-5422I940J1040D01*
G37*
G36*
G01X284985D02*
G03X284990Y-6010I274J-292D01*
G02X283089Y-6029I-940J-1040D01*
G03X283084Y-5441I-274J292D01*
G02X284985Y-5422I940J1040D01*
G37*
G36*
G01X248174D02*
G03X248179Y-6010I274J-292D01*
G02X246278Y-6029I-940J-1040D01*
G03X246273Y-5441I-274J292D01*
G02X248174Y-5422I940J1040D01*
G37*
G36*
G01X211363D02*
G03X211368Y-6010I274J-292D01*
G02X209467Y-6029I-940J-1040D01*
G03X209462Y-5441I-274J292D01*
G02X211363Y-5422I940J1040D01*
G37*
G36*
G01X174552D02*
G03X174557Y-6010I274J-292D01*
G02X172656Y-6029I-940J-1040D01*
G03X172651Y-5441I-274J292D01*
G02X174552Y-5422I940J1040D01*
G37*
G36*
G01X137741D02*
G03X137746Y-6010I274J-292D01*
G02X135845Y-6029I-940J-1040D01*
G03X135840Y-5441I-274J292D01*
G02X137741Y-5422I940J1040D01*
G37*
G36*
G01X1230841Y-5666D02*
G03Y-6245I276J-290D01*
G02X1228907I-967J-1015D01*
G03Y-5666I-276J290D01*
G02X1230841I967J1015D01*
G37*
G36*
G01X1194030D02*
G03Y-6245I276J-290D01*
G02X1192096I-967J-1015D01*
G03Y-5666I-276J290D01*
G02X1194030I967J1015D01*
G37*
G36*
G01X1157219D02*
G03Y-6245I276J-290D01*
G02X1155285I-967J-1015D01*
G03Y-5666I-276J290D01*
G02X1157219I967J1015D01*
G37*
G36*
G01X1120407D02*
G03Y-6245I276J-290D01*
G02X1118473I-967J-1015D01*
G03Y-5666I-276J290D01*
G02X1120407I967J1015D01*
G37*
G36*
G01X939699D02*
G03Y-6245I276J-290D01*
G02X937765I-967J-1015D01*
G03Y-5666I-276J290D01*
G02X939699I967J1015D01*
G37*
G36*
G01X902888D02*
G03Y-6245I276J-290D01*
G02X900954I-967J-1015D01*
G03Y-5666I-276J290D01*
G02X902888I967J1015D01*
G37*
G36*
G01X866077D02*
G03Y-6245I276J-290D01*
G02X864143I-967J-1015D01*
G03Y-5666I-276J290D01*
G02X866077I967J1015D01*
G37*
G36*
G01X829266D02*
G03Y-6245I276J-290D01*
G02X827332I-967J-1015D01*
G03Y-5666I-276J290D01*
G02X829266I967J1015D01*
G37*
G36*
G01X792455D02*
G03Y-6245I276J-290D01*
G02X790521I-967J-1015D01*
G03Y-5666I-276J290D01*
G02X792455I967J1015D01*
G37*
G36*
G01X581233D02*
G03Y-6245I276J-290D01*
G02X579299I-967J-1015D01*
G03Y-5666I-276J290D01*
G02X581233I967J1015D01*
G37*
G36*
G01X544422D02*
G03Y-6245I276J-290D01*
G02X542488I-967J-1015D01*
G03Y-5666I-276J290D01*
G02X544422I967J1015D01*
G37*
G36*
G01X507611D02*
G03Y-6245I276J-290D01*
G02X505677I-967J-1015D01*
G03Y-5666I-276J290D01*
G02X507611I967J1015D01*
G37*
G36*
G01X470799D02*
G03Y-6245I276J-290D01*
G02X468865I-967J-1015D01*
G03Y-5666I-276J290D01*
G02X470799I967J1015D01*
G37*
G36*
G01X290091D02*
G03Y-6245I276J-290D01*
G02X288157I-967J-1015D01*
G03Y-5666I-276J290D01*
G02X290091I967J1015D01*
G37*
G36*
G01X253280D02*
G03Y-6245I276J-290D01*
G02X251346I-967J-1015D01*
G03Y-5666I-276J290D01*
G02X253280I967J1015D01*
G37*
G36*
G01X216469D02*
G03Y-6245I276J-290D01*
G02X214535I-967J-1015D01*
G03Y-5666I-276J290D01*
G02X216469I967J1015D01*
G37*
G36*
G01X179658D02*
G03Y-6245I276J-290D01*
G02X177724I-967J-1015D01*
G03Y-5666I-276J290D01*
G02X179658I967J1015D01*
G37*
G36*
G01X142847D02*
G03Y-6245I276J-290D01*
G02X140913I-967J-1015D01*
G03Y-5666I-276J290D01*
G02X142847I967J1015D01*
G37*
G36*
G01X647971Y-10511D02*
G03Y-11089I277J-289D01*
G02X646029I-971J-1011D01*
G03Y-10511I-277J289D01*
G02X646208Y-8343I971J1011D01*
G03X646297Y-7766I-226J330D01*
G02X648192Y-8057I1103J866D01*
G03X648103Y-8634I226J-330D01*
G02X647971Y-10511I-1103J-866D01*
G37*
G36*
G01X64936Y-12238D02*
G03X65464Y-12420I357J180D01*
G02X64808Y-14317I597J-1268D01*
G03X64280Y-14135I-357J-180D01*
G02X64936Y-12238I-597J1268D01*
G37*
G36*
G01X730372Y-16258D02*
G03X729818Y-16331I-240J-320D01*
G02X727466Y-16100I-1102J866D01*
G03X726936Y-15921I-356J-181D01*
G02X725354Y-15668I-609J1263D01*
G03X724800I-277J-288D01*
G02Y-13648I-973J1010D01*
G03X725354I277J288D01*
G02X726891Y-13374I973J-1010D01*
G03X727448Y-12954I161J366D01*
G02X729716Y-13856I1389J191D01*
G03X729689Y-14455I250J-311D01*
G02X729693Y-14460I-1084J-871D01*
G03X730004Y-14418I139J144D01*
G02X730372Y-16258I1206J-716D01*
G37*
G36*
G01X1585527Y-17110D02*
G03X1584973I-277J-288D01*
G02Y-15090I-973J1010D01*
G03X1585527I277J288D01*
G02Y-17110I973J-1010D01*
G37*
G36*
G01X42908Y-15061D02*
G03X43095Y-15617I351J-191D01*
G02X41289Y-16225I-575J-1279D01*
G03X41102Y-15669I-351J191D01*
G02X42908Y-15061I575J1279D01*
G37*
G36*
G01X1375736Y-17802D02*
G03X1375155Y-17824I-280J-285D01*
G02X1373046I-1055J924D01*
G03X1372502Y-17769I-301J-263D01*
G02X1370658Y-15667I-849J1115D01*
G03X1370647Y-15093I-284J282D01*
G02X1370569Y-13124I958J1024D01*
G03X1370568Y-12584I-296J269D01*
G02X1370580Y-10669I1030J951D01*
G03X1370588Y-10127I-290J275D01*
G02X1372650Y-10155I1044J936D01*
G03X1372642Y-10697I290J-275D01*
G02X1372634Y-12578I-1044J-936D01*
G03X1372635Y-13118I296J-269D01*
G02X1372600Y-15056I-1030J-951D01*
G03X1372611Y-15630I284J-282D01*
G02X1372707Y-15730I-962J-1020D01*
G03X1373251Y-15785I301J263D01*
G02X1375083Y-15900I850J-1115D01*
G03X1375664Y-15878I280J285D01*
G02X1375736Y-17802I1055J-924D01*
G37*
G36*
G01X1316783Y-17747D02*
G03X1316140Y-17755I-319J-242D01*
G02X1313907Y-17806I-1136J822D01*
G03X1313306Y-17776I-314J-248D01*
G02X1311211Y-17683I-1006J976D01*
G03X1310589I-311J-252D01*
G02X1308411I-1089J883D01*
G03X1307789I-311J-252D01*
G02X1306264Y-15467I-1089J883D01*
G03X1306531Y-15001I-124J380D01*
G02X1308989Y-13817I1369J301D01*
G03X1309611I311J252D01*
G02X1311789I1089J-883D01*
G03X1312411I311J252D01*
G02X1314621Y-13858I1089J-883D01*
G03X1315242Y-13880I319J241D01*
G02X1317428Y-13968I1058J-920D01*
G03X1318072I322J238D01*
G02X1320289Y-13917I1128J-832D01*
G03X1320911I311J252D01*
G02X1321879Y-13403I1089J-883D01*
G03X1322234Y-12915I-35J398D01*
G02X1324577Y-11595I1366J315D01*
G03X1325110Y-11617I279J287D01*
G02X1327089Y-11817I890J-1083D01*
G03X1327711I311J252D01*
G02X1329236Y-14033I1089J-883D01*
G03X1328969Y-14499I124J-380D01*
G02X1328036Y-16133I-1369J-302D01*
G03X1327769Y-16599I124J-380D01*
G02X1325311Y-17783I-1369J-301D01*
G03X1324689I-311J-252D01*
G02X1322511I-1089J883D01*
G03X1321889I-311J-252D01*
G02X1319672Y-17732I-1089J883D01*
G03X1319028I-322J-238D01*
G02X1316783Y-17747I-1128J832D01*
G37*
G36*
G01X1606531Y-18356D02*
G03X1605977I-277J-288D01*
G02Y-16336I-973J1010D01*
G03X1606531I277J288D01*
G02X1608477I973J-1010D01*
G03X1609031I277J288D01*
G02Y-18356I973J-1010D01*
G03X1608477I-277J-288D01*
G02X1606531I-973J1010D01*
G37*
G36*
G01X1596531D02*
G03X1595977I-277J-288D01*
G02Y-16336I-973J1010D01*
G03X1596531I277J288D01*
G02X1598477I973J-1010D01*
G03X1599031I277J288D01*
G02Y-18356I973J-1010D01*
G03X1598477I-277J-288D01*
G02X1596531I-973J1010D01*
G37*
G36*
G01X661185Y-16750D02*
G03X661784Y-16839I338J214D01*
G02X661515Y-18650I916J-1062D01*
G03X660916Y-18561I-338J-214D01*
G02X661185Y-16750I-916J1062D01*
G37*
G36*
G01X1300366Y-16666D02*
G03X1300430Y-17281I284J-281D01*
G02X1298511Y-17399I-881J-1338D01*
G03X1298500Y-16780I-259J305D01*
G02X1300366Y-16666I869J1100D01*
G37*
G36*
G01X21111Y-18129D02*
G03X21683Y-18241I339J213D01*
G02X21312Y-20127I816J-1140D01*
G03X20740Y-20015I-339J-213D01*
G02X21111Y-18129I-816J1140D01*
G37*
G36*
G01X709720Y-17986D02*
G03X710115Y-18437I397J-51D01*
G02X708717Y-19659I-8J-1402D01*
G03X708322Y-19208I-397J51D01*
G02X709720Y-17986I8J1402D01*
G37*
G36*
G01X1902168Y-18425D02*
G02X1901892Y-20014I992J-991D01*
G03X1901248Y-19902I-361J-171D01*
G02X1901524Y-18313I-992J991D01*
G03X1902168Y-18425I361J171D01*
G37*
G36*
G01X304756Y-318D02*
X303228D01*
Y6784D01*
X304756D01*
Y10313D01*
G03X304350Y10712I-400J-1D01*
G02Y13516I-22J1402D01*
G03X304756Y13915I6J400D01*
G01Y14495D01*
X304805Y14664D01*
X304807Y14671D01*
G03Y14957I-479J143D01*
G01X304805Y14964D01*
X304756Y15133D01*
Y29630D01*
X304805Y29799D01*
X304807Y29806D01*
G03Y30092I-479J143D01*
G01X304805Y30099D01*
X304756Y30268D01*
Y32299D01*
G03X304350Y32698I-400J-1D01*
G02Y35502I-22J1402D01*
G03X304756Y35901I6J400D01*
G01Y37482D01*
X303228D01*
Y44584D01*
X304756D01*
Y48113D01*
G03X304350Y48512I-400J-1D01*
G02Y51316I-22J1402D01*
G03X304756Y51715I6J400D01*
G01Y52295D01*
X304805Y52464D01*
X304807Y52471D01*
G03Y52757I-479J143D01*
G01X304805Y52764D01*
X304756Y52933D01*
Y67430D01*
X304805Y67599D01*
X304807Y67606D01*
G03Y67892I-479J143D01*
G01X304805Y67899D01*
X304756Y68068D01*
Y70099D01*
G03X304350Y70498I-400J-1D01*
G02Y73302I-22J1402D01*
G03X304756Y73701I6J400D01*
G01Y75282D01*
X303228D01*
Y82384D01*
X304756D01*
Y85913D01*
G03X304350Y86312I-400J-1D01*
G02Y89116I-22J1402D01*
G03X304756Y89515I6J400D01*
G01Y90191D01*
X304769Y90307D01*
X304773Y90334D01*
G03X304774Y90485I-495J79D01*
G01X304756Y90578D01*
Y98081D01*
X304816Y98140D01*
Y101240D01*
X319540Y115965D01*
Y123515D01*
X329440Y133415D01*
Y136465D01*
X334790Y141815D01*
Y158245D01*
G03X334063Y158474I-400J0D01*
G02Y168690I-7291J5108D01*
G03X334790Y168919I327J229D01*
G01Y182065D01*
X336290Y183565D01*
Y190565D01*
X338340Y192615D01*
Y201166D01*
X338330Y201198D01*
G02X338290Y201968I1326J455D01*
G02X337673Y204037I548J1290D01*
G02X337240Y205049I969J1013D01*
G01Y205367D01*
G02X337673Y206379I1402J-1D01*
G02Y207937I1165J779D01*
G02X337240Y208949I969J1013D01*
G01Y209267D01*
G02X338794Y210660I1402J0D01*
G03Y211456I44J398D01*
G02X337240Y212849I-152J1393D01*
G01Y213169D01*
G02X337673Y214181I1402J-1D01*
G02Y215739I1165J779D01*
G02X337240Y216751I969J1013D01*
G01Y219653D01*
G03X336534Y219910I-400J0D01*
G02X336664Y221524I-1076J899D01*
G03X337371Y221559I344J204D01*
G02X337673Y221981I1271J-590D01*
G02Y223539I1165J779D01*
G02X337240Y224551I969J1013D01*
G01Y228315D01*
X337888Y228963D01*
G03X337879Y229537I-283J283D01*
G02X338723Y231957I959J1023D01*
G03X339090Y232355I-33J399D01*
G01Y234046D01*
X339199Y234287D01*
X339201Y234292D01*
G03Y234628I-363J168D01*
G01X339199Y234633D01*
X339090Y234874D01*
Y237946D01*
X339199Y238187D01*
X339201Y238192D01*
G03Y238528I-363J168D01*
G01X339199Y238533D01*
X339090Y238774D01*
Y241846D01*
X339199Y242087D01*
X339201Y242092D01*
G03Y242428I-363J168D01*
G01X339199Y242433D01*
X339090Y242674D01*
Y245765D01*
X340912Y247586D01*
X340877Y247701D01*
G02X343596Y248365I1341J408D01*
G01X343627Y248202D01*
X343915D01*
G02X345137Y247484I-2J-1402D01*
G02X346059I461J-1324D01*
G02X347281Y248202I1224J-684D01*
G01X348373D01*
X348673Y247849D01*
G03X349283I305J260D01*
G01X349583Y248202D01*
X350674D01*
G02X351896Y247484I-2J-1402D01*
G02X352818I461J-1324D01*
G02X354040Y248202I1224J-684D01*
G01X355132D01*
X355432Y247849D01*
G03X356042I305J260D01*
G01X356342Y248202D01*
X357434D01*
G02X358656Y247484I-2J-1402D01*
G02X359578I461J-1324D01*
G02X360800Y248202I1224J-684D01*
G01X361088D01*
X361119Y248365D01*
G02X363898Y248052I1378J-257D01*
G01X363894Y247964D01*
X364791Y247067D01*
X364932Y247196D01*
G02X367225Y246546I945J-1036D01*
G01X367266Y246402D01*
X368017D01*
G03X368292Y247092I0J400D01*
G02X370222I965J1017D01*
G03X370497Y246402I275J-290D01*
G01X371248D01*
X371289Y246546D01*
G02X373339Y244946I1348J-386D01*
G03X373171Y244444I200J-346D01*
G02X373257Y244159I-1291J-545D01*
G03X373818Y243872I393J76D01*
G02X374406Y244002I590J-1272D01*
G01X374615D01*
Y244202D01*
G02X377406Y244015I1402J6D01*
G01X377392Y243917D01*
X377953Y243355D01*
G03X378494Y243332I283J283D01*
G02X380345Y241227I903J-1072D01*
G03X380318Y240964I136J-147D01*
G02X380575Y240257I-1140J-815D01*
G03X381022Y239891I399J31D01*
G01X381024D01*
G03X381375Y240293I-49J397D01*
G02X384179I1402J16D01*
G03X384530Y239891I400J-5D01*
G02X385757Y238391I-170J-1391D01*
G03X386557I400J-31D01*
G02X387784Y239891I1397J109D01*
G03X388135Y240293I-49J397D01*
G02X390939I1402J16D01*
G03X391290Y239891I400J-5D01*
G02X392516Y238391I-171J-1391D01*
G03X393316I400J-31D01*
G02X394543Y239891I1397J109D01*
G03X394894Y240293I-49J397D01*
G02X397698I1402J16D01*
G03X398049Y239891I400J-5D01*
G02X398190Y239867I-164J-1392D01*
G03X398677Y240226I89J390D01*
G02X398890Y240867I1398J-109D01*
G03X398841Y241134I-169J107D01*
G02X400947Y242852I835J1126D01*
G01X406180D01*
G03X406518Y243464I-1J400D01*
G02X408757Y243281I1188J745D01*
G03X408774Y242734I300J-264D01*
G01X413660Y237849D01*
Y197681D01*
X415010Y196331D01*
Y161085D01*
X414294Y160369D01*
Y142515D01*
X415192Y141617D01*
Y133413D01*
X448966Y99639D01*
Y90535D01*
X448484Y90242D01*
G03Y89558I208J-342D01*
G01X448966Y89265D01*
Y85932D01*
X448426Y85651D01*
G03Y84941I184J-355D01*
G01X448966Y84660D01*
Y76088D01*
G02X448434Y73953I-1109J-857D01*
G03X448339Y73284I165J-365D01*
G02X448379Y71191I-911J-1064D01*
G03X448397Y70587I272J-294D01*
G02X448379Y68404I-888J-1084D01*
G03X448596Y67691I248J-314D01*
G02X449818Y66736I-108J-1397D01*
G03X450503Y66604I380J126D01*
G02X452477Y64627I1071J-905D01*
G01X452406Y64567D01*
Y64274D01*
X452674D01*
Y57172D01*
X450470D01*
Y64274D01*
X450740D01*
Y64567D01*
X450669Y64627D01*
G02X450574Y64715I904J1072D01*
G03X449890Y64434I-284J-281D01*
G01Y62408D01*
X448966Y61484D01*
Y55552D01*
X448637Y55254D01*
G03Y54512I336J-371D01*
G01X448966Y54214D01*
Y51694D01*
X448311Y51358D01*
X448310Y51357D01*
G03Y50643I182J-357D01*
G01X448311Y50642D01*
X448966Y50306D01*
Y47753D01*
X448295Y47424D01*
G03Y46526I222J-449D01*
G01X448966Y46197D01*
Y36684D01*
X447997Y36491D01*
X447996D01*
G03X447644Y36223I96J-491D01*
G02X447499Y35992I-1254J626D01*
G02X447650Y35765I-1086J-886D01*
G03X448108Y35499I442J235D01*
G03X448248Y35397I300J265D01*
G01X448250Y35396D01*
X448966Y35077D01*
Y32555D01*
X448158Y32278D01*
G03X447930Y31729I134J-378D01*
G02X447825Y30701I-906J-427D01*
G03X447877Y30040I401J-301D01*
G02X447930Y28370I-836J-862D01*
G03X448111Y27717I296J-270D01*
G01X448112D01*
X448966Y27458D01*
Y17694D01*
X448583Y17394D01*
G03Y16606I309J-394D01*
G01X448966Y16306D01*
Y14355D01*
X448158Y14078D01*
G03X447993Y13434I134J-377D01*
G02X448345Y12497I-1050J-929D01*
G02X448966Y9909I-119J-1397D01*
G01Y59D01*
X448972Y53D01*
Y-4695D01*
X449376Y-5100D01*
Y-6838D01*
X448020D01*
X447860Y-6797D01*
X447851Y-6794D01*
G03X447795Y-7577I-107J-386D01*
G02X449376Y-8967I180J-1390D01*
G01Y-16945D01*
X447372Y-18950D01*
G02X446837Y-19283I-989J993D01*
G02X446502Y-19819I-1325J456D01*
G01X445978Y-20344D01*
X436703D01*
X436661Y-20338D01*
X436600D01*
X436485Y-20311D01*
G03X436299I-93J-389D01*
G01X436289Y-20313D01*
X436151Y-20344D01*
X423203D01*
X423161Y-20338D01*
X423100D01*
X422985Y-20311D01*
G03X422799I-93J-389D01*
G01X422789Y-20313D01*
X422651Y-20344D01*
X409203D01*
X409161Y-20338D01*
X409100D01*
X408985Y-20311D01*
G03X408799I-93J-389D01*
G01X408789Y-20313D01*
X408651Y-20344D01*
X394203D01*
X394161Y-20338D01*
X394100D01*
X393985Y-20311D01*
G03X393799I-93J-389D01*
G01X393789Y-20313D01*
X393651Y-20344D01*
X326827D01*
X326595Y-20242D01*
X326594D01*
G03X326190I-202J-458D01*
G01X326189D01*
X325957Y-20344D01*
X307893D01*
X307369Y-19819D01*
G02X306958Y-18828I991J992D01*
G03X306573Y-18429I-400J0D01*
G03X306174Y-18044I-399J-15D01*
G02X305183Y-17633I1J1402D01*
G01X304756Y-17207D01*
Y-8170D01*
X304805Y-8001D01*
X304807Y-7994D01*
G03Y-7708I-479J143D01*
G01X304805Y-7701D01*
X304756Y-7532D01*
Y-5501D01*
G03X304350Y-5102I-400J-1D01*
G02Y-2298I-22J1402D01*
G03X304756Y-1899I6J400D01*
G01Y-318D01*
G37*
G36*
G01X714334Y-17027D02*
G02X712514Y-17832I-510J-1306D01*
G03X712286Y-17317I-373J143D01*
G02X711398Y-16115I510J1306D01*
G03X710836Y-15780I-399J-30D01*
G02X709291Y-13490I-573J1280D01*
G03X709305Y-12928I-277J288D01*
G02X711299Y-12978I1022J960D01*
G03X711285Y-13540I277J-288D01*
G02X711661Y-14396I-1022J-960D01*
G03X712223Y-14731I399J30D01*
G02X714106Y-16512I573J-1280D01*
G03X714334Y-17027I373J-143D01*
G37*
G36*
G01X1674935Y-17561D02*
G02X1674904Y-16078I-1435J712D01*
G03X1675602Y-16084I351J193D01*
G02X1675632Y-17526I1217J-696D01*
G03X1674935Y-17561I-339J-213D01*
G37*
G36*
G01X124524Y-10973D02*
X124453Y-11033D01*
Y-11326D01*
X124722D01*
Y-18428D01*
X122518D01*
Y-11326D01*
X122787D01*
Y-11033D01*
X122716Y-10973D01*
G02X124524I904J1072D01*
G37*
G36*
G01X131217D02*
X131146Y-11033D01*
Y-11326D01*
X131414D01*
Y-18428D01*
X129212D01*
Y-11326D01*
X129480D01*
Y-11033D01*
X129409Y-10973D01*
G02X131217I904J1072D01*
G37*
G36*
G01X147949D02*
X147878Y-11033D01*
Y-11326D01*
X148146D01*
Y-18428D01*
X145944D01*
Y-11326D01*
X146212D01*
Y-11033D01*
X146141Y-10973D01*
G02X147949I904J1072D01*
G37*
G36*
G01X154642D02*
X154571Y-11033D01*
Y-11326D01*
X154840D01*
Y-18428D01*
X152636D01*
Y-11326D01*
X152905D01*
Y-11033D01*
X152834Y-10973D01*
G02X154642I904J1072D01*
G37*
G36*
G01X161335D02*
X161264Y-11033D01*
Y-11326D01*
X161532D01*
Y-18428D01*
X159330D01*
Y-11326D01*
X159598D01*
Y-11033D01*
X159527Y-10973D01*
G02X161335I904J1072D01*
G37*
G36*
G01X168028D02*
X167957Y-11033D01*
Y-11326D01*
X168226D01*
Y-18428D01*
X166022D01*
Y-11326D01*
X166291D01*
Y-11033D01*
X166220Y-10973D01*
G02X168028I904J1072D01*
G37*
G36*
G01X184760D02*
X184689Y-11033D01*
Y-11326D01*
X184958D01*
Y-18428D01*
X182754D01*
Y-11326D01*
X183023D01*
Y-11033D01*
X182952Y-10973D01*
G02X184760I904J1072D01*
G37*
G36*
G01X191453D02*
X191382Y-11033D01*
Y-11326D01*
X191650D01*
Y-18428D01*
X189448D01*
Y-11326D01*
X189716D01*
Y-11033D01*
X189645Y-10973D01*
G02X191453I904J1072D01*
G37*
G36*
G01X198146D02*
X198075Y-11033D01*
Y-11326D01*
X198344D01*
Y-18428D01*
X196140D01*
Y-11326D01*
X196409D01*
Y-11033D01*
X196338Y-10973D01*
G02X198146I904J1072D01*
G37*
G36*
G01X204839D02*
X204768Y-11033D01*
Y-11326D01*
X205036D01*
Y-18428D01*
X202834D01*
Y-11326D01*
X203102D01*
Y-11033D01*
X203031Y-10973D01*
G02X204839I904J1072D01*
G37*
G36*
G01X221571D02*
X221500Y-11033D01*
Y-11326D01*
X221768D01*
Y-18428D01*
X219566D01*
Y-11326D01*
X219834D01*
Y-11033D01*
X219763Y-10973D01*
G02X221571I904J1072D01*
G37*
G36*
G01X228264D02*
X228193Y-11033D01*
Y-11326D01*
X228462D01*
Y-18428D01*
X226258D01*
Y-11326D01*
X226527D01*
Y-11033D01*
X226456Y-10973D01*
G02X228264I904J1072D01*
G37*
G36*
G01X234957D02*
X234886Y-11033D01*
Y-11326D01*
X235154D01*
Y-18428D01*
X232952D01*
Y-11326D01*
X233220D01*
Y-11033D01*
X233149Y-10973D01*
G02X234957I904J1072D01*
G37*
G36*
G01X241650D02*
X241579Y-11033D01*
Y-11326D01*
X241848D01*
Y-18428D01*
X239644D01*
Y-11326D01*
X239913D01*
Y-11033D01*
X239842Y-10973D01*
G02X241650I904J1072D01*
G37*
G36*
G01X258382D02*
X258311Y-11033D01*
Y-11326D01*
X258580D01*
Y-18428D01*
X256376D01*
Y-11326D01*
X256645D01*
Y-11033D01*
X256574Y-10973D01*
G02X258382I904J1072D01*
G37*
G36*
G01X265075D02*
X265004Y-11033D01*
Y-11326D01*
X265272D01*
Y-18428D01*
X263070D01*
Y-11326D01*
X263338D01*
Y-11033D01*
X263267Y-10973D01*
G02X265075I904J1072D01*
G37*
G36*
G01X271768D02*
X271697Y-11033D01*
Y-11326D01*
X271966D01*
Y-18428D01*
X269762D01*
Y-11326D01*
X270031D01*
Y-11033D01*
X269960Y-10973D01*
G02X271768I904J1072D01*
G37*
G36*
G01X278461D02*
X278390Y-11033D01*
Y-11326D01*
X278658D01*
Y-18428D01*
X276456D01*
Y-11326D01*
X276724D01*
Y-11033D01*
X276653Y-10973D01*
G02X278461I904J1072D01*
G37*
G36*
G01X295193D02*
X295122Y-11033D01*
Y-11326D01*
X295390D01*
Y-18428D01*
X293188D01*
Y-11326D01*
X293456D01*
Y-11033D01*
X293385Y-10973D01*
G02X295193I904J1072D01*
G37*
G36*
G01X301886D02*
X301815Y-11033D01*
Y-11326D01*
X302084D01*
Y-18428D01*
X299882D01*
Y-11326D01*
X300149D01*
Y-11033D01*
X300078Y-10973D01*
G02X301886I904J1072D01*
G37*
G36*
G01X452477D02*
X452406Y-11033D01*
Y-11326D01*
X452674D01*
Y-18428D01*
X450470D01*
Y-11326D01*
X450740D01*
Y-11033D01*
X450669Y-10973D01*
G02X452477I904J1072D01*
G37*
G36*
G01X459170D02*
X459099Y-11033D01*
Y-11326D01*
X459366D01*
Y-18428D01*
X457164D01*
Y-11326D01*
X457433D01*
Y-11033D01*
X457362Y-10973D01*
G02X459170I904J1072D01*
G37*
G36*
G01X475902D02*
X475831Y-11033D01*
Y-11326D01*
X476100D01*
Y-18428D01*
X473896D01*
Y-11326D01*
X474165D01*
Y-11033D01*
X474094Y-10973D01*
G02X475902I904J1072D01*
G37*
G36*
G01X482595D02*
X482524Y-11033D01*
Y-11326D01*
X482792D01*
Y-18428D01*
X480590D01*
Y-11326D01*
X480858D01*
Y-11033D01*
X480787Y-10973D01*
G02X482595I904J1072D01*
G37*
G36*
G01X489288D02*
X489217Y-11033D01*
Y-11326D01*
X489484D01*
Y-18428D01*
X487282D01*
Y-11326D01*
X487551D01*
Y-11033D01*
X487480Y-10973D01*
G02X489288I904J1072D01*
G37*
G36*
G01X495981D02*
X495910Y-11033D01*
Y-11326D01*
X496178D01*
Y-18428D01*
X493974D01*
Y-11326D01*
X494244D01*
Y-11033D01*
X494173Y-10973D01*
G02X495981I904J1072D01*
G37*
G36*
G01X512713D02*
X512642Y-11033D01*
Y-11326D01*
X512910D01*
Y-18428D01*
X510708D01*
Y-11326D01*
X510976D01*
Y-11033D01*
X510905Y-10973D01*
G02X512713I904J1072D01*
G37*
G36*
G01X519406D02*
X519335Y-11033D01*
Y-11326D01*
X519604D01*
Y-18428D01*
X517400D01*
Y-11326D01*
X517669D01*
Y-11033D01*
X517598Y-10973D01*
G02X519406I904J1072D01*
G37*
G36*
G01X526099D02*
X526028Y-11033D01*
Y-11326D01*
X526296D01*
Y-18428D01*
X524092D01*
Y-11326D01*
X524362D01*
Y-11033D01*
X524291Y-10973D01*
G02X526099I904J1072D01*
G37*
G36*
G01X532792D02*
X532721Y-11033D01*
Y-11326D01*
X532988D01*
Y-18428D01*
X530786D01*
Y-11326D01*
X531055D01*
Y-11033D01*
X530984Y-10973D01*
G02X532792I904J1072D01*
G37*
G36*
G01X549524D02*
X549453Y-11033D01*
Y-11326D01*
X549722D01*
Y-18428D01*
X547518D01*
Y-11326D01*
X547787D01*
Y-11033D01*
X547716Y-10973D01*
G02X549524I904J1072D01*
G37*
G36*
G01X556217D02*
X556146Y-11033D01*
Y-11326D01*
X556414D01*
Y-18428D01*
X554212D01*
Y-11326D01*
X554480D01*
Y-11033D01*
X554409Y-10973D01*
G02X556217I904J1072D01*
G37*
G36*
G01X562910D02*
X562839Y-11033D01*
Y-11326D01*
X563106D01*
Y-18428D01*
X560904D01*
Y-11326D01*
X561173D01*
Y-11033D01*
X561102Y-10973D01*
G02X562910I904J1072D01*
G37*
G36*
G01X569603D02*
X569532Y-11033D01*
Y-11326D01*
X569800D01*
Y-18428D01*
X567596D01*
Y-11326D01*
X567866D01*
Y-11033D01*
X567795Y-10973D01*
G02X569603I904J1072D01*
G37*
G36*
G01X586335D02*
X586264Y-11033D01*
Y-11326D01*
X586532D01*
Y-18428D01*
X584330D01*
Y-11326D01*
X584598D01*
Y-11033D01*
X584527Y-10973D01*
G02X586335I904J1072D01*
G37*
G36*
G01X593028D02*
X592957Y-11033D01*
Y-11326D01*
X593226D01*
Y-18428D01*
X591022D01*
Y-11326D01*
X591291D01*
Y-11033D01*
X591220Y-10973D01*
G02X593028I904J1072D01*
G37*
G36*
G01X774132D02*
X774061Y-11033D01*
Y-11326D01*
X774330D01*
Y-18428D01*
X772126D01*
Y-11326D01*
X772395D01*
Y-11033D01*
X772324Y-10973D01*
G02X774132I904J1072D01*
G37*
G36*
G01X780825D02*
X780754Y-11033D01*
Y-11326D01*
X781022D01*
Y-18428D01*
X778820D01*
Y-11326D01*
X779088D01*
Y-11033D01*
X779017Y-10973D01*
G02X780825I904J1072D01*
G37*
G36*
G01X797557D02*
X797486Y-11033D01*
Y-11326D01*
X797754D01*
Y-18428D01*
X795552D01*
Y-11326D01*
X795820D01*
Y-11033D01*
X795749Y-10973D01*
G02X797557I904J1072D01*
G37*
G36*
G01X804250D02*
X804179Y-11033D01*
Y-11326D01*
X804448D01*
Y-18428D01*
X802244D01*
Y-11326D01*
X802513D01*
Y-11033D01*
X802442Y-10973D01*
G02X804250I904J1072D01*
G37*
G36*
G01X810943D02*
X810872Y-11033D01*
Y-11326D01*
X811140D01*
Y-18428D01*
X808938D01*
Y-11326D01*
X809206D01*
Y-11033D01*
X809135Y-10973D01*
G02X810943I904J1072D01*
G37*
G36*
G01X817636D02*
X817565Y-11033D01*
Y-11326D01*
X817834D01*
Y-18428D01*
X815630D01*
Y-11326D01*
X815899D01*
Y-11033D01*
X815828Y-10973D01*
G02X817636I904J1072D01*
G37*
G36*
G01X834368D02*
X834297Y-11033D01*
Y-11326D01*
X834566D01*
Y-18428D01*
X832362D01*
Y-11326D01*
X832631D01*
Y-11033D01*
X832560Y-10973D01*
G02X834368I904J1072D01*
G37*
G36*
G01X841061D02*
X840990Y-11033D01*
Y-11326D01*
X841258D01*
Y-18428D01*
X839056D01*
Y-11326D01*
X839324D01*
Y-11033D01*
X839253Y-10973D01*
G02X841061I904J1072D01*
G37*
G36*
G01X847754D02*
X847683Y-11033D01*
Y-11326D01*
X847952D01*
Y-18428D01*
X845748D01*
Y-11326D01*
X846017D01*
Y-11033D01*
X845946Y-10973D01*
G02X847754I904J1072D01*
G37*
G36*
G01X854447D02*
X854376Y-11033D01*
Y-11326D01*
X854644D01*
Y-18428D01*
X852442D01*
Y-11326D01*
X852710D01*
Y-11033D01*
X852639Y-10973D01*
G02X854447I904J1072D01*
G37*
G36*
G01X871179D02*
X871108Y-11033D01*
Y-11326D01*
X871376D01*
Y-18428D01*
X869174D01*
Y-11326D01*
X869442D01*
Y-11033D01*
X869371Y-10973D01*
G02X871179I904J1072D01*
G37*
G36*
G01X877872D02*
X877801Y-11033D01*
Y-11326D01*
X878070D01*
Y-18428D01*
X875866D01*
Y-11326D01*
X876135D01*
Y-11033D01*
X876064Y-10973D01*
G02X877872I904J1072D01*
G37*
G36*
G01X884565D02*
X884494Y-11033D01*
Y-11326D01*
X884762D01*
Y-18428D01*
X882560D01*
Y-11326D01*
X882828D01*
Y-11033D01*
X882757Y-10973D01*
G02X884565I904J1072D01*
G37*
G36*
G01X891258D02*
X891187Y-11033D01*
Y-11326D01*
X891456D01*
Y-18428D01*
X889252D01*
Y-11326D01*
X889521D01*
Y-11033D01*
X889450Y-10973D01*
G02X891258I904J1072D01*
G37*
G36*
G01X907990D02*
X907919Y-11033D01*
Y-11326D01*
X908188D01*
Y-18428D01*
X905984D01*
Y-11326D01*
X906253D01*
Y-11033D01*
X906182Y-10973D01*
G02X907990I904J1072D01*
G37*
G36*
G01X914683D02*
X914612Y-11033D01*
Y-11326D01*
X914880D01*
Y-18428D01*
X912678D01*
Y-11326D01*
X912946D01*
Y-11033D01*
X912875Y-10973D01*
G02X914683I904J1072D01*
G37*
G36*
G01X921376D02*
X921305Y-11033D01*
Y-11326D01*
X921574D01*
Y-18428D01*
X919370D01*
Y-11326D01*
X919639D01*
Y-11033D01*
X919568Y-10973D01*
G02X921376I904J1072D01*
G37*
G36*
G01X928069D02*
X927998Y-11033D01*
Y-11326D01*
X928266D01*
Y-18428D01*
X926064D01*
Y-11326D01*
X926332D01*
Y-11033D01*
X926261Y-10973D01*
G02X928069I904J1072D01*
G37*
G36*
G01X944801D02*
X944730Y-11033D01*
Y-11326D01*
X944998D01*
Y-18428D01*
X942796D01*
Y-11326D01*
X943064D01*
Y-11033D01*
X942993Y-10973D01*
G02X944801I904J1072D01*
G37*
G36*
G01X951494D02*
X951423Y-11033D01*
Y-11326D01*
X951692D01*
Y-18428D01*
X949490D01*
Y-11326D01*
X949757D01*
Y-11033D01*
X949686Y-10973D01*
G02X951494I904J1072D01*
G37*
G36*
G01X1102085D02*
X1102014Y-11033D01*
Y-11326D01*
X1102282D01*
Y-18428D01*
X1100078D01*
Y-11326D01*
X1100348D01*
Y-11033D01*
X1100277Y-10973D01*
G02X1102085I904J1072D01*
G37*
G36*
G01X1108778D02*
X1108707Y-11033D01*
Y-11326D01*
X1108974D01*
Y-18428D01*
X1106772D01*
Y-11326D01*
X1107041D01*
Y-11033D01*
X1106970Y-10973D01*
G02X1108778I904J1072D01*
G37*
G36*
G01X1125510D02*
X1125439Y-11033D01*
Y-11326D01*
X1125708D01*
Y-18428D01*
X1123504D01*
Y-11326D01*
X1123773D01*
Y-11033D01*
X1123702Y-10973D01*
G02X1125510I904J1072D01*
G37*
G36*
G01X1132203D02*
X1132132Y-11033D01*
Y-11326D01*
X1132400D01*
Y-18428D01*
X1130198D01*
Y-11326D01*
X1130466D01*
Y-11033D01*
X1130395Y-10973D01*
G02X1132203I904J1072D01*
G37*
G36*
G01X1138896D02*
X1138825Y-11033D01*
Y-11326D01*
X1139092D01*
Y-18428D01*
X1136890D01*
Y-11326D01*
X1137159D01*
Y-11033D01*
X1137088Y-10973D01*
G02X1138896I904J1072D01*
G37*
G36*
G01X1145589D02*
X1145518Y-11033D01*
Y-11326D01*
X1145786D01*
Y-18428D01*
X1143582D01*
Y-11326D01*
X1143852D01*
Y-11033D01*
X1143781Y-10973D01*
G02X1145589I904J1072D01*
G37*
G36*
G01X1162321D02*
X1162250Y-11033D01*
Y-11326D01*
X1162518D01*
Y-18428D01*
X1160316D01*
Y-11326D01*
X1160584D01*
Y-11033D01*
X1160513Y-10973D01*
G02X1162321I904J1072D01*
G37*
G36*
G01X1169014D02*
X1168943Y-11033D01*
Y-11326D01*
X1169212D01*
Y-18428D01*
X1167008D01*
Y-11326D01*
X1167277D01*
Y-11033D01*
X1167206Y-10973D01*
G02X1169014I904J1072D01*
G37*
G36*
G01X1175707D02*
X1175636Y-11033D01*
Y-11326D01*
X1175904D01*
Y-18428D01*
X1173700D01*
Y-11326D01*
X1173970D01*
Y-11033D01*
X1173899Y-10973D01*
G02X1175707I904J1072D01*
G37*
G36*
G01X1182400D02*
X1182329Y-11033D01*
Y-11326D01*
X1182596D01*
Y-18428D01*
X1180394D01*
Y-11326D01*
X1180663D01*
Y-11033D01*
X1180592Y-10973D01*
G02X1182400I904J1072D01*
G37*
G36*
G01X1199132D02*
X1199061Y-11033D01*
Y-11326D01*
X1199330D01*
Y-18428D01*
X1197126D01*
Y-11326D01*
X1197395D01*
Y-11033D01*
X1197324Y-10973D01*
G02X1199132I904J1072D01*
G37*
G36*
G01X1205825D02*
X1205754Y-11033D01*
Y-11326D01*
X1206022D01*
Y-18428D01*
X1203820D01*
Y-11326D01*
X1204088D01*
Y-11033D01*
X1204017Y-10973D01*
G02X1205825I904J1072D01*
G37*
G36*
G01X1212518D02*
X1212447Y-11033D01*
Y-11326D01*
X1212714D01*
Y-18428D01*
X1210512D01*
Y-11326D01*
X1210781D01*
Y-11033D01*
X1210710Y-10973D01*
G02X1212518I904J1072D01*
G37*
G36*
G01X1219211D02*
X1219140Y-11033D01*
Y-11326D01*
X1219408D01*
Y-18428D01*
X1217204D01*
Y-11326D01*
X1217474D01*
Y-11033D01*
X1217403Y-10973D01*
G02X1219211I904J1072D01*
G37*
G36*
G01X1235943D02*
X1235872Y-11033D01*
Y-11326D01*
X1236140D01*
Y-18428D01*
X1233938D01*
Y-11326D01*
X1234206D01*
Y-11033D01*
X1234135Y-10973D01*
G02X1235943I904J1072D01*
G37*
G36*
G01X1242636D02*
X1242565Y-11033D01*
Y-11326D01*
X1242834D01*
Y-18428D01*
X1240630D01*
Y-11326D01*
X1240899D01*
Y-11033D01*
X1240828Y-10973D01*
G02X1242636I904J1072D01*
G37*
G36*
G01X1280343Y-15495D02*
G02X1280321Y-14060I-1443J696D01*
G03X1281025Y-14068I354J186D01*
G02X1283184Y-13700I1227J-679D01*
G03X1283763Y-13650I266J299D01*
G02X1283927Y-15571I1096J-874D01*
G03X1283348Y-15621I-266J-299D01*
G02X1281047Y-15464I-1096J874D01*
G03X1280343Y-15495I-344J-205D01*
G37*
G36*
G01X1498611Y-11287D02*
G02X1497445Y-12317I189J-1389D01*
G03X1496979Y-11822I-387J103D01*
G02X1498178Y-10763I-319J1570D01*
G03X1498611Y-11287I379J-127D01*
G37*
G36*
G01X90170Y-10745D02*
G02X88916Y-9191I-1393J159D01*
G03X89311Y-8609I40J398D01*
G02X90822Y-10483I5373J2786D01*
G03X90170Y-10745I-255J-308D01*
G37*
G36*
G01X735454Y-7525D02*
G02X734182Y-7734I-434J-1333D01*
G03X734066Y-7033I-239J320D01*
G02X733101Y-5790I434J1333D01*
G03X732588Y-5432I-399J-25D01*
G02X731232Y-3064I-397J1345D01*
G03X731260Y-2509I-273J292D01*
G02X733327Y-616I1056J922D01*
G03X733905I289J277D01*
G02Y-2558I1011J-971D01*
G03X733327I-289J-277D01*
G02X733275Y-2610I-1017J965D01*
G03X733247Y-3165I273J-292D01*
G02X733590Y-3997I-1056J-922D01*
G03X734103Y-4355I399J25D01*
G02X735338Y-6824I397J-1345D01*
G03X735454Y-7525I239J-320D01*
G37*
G36*
G01X1606667Y-4377D02*
G02Y-2823I-1167J777D01*
G03X1607333I333J222D01*
G02Y-4377I1167J-777D01*
G03X1606667I-333J-222D01*
G37*
G36*
G01X1837406Y-2254D02*
G02X1836404Y-3467I394J-1346D01*
G03X1835894Y-3046I-398J37D01*
G02X1836896Y-1833I-394J1346D01*
G03X1837406Y-2254I398J-37D01*
G37*
G36*
G01X624333Y-2565D02*
G02X623044Y-1599I-1333J-435D01*
G03X623437Y-1075I13J400D01*
G02X624726Y-2041I1333J435D01*
G03X624333Y-2565I-13J-400D01*
G37*
G36*
G01X1689167Y2223D02*
G02Y3777I-1167J777D01*
G03X1689833I333J222D01*
G02Y2223I1167J-777D01*
G03X1689167I-333J-222D01*
G37*
G36*
G01X1547967Y2623D02*
G02Y4177I-1167J777D01*
G03X1548633I333J222D01*
G02X1550773Y4410I1167J-777D01*
G03X1551327I277J288D01*
G02X1553273I973J-1010D01*
G03X1553827I277J288D01*
G02X1556045Y4045I973J-1010D01*
G03X1556755I355J184D01*
G02X1558973Y4410I1245J-645D01*
G03X1559527I277J288D01*
G02X1561550Y4329I973J-1010D01*
G03X1562150I300J265D01*
G02X1564289Y4283I1050J-929D01*
G03X1564911I311J252D01*
G02X1567167Y4177I1089J-883D01*
G03X1567833I333J222D01*
G02Y2623I1167J-777D01*
G03X1567167I-333J-222D01*
G02X1564911Y2517I-1167J777D01*
G03X1564289I-311J-252D01*
G02X1562150Y2471I-1089J883D01*
G03X1561550I-300J-265D01*
G02X1559527Y2390I-1050J929D01*
G03X1558973I-277J-288D01*
G02X1556755Y2755I-973J1010D01*
G03X1556045I-355J-184D01*
G02X1553827Y2390I-1245J645D01*
G03X1553273I-277J-288D01*
G02X1551327I-973J1010D01*
G03X1550773I-277J-288D01*
G02X1548633Y2623I-973J1010D01*
G03X1547967I-333J-222D01*
G37*
G36*
G01X1510373Y2490D02*
G02Y4510I-973J1010D01*
G03X1510927I277J288D01*
G02X1512873I973J-1010D01*
G03X1513427I277J288D01*
G02X1515373I973J-1010D01*
G03X1515927I277J288D01*
G02X1518145Y4145I973J-1010D01*
G03X1518855I355J184D01*
G02Y2855I1245J-645D01*
G03X1518145I-355J-184D01*
G02X1515927Y2490I-1245J645D01*
G03X1515373I-277J-288D01*
G02X1513427I-973J1010D01*
G03X1512873I-277J-288D01*
G02X1510927I-973J1010D01*
G03X1510373I-277J-288D01*
G37*
G36*
G01X1525889Y2617D02*
G02Y4383I-1089J883D01*
G03X1526511I311J252D01*
G02X1528845Y4145I1089J-883D01*
G03X1529555I355J184D01*
G02X1532045I1245J-645D01*
G03X1532755I355J184D01*
G02Y2855I1245J-645D01*
G03X1532045I-355J-184D01*
G02X1529555I-1245J645D01*
G03X1528845I-355J-184D01*
G02X1526511Y2617I-1245J645D01*
G03X1525889I-311J-252D01*
G37*
G36*
G01X1786560Y7365D02*
G02X1786549Y8852I-1194J735D01*
G03X1787227Y8857I337J215D01*
G02X1787238Y7370I1194J-735D01*
G03X1786560Y7365I-337J-215D01*
G37*
G36*
G01X649581Y7600D02*
G02X647784Y9724I-1031J950D01*
G03X647773Y10401I-218J335D01*
G02X649474Y12608I727J1199D01*
G03X650051Y12630I278J288D01*
G02X651847Y10513I1049J-931D01*
G03Y9837I213J-338D01*
G02X650147Y7622I-747J-1186D01*
G03X649581Y7600I-272J-293D01*
G37*
G36*
G01X1809523Y10358D02*
G02X1807832Y10471I-920J-1058D01*
G03X1807875Y11107I-220J334D01*
G02X1809566Y10994I920J1058D01*
G03X1809523Y10358I220J-334D01*
G37*
G36*
G01X1619797Y12266D02*
X1624799D01*
G02X1626310Y10765I0J-1512D01*
G01Y10670D01*
X1626300Y10586D01*
G02X1624798Y9244I-1502J169D01*
G01X1619796D01*
G02X1618983Y9482I1J1511D01*
G03X1618375Y9224I-216J-336D01*
G02X1617708Y10710I-1375J276D01*
G03X1618305Y10992I202J345D01*
G02X1619797Y12266I1493J-237D01*
G37*
G36*
G01X1842292Y10352D02*
G02X1842206Y8838I1134J-824D01*
G03X1841534Y8876I-348J-197D01*
G02X1839427Y8690I-1134J824D01*
G03X1838873I-277J-288D01*
G02Y10710I-973J1010D01*
G03X1839427I277J288D01*
G02X1841620Y10390I972J-1010D01*
G03X1842292Y10352I348J197D01*
G37*
G36*
G01X1323621Y8939D02*
G02X1321743Y10981I-1089J883D01*
G03X1321733Y11650I-224J331D01*
G02X1321660Y13969I750J1184D01*
G03X1321666Y14613I-234J324D01*
G02X1323597Y16617I842J1121D01*
G03X1324219I311J252D01*
G02X1326340Y16682I1089J-883D01*
G03X1326948Y16704I295J271D01*
G02X1328789Y14643I1097J-873D01*
G03X1328806Y13954I212J-339D01*
G02X1328959Y11604I-683J-1224D01*
G03X1328950Y10968I238J-321D01*
G02X1327028Y8944I-865J-1103D01*
G03X1326417Y8934I-301J-263D01*
G02X1324243Y8939I-1085J888D01*
G03X1323621I-311J-252D01*
G37*
G36*
G01X1833522Y11557D02*
G02X1831621Y9726I-622J-1257D01*
G03X1830952Y9822I-365J-164D01*
G02X1831167Y11309I-1064J913D01*
G03X1831836Y11213I365J164D01*
G02X1832233Y11533I1064J-913D01*
G03X1832220Y12243I-190J352D01*
G02X1833509Y12267I621J1257D01*
G03X1833522Y11557I190J-352D01*
G37*
G36*
G01X63880Y12677D02*
G02X62764Y11443I279J-1374D01*
G03X62287Y11875I-398J40D01*
G02X63403Y13109I-279J1374D01*
G03X63880Y12677I398J-40D01*
G37*
G36*
G01X1847352Y13735D02*
G02X1847035Y12168I970J-1012D01*
G03X1846390Y12298I-368J-158D01*
G02X1846707Y13865I-970J1012D01*
G03X1847352Y13735I368J158D01*
G37*
G36*
G01X1869503Y12151D02*
G02X1869308Y13808I-1217J697D01*
G03X1869946Y13883I291J274D01*
G02X1870141Y12226I1217J-697D01*
G03X1869503Y12151I-291J-274D01*
G37*
G36*
G01X1414946Y12458D02*
G02Y13820I-1225J681D01*
G03X1415646I350J194D01*
G02Y12458I1225J-681D01*
G03X1414946I-350J-194D01*
G37*
G36*
G01X25301Y17595D02*
G02X23782Y16791I-241J-1381D01*
G03X23487Y17350I-364J165D01*
G02X25006Y18154I241J1381D01*
G03X25301Y17595I364J-165D01*
G37*
G36*
G01X63377Y18524D02*
G02X62881Y16915I823J-1135D01*
G03X62269Y17103I-376J-135D01*
G02X62765Y18712I-823J1135D01*
G03X63377Y18524I376J135D01*
G37*
G36*
G01X35905Y18708D02*
G02X35882Y20238I-1186J747D01*
G03X36553Y20248I332J223D01*
G02X38615Y20596I1186J-747D01*
G03X39234Y20755I250J312D01*
G02X39654Y19125I1296J-535D01*
G03X39035Y18966I-250J-312D01*
G02X36576Y18718I-1296J535D01*
G03X35905Y18708I-332J-223D01*
G37*
G36*
G01X702306Y18872D02*
G02X700071Y18689I-1186J747D01*
G03X699483Y18700I-299J-266D01*
G02X699519Y20599I-1013J969D01*
G03X700107Y20588I299J266D01*
G02X702291Y20390I1013J-969D01*
G03X702964Y20397I334J220D01*
G02X702979Y18879I1186J-747D01*
G03X702306Y18872I-334J-220D01*
G37*
G36*
G01X124524Y26827D02*
X124453Y26767D01*
Y26474D01*
X124722D01*
Y19372D01*
X122518D01*
Y26474D01*
X122787D01*
Y26767D01*
X122716Y26827D01*
G02X124524I904J1072D01*
G37*
G36*
G01X131217D02*
X131146Y26767D01*
Y26474D01*
X131414D01*
Y19372D01*
X129212D01*
Y26474D01*
X129480D01*
Y26767D01*
X129409Y26827D01*
G02X131217I904J1072D01*
G37*
G36*
G01X147949D02*
X147878Y26767D01*
Y26474D01*
X148146D01*
Y19372D01*
X145944D01*
Y26474D01*
X146212D01*
Y26767D01*
X146141Y26827D01*
G02X147949I904J1072D01*
G37*
G36*
G01X154642D02*
X154571Y26767D01*
Y26474D01*
X154840D01*
Y19372D01*
X152636D01*
Y26474D01*
X152905D01*
Y26767D01*
X152834Y26827D01*
G02X154642I904J1072D01*
G37*
G36*
G01X161335D02*
X161264Y26767D01*
Y26474D01*
X161532D01*
Y19372D01*
X159330D01*
Y26474D01*
X159598D01*
Y26767D01*
X159527Y26827D01*
G02X161335I904J1072D01*
G37*
G36*
G01X168028D02*
X167957Y26767D01*
Y26474D01*
X168226D01*
Y19372D01*
X166022D01*
Y26474D01*
X166291D01*
Y26767D01*
X166220Y26827D01*
G02X168028I904J1072D01*
G37*
G36*
G01X184760D02*
X184689Y26767D01*
Y26474D01*
X184958D01*
Y19372D01*
X182754D01*
Y26474D01*
X183023D01*
Y26767D01*
X182952Y26827D01*
G02X184760I904J1072D01*
G37*
G36*
G01X191453D02*
X191382Y26767D01*
Y26474D01*
X191650D01*
Y19372D01*
X189448D01*
Y26474D01*
X189716D01*
Y26767D01*
X189645Y26827D01*
G02X191453I904J1072D01*
G37*
G36*
G01X198146D02*
X198075Y26767D01*
Y26474D01*
X198344D01*
Y19372D01*
X196140D01*
Y26474D01*
X196409D01*
Y26767D01*
X196338Y26827D01*
G02X198146I904J1072D01*
G37*
G36*
G01X204839D02*
X204768Y26767D01*
Y26474D01*
X205036D01*
Y19372D01*
X202834D01*
Y26474D01*
X203102D01*
Y26767D01*
X203031Y26827D01*
G02X204839I904J1072D01*
G37*
G36*
G01X221571D02*
X221500Y26767D01*
Y26474D01*
X221768D01*
Y19372D01*
X219566D01*
Y26474D01*
X219834D01*
Y26767D01*
X219763Y26827D01*
G02X221571I904J1072D01*
G37*
G36*
G01X228264D02*
X228193Y26767D01*
Y26474D01*
X228462D01*
Y19372D01*
X226258D01*
Y26474D01*
X226527D01*
Y26767D01*
X226456Y26827D01*
G02X228264I904J1072D01*
G37*
G36*
G01X234957D02*
X234886Y26767D01*
Y26474D01*
X235154D01*
Y19372D01*
X232952D01*
Y26474D01*
X233220D01*
Y26767D01*
X233149Y26827D01*
G02X234957I904J1072D01*
G37*
G36*
G01X241650D02*
X241579Y26767D01*
Y26474D01*
X241848D01*
Y19372D01*
X239644D01*
Y26474D01*
X239913D01*
Y26767D01*
X239842Y26827D01*
G02X241650I904J1072D01*
G37*
G36*
G01X258382D02*
X258311Y26767D01*
Y26474D01*
X258580D01*
Y19372D01*
X256376D01*
Y26474D01*
X256645D01*
Y26767D01*
X256574Y26827D01*
G02X258382I904J1072D01*
G37*
G36*
G01X265075D02*
X265004Y26767D01*
Y26474D01*
X265272D01*
Y19372D01*
X263070D01*
Y26474D01*
X263338D01*
Y26767D01*
X263267Y26827D01*
G02X265075I904J1072D01*
G37*
G36*
G01X271768D02*
X271697Y26767D01*
Y26474D01*
X271966D01*
Y19372D01*
X269762D01*
Y26474D01*
X270031D01*
Y26767D01*
X269960Y26827D01*
G02X271768I904J1072D01*
G37*
G36*
G01X278461D02*
X278390Y26767D01*
Y26474D01*
X278658D01*
Y19372D01*
X276456D01*
Y26474D01*
X276724D01*
Y26767D01*
X276653Y26827D01*
G02X278461I904J1072D01*
G37*
G36*
G01X295193D02*
X295122Y26767D01*
Y26474D01*
X295390D01*
Y19372D01*
X293188D01*
Y26474D01*
X293456D01*
Y26767D01*
X293385Y26827D01*
G02X295193I904J1072D01*
G37*
G36*
G01X301886D02*
X301815Y26767D01*
Y26474D01*
X302084D01*
Y19372D01*
X299882D01*
Y26474D01*
X300149D01*
Y26767D01*
X300078Y26827D01*
G02X301886I904J1072D01*
G37*
G36*
G01X452477D02*
X452406Y26767D01*
Y26474D01*
X452674D01*
Y19372D01*
X450470D01*
Y26474D01*
X450740D01*
Y26767D01*
X450669Y26827D01*
G02X452477I904J1072D01*
G37*
G36*
G01X459170D02*
X459099Y26767D01*
Y26474D01*
X459366D01*
Y19372D01*
X457164D01*
Y26474D01*
X457433D01*
Y26767D01*
X457362Y26827D01*
G02X459170I904J1072D01*
G37*
G36*
G01X475902D02*
X475831Y26767D01*
Y26474D01*
X476100D01*
Y19372D01*
X473896D01*
Y26474D01*
X474165D01*
Y26767D01*
X474094Y26827D01*
G02X475902I904J1072D01*
G37*
G36*
G01X482595D02*
X482524Y26767D01*
Y26474D01*
X482792D01*
Y19372D01*
X480590D01*
Y26474D01*
X480858D01*
Y26767D01*
X480787Y26827D01*
G02X482595I904J1072D01*
G37*
G36*
G01X489288D02*
X489217Y26767D01*
Y26474D01*
X489484D01*
Y19372D01*
X487282D01*
Y26474D01*
X487551D01*
Y26767D01*
X487480Y26827D01*
G02X489288I904J1072D01*
G37*
G36*
G01X495981D02*
X495910Y26767D01*
Y26474D01*
X496178D01*
Y19372D01*
X493974D01*
Y26474D01*
X494244D01*
Y26767D01*
X494173Y26827D01*
G02X495981I904J1072D01*
G37*
G36*
G01X512713D02*
X512642Y26767D01*
Y26474D01*
X512910D01*
Y19372D01*
X510708D01*
Y26474D01*
X510976D01*
Y26767D01*
X510905Y26827D01*
G02X512713I904J1072D01*
G37*
G36*
G01X519406D02*
X519335Y26767D01*
Y26474D01*
X519604D01*
Y19372D01*
X517400D01*
Y26474D01*
X517669D01*
Y26767D01*
X517598Y26827D01*
G02X519406I904J1072D01*
G37*
G36*
G01X526099D02*
X526028Y26767D01*
Y26474D01*
X526296D01*
Y19372D01*
X524092D01*
Y26474D01*
X524362D01*
Y26767D01*
X524291Y26827D01*
G02X526099I904J1072D01*
G37*
G36*
G01X532792D02*
X532721Y26767D01*
Y26474D01*
X532988D01*
Y19372D01*
X530786D01*
Y26474D01*
X531055D01*
Y26767D01*
X530984Y26827D01*
G02X532792I904J1072D01*
G37*
G36*
G01X549524D02*
X549453Y26767D01*
Y26474D01*
X549722D01*
Y19372D01*
X547518D01*
Y26474D01*
X547787D01*
Y26767D01*
X547716Y26827D01*
G02X549524I904J1072D01*
G37*
G36*
G01X556217D02*
X556146Y26767D01*
Y26474D01*
X556414D01*
Y19372D01*
X554212D01*
Y26474D01*
X554480D01*
Y26767D01*
X554409Y26827D01*
G02X556217I904J1072D01*
G37*
G36*
G01X562910D02*
X562839Y26767D01*
Y26474D01*
X563106D01*
Y19372D01*
X560904D01*
Y26474D01*
X561173D01*
Y26767D01*
X561102Y26827D01*
G02X562910I904J1072D01*
G37*
G36*
G01X569603D02*
X569532Y26767D01*
Y26474D01*
X569800D01*
Y19372D01*
X567596D01*
Y26474D01*
X567866D01*
Y26767D01*
X567795Y26827D01*
G02X569603I904J1072D01*
G37*
G36*
G01X586335D02*
X586264Y26767D01*
Y26474D01*
X586532D01*
Y19372D01*
X584330D01*
Y26474D01*
X584598D01*
Y26767D01*
X584527Y26827D01*
G02X586335I904J1072D01*
G37*
G36*
G01X593028D02*
X592957Y26767D01*
Y26474D01*
X593226D01*
Y19372D01*
X591022D01*
Y26474D01*
X591291D01*
Y26767D01*
X591220Y26827D01*
G02X593028I904J1072D01*
G37*
G36*
G01X774132D02*
X774061Y26767D01*
Y26474D01*
X774330D01*
Y19372D01*
X772126D01*
Y26474D01*
X772395D01*
Y26767D01*
X772324Y26827D01*
G02X774132I904J1072D01*
G37*
G36*
G01X780825D02*
X780754Y26767D01*
Y26474D01*
X781022D01*
Y19372D01*
X778820D01*
Y26474D01*
X779088D01*
Y26767D01*
X779017Y26827D01*
G02X780825I904J1072D01*
G37*
G36*
G01X797557D02*
X797486Y26767D01*
Y26474D01*
X797754D01*
Y19372D01*
X795552D01*
Y26474D01*
X795820D01*
Y26767D01*
X795749Y26827D01*
G02X797557I904J1072D01*
G37*
G36*
G01X804250D02*
X804179Y26767D01*
Y26474D01*
X804448D01*
Y19372D01*
X802244D01*
Y26474D01*
X802513D01*
Y26767D01*
X802442Y26827D01*
G02X804250I904J1072D01*
G37*
G36*
G01X810943D02*
X810872Y26767D01*
Y26474D01*
X811140D01*
Y19372D01*
X808938D01*
Y26474D01*
X809206D01*
Y26767D01*
X809135Y26827D01*
G02X810943I904J1072D01*
G37*
G36*
G01X817636D02*
X817565Y26767D01*
Y26474D01*
X817834D01*
Y19372D01*
X815630D01*
Y26474D01*
X815899D01*
Y26767D01*
X815828Y26827D01*
G02X817636I904J1072D01*
G37*
G36*
G01X834368D02*
X834297Y26767D01*
Y26474D01*
X834566D01*
Y19372D01*
X832362D01*
Y26474D01*
X832631D01*
Y26767D01*
X832560Y26827D01*
G02X834368I904J1072D01*
G37*
G36*
G01X841061D02*
X840990Y26767D01*
Y26474D01*
X841258D01*
Y19372D01*
X839056D01*
Y26474D01*
X839324D01*
Y26767D01*
X839253Y26827D01*
G02X841061I904J1072D01*
G37*
G36*
G01X847754D02*
X847683Y26767D01*
Y26474D01*
X847952D01*
Y19372D01*
X845748D01*
Y26474D01*
X846017D01*
Y26767D01*
X845946Y26827D01*
G02X847754I904J1072D01*
G37*
G36*
G01X854447D02*
X854376Y26767D01*
Y26474D01*
X854644D01*
Y19372D01*
X852442D01*
Y26474D01*
X852710D01*
Y26767D01*
X852639Y26827D01*
G02X854447I904J1072D01*
G37*
G36*
G01X871179D02*
X871108Y26767D01*
Y26474D01*
X871376D01*
Y19372D01*
X869174D01*
Y26474D01*
X869442D01*
Y26767D01*
X869371Y26827D01*
G02X871179I904J1072D01*
G37*
G36*
G01X877872D02*
X877801Y26767D01*
Y26474D01*
X878070D01*
Y19372D01*
X875866D01*
Y26474D01*
X876135D01*
Y26767D01*
X876064Y26827D01*
G02X877872I904J1072D01*
G37*
G36*
G01X884565D02*
X884494Y26767D01*
Y26474D01*
X884762D01*
Y19372D01*
X882560D01*
Y26474D01*
X882828D01*
Y26767D01*
X882757Y26827D01*
G02X884565I904J1072D01*
G37*
G36*
G01X891258D02*
X891187Y26767D01*
Y26474D01*
X891456D01*
Y19372D01*
X889252D01*
Y26474D01*
X889521D01*
Y26767D01*
X889450Y26827D01*
G02X891258I904J1072D01*
G37*
G36*
G01X907990D02*
X907919Y26767D01*
Y26474D01*
X908188D01*
Y19372D01*
X905984D01*
Y26474D01*
X906253D01*
Y26767D01*
X906182Y26827D01*
G02X907990I904J1072D01*
G37*
G36*
G01X914683D02*
X914612Y26767D01*
Y26474D01*
X914880D01*
Y19372D01*
X912678D01*
Y26474D01*
X912946D01*
Y26767D01*
X912875Y26827D01*
G02X914683I904J1072D01*
G37*
G36*
G01X921376D02*
X921305Y26767D01*
Y26474D01*
X921574D01*
Y19372D01*
X919370D01*
Y26474D01*
X919639D01*
Y26767D01*
X919568Y26827D01*
G02X921376I904J1072D01*
G37*
G36*
G01X928069D02*
X927998Y26767D01*
Y26474D01*
X928266D01*
Y19372D01*
X926064D01*
Y26474D01*
X926332D01*
Y26767D01*
X926261Y26827D01*
G02X928069I904J1072D01*
G37*
G36*
G01X944801D02*
X944730Y26767D01*
Y26474D01*
X944998D01*
Y19372D01*
X942796D01*
Y26474D01*
X943064D01*
Y26767D01*
X942993Y26827D01*
G02X944801I904J1072D01*
G37*
G36*
G01X951494D02*
X951423Y26767D01*
Y26474D01*
X951692D01*
Y19372D01*
X949490D01*
Y26474D01*
X949757D01*
Y26767D01*
X949686Y26827D01*
G02X951494I904J1072D01*
G37*
G36*
G01X1102085D02*
X1102014Y26767D01*
Y26474D01*
X1102282D01*
Y19372D01*
X1100078D01*
Y26474D01*
X1100348D01*
Y26767D01*
X1100277Y26827D01*
G02X1102085I904J1072D01*
G37*
G36*
G01X1108778D02*
X1108707Y26767D01*
Y26474D01*
X1108974D01*
Y19372D01*
X1106772D01*
Y26474D01*
X1107041D01*
Y26767D01*
X1106970Y26827D01*
G02X1108778I904J1072D01*
G37*
G36*
G01X1125510D02*
X1125439Y26767D01*
Y26474D01*
X1125708D01*
Y19372D01*
X1123504D01*
Y26474D01*
X1123773D01*
Y26767D01*
X1123702Y26827D01*
G02X1125510I904J1072D01*
G37*
G36*
G01X1132203D02*
X1132132Y26767D01*
Y26474D01*
X1132400D01*
Y19372D01*
X1130198D01*
Y26474D01*
X1130466D01*
Y26767D01*
X1130395Y26827D01*
G02X1132203I904J1072D01*
G37*
G36*
G01X1138896D02*
X1138825Y26767D01*
Y26474D01*
X1139092D01*
Y19372D01*
X1136890D01*
Y26474D01*
X1137159D01*
Y26767D01*
X1137088Y26827D01*
G02X1138896I904J1072D01*
G37*
G36*
G01X1145589D02*
X1145518Y26767D01*
Y26474D01*
X1145786D01*
Y19372D01*
X1143582D01*
Y26474D01*
X1143852D01*
Y26767D01*
X1143781Y26827D01*
G02X1145589I904J1072D01*
G37*
G36*
G01X1162321D02*
X1162250Y26767D01*
Y26474D01*
X1162518D01*
Y19372D01*
X1160316D01*
Y26474D01*
X1160584D01*
Y26767D01*
X1160513Y26827D01*
G02X1162321I904J1072D01*
G37*
G36*
G01X1169014D02*
X1168943Y26767D01*
Y26474D01*
X1169212D01*
Y19372D01*
X1167008D01*
Y26474D01*
X1167277D01*
Y26767D01*
X1167206Y26827D01*
G02X1169014I904J1072D01*
G37*
G36*
G01X1175707D02*
X1175636Y26767D01*
Y26474D01*
X1175904D01*
Y19372D01*
X1173700D01*
Y26474D01*
X1173970D01*
Y26767D01*
X1173899Y26827D01*
G02X1175707I904J1072D01*
G37*
G36*
G01X1182400D02*
X1182329Y26767D01*
Y26474D01*
X1182596D01*
Y19372D01*
X1180394D01*
Y26474D01*
X1180663D01*
Y26767D01*
X1180592Y26827D01*
G02X1182400I904J1072D01*
G37*
G36*
G01X1199132D02*
X1199061Y26767D01*
Y26474D01*
X1199330D01*
Y19372D01*
X1197126D01*
Y26474D01*
X1197395D01*
Y26767D01*
X1197324Y26827D01*
G02X1199132I904J1072D01*
G37*
G36*
G01X1205825D02*
X1205754Y26767D01*
Y26474D01*
X1206022D01*
Y19372D01*
X1203820D01*
Y26474D01*
X1204088D01*
Y26767D01*
X1204017Y26827D01*
G02X1205825I904J1072D01*
G37*
G36*
G01X1212518D02*
X1212447Y26767D01*
Y26474D01*
X1212714D01*
Y19372D01*
X1210512D01*
Y26474D01*
X1210781D01*
Y26767D01*
X1210710Y26827D01*
G02X1212518I904J1072D01*
G37*
G36*
G01X1219211D02*
X1219140Y26767D01*
Y26474D01*
X1219408D01*
Y19372D01*
X1217204D01*
Y26474D01*
X1217474D01*
Y26767D01*
X1217403Y26827D01*
G02X1219211I904J1072D01*
G37*
G36*
G01X1235943D02*
X1235872Y26767D01*
Y26474D01*
X1236140D01*
Y19372D01*
X1233938D01*
Y26474D01*
X1234206D01*
Y26767D01*
X1234135Y26827D01*
G02X1235943I904J1072D01*
G37*
G36*
G01X1242636D02*
X1242565Y26767D01*
Y26474D01*
X1242834D01*
Y19372D01*
X1240630D01*
Y26474D01*
X1240899D01*
Y26767D01*
X1240828Y26827D01*
G02X1242636I904J1072D01*
G37*
G36*
G01X1853568Y21812D02*
G02X1851033Y22017I-1332J-694D01*
G03X1850781Y22650I-321J239D01*
G02X1850430Y25502I259J1479D01*
G03X1850618Y26060I-163J366D01*
G02X1852351Y25337I1318J720D01*
G03X1852246Y25025I56J-192D01*
G02X1852325Y24907I-1207J-894D01*
G03X1852647Y24879I171J104D01*
G02X1853803Y25396I1134J-985D01*
G03X1854151Y26003I6J400D01*
G02X1855414Y25278I1285J777D01*
G03X1855066Y24671I-6J-400D01*
G02X1853893Y22396I-1285J-777D01*
G03X1853568Y21812I29J-399D01*
G37*
G36*
G01X1857168D02*
G02X1855724Y22616I-1332J-694D01*
G03X1856049Y23200I-29J399D01*
G02X1857403Y25396I1332J694D01*
G03X1857751Y26003I6J400D01*
G02X1859014Y25278I1285J777D01*
G03X1858666Y24671I-6J-400D01*
G02X1857493Y22396I-1285J-777D01*
G03X1857168Y21812I29J-399D01*
G37*
G36*
G01X1860768D02*
G02X1859324Y22616I-1332J-694D01*
G03X1859649Y23200I-29J399D01*
G02X1861003Y25396I1332J694D01*
G03X1861351Y26003I6J400D01*
G02X1864093Y26413I1285J777D01*
G03X1864384Y25927I388J-98D01*
G02X1865444Y23992I-364J-1457D01*
G03X1865745Y23473I379J-127D01*
G02X1864812Y20640I-296J-1473D01*
G03X1864284Y20455I-170J-362D01*
G02X1861610Y21824I-1348J663D01*
G03X1861199Y22408I-353J188D01*
G02X1861093Y22396I-222J1486D01*
G03X1860768Y21812I29J-399D01*
G37*
G36*
G01X1839435Y20812D02*
G02X1836914Y20579I-1335J688D01*
G03X1836287Y20585I-316J-245D01*
G02X1833917Y20634I-1166J947D01*
G03X1833275I-321J-239D01*
G02Y22430I-1204J898D01*
G03X1833917I321J239D01*
G02X1836307Y22453I1204J-898D01*
G03X1836934Y22447I316J245D01*
G02X1839375Y22295I1166J-947D01*
G03X1840064Y22312I339J211D01*
G02X1840124Y20852I1225J-681D01*
G03X1839435Y20812I-333J-222D01*
G37*
G36*
G01X755559Y23924D02*
G02X755505Y22420I1155J-794D01*
G03X754830Y22445I-345J-202D01*
G02X754884Y23949I-1155J794D01*
G03X755559Y23924I345J202D01*
G37*
G36*
G01X713670Y24408D02*
G02X713617Y22895I1153J-798D01*
G03X712944Y22918I-344J-204D01*
G02X712997Y24431I-1153J798D01*
G03X713670Y24408I344J204D01*
G37*
G36*
G01X1871884Y25563D02*
G02X1869964Y26249I-1284J-563D01*
G03X1870029Y26921I-181J357D01*
G02X1872259Y26123I2314J2953D01*
G03X1871884Y25563I-8J-400D01*
G37*
G36*
G01X69167Y25215D02*
G02X66831Y25218I-1167J777D01*
G03X66165Y25220I-334J-221D01*
G02X63833Y25223I-1165J780D01*
G03X63167I-333J-222D01*
G02X61027Y24990I-1167J777D01*
G03X60473I-277J-288D01*
G02X58490Y26973I-973J1010D01*
G03Y27527I-288J277D01*
G02X60473Y29510I1010J973D01*
G03X61027I277J288D01*
G02X63167Y29277I973J-1010D01*
G03X63833I333J222D01*
G02X66167I1167J-777D01*
G03X66833I333J222D01*
G02X69167I1167J-777D01*
G03X69833I333J222D01*
G02X72167I1167J-777D01*
G03X72833I333J222D01*
G02X75167I1167J-777D01*
G03X75833I333J222D01*
G02X78043Y29436I1167J-777D01*
G03X78709Y29547I298J267D01*
G02X80777Y27833I1291J-547D01*
G03Y27167I222J-333D01*
G02X78835Y25220I-777J-1167D01*
G03X78169Y25218I-332J-223D01*
G02X75833Y25215I-1169J774D01*
G03X75167I-333J-222D01*
G02X72833I-1167J777D01*
G03X72167I-333J-222D01*
G02X69833I-1167J777D01*
G03X69167I-333J-222D01*
G37*
G36*
G01X1837669Y27730D02*
G02X1837537Y25688I1031J-1092D01*
G03X1836952Y25726I-310J-253D01*
G02X1834677Y25976I-1031J1092D01*
G03X1834015I-331J-224D01*
G02X1831521Y25986I-1244J842D01*
G03X1830843Y25967I-333J-222D01*
G02X1830776Y27496I-1207J713D01*
G03X1831452Y27537I325J233D01*
G02X1834015Y27660I1319J-719D01*
G03X1834677I331J224D01*
G02X1837084Y27768I1244J-842D01*
G03X1837669Y27730I310J253D01*
G37*
G36*
G01X643566Y30162D02*
G02X643831Y32385I-5773J1815D01*
G03X644497Y32113I399J26D01*
G02X644277Y30270I933J-1046D01*
G03X643566Y30162I-329J-228D01*
G37*
G36*
G01X1855356Y35523D02*
G02X1855081Y33888I977J-1005D01*
G03X1854444Y33995I-358J-180D01*
G02X1854719Y35630I-977J1005D01*
G03X1855356Y35523I358J180D01*
G37*
G36*
G01X3401Y37588D02*
G02X2221Y36451I199J-1388D01*
G03X1771Y36919I-393J72D01*
G02X2951Y38056I-199J1388D01*
G03X3401Y37588I393J-72D01*
G37*
G36*
G01X1818049Y38126D02*
G02X1816526Y38042I-697J-1217D01*
G03X1816489Y38712I-236J323D01*
G02X1818012Y38796I697J1217D01*
G03X1818049Y38126I236J-323D01*
G37*
G36*
G01X1879863Y38648D02*
G02X1877978Y38508I-866J-1102D01*
G03X1877934Y39098I-291J275D01*
G02X1878027Y41370I866J1102D01*
G03Y42037I-220J334D01*
G02X1879573I773J1170D01*
G03Y41370I220J-333D01*
G02X1879819Y39238I-773J-1169D01*
G03X1879863Y38648I291J-275D01*
G37*
G36*
G01X1549250Y38482D02*
X1547371D01*
G03X1546972Y38106I0J-400D01*
G02X1546564Y39179I-1400J82D01*
G03X1547246Y39462I282J283D01*
G01Y43986D01*
X1549250D01*
Y38482D01*
G37*
G36*
G01X1472260Y38105D02*
G02X1471852Y39202I-1398J104D01*
G03X1472534Y39485I282J283D01*
G01Y43978D01*
X1474538D01*
Y38476D01*
X1472659D01*
G03X1472260Y38105I0J-400D01*
G37*
G36*
G01X717821Y39557D02*
G02X715736Y37718I-921J-1057D01*
G03X715097Y37752I-332J-223D01*
G02X712873Y37851I-1074J901D01*
G03X712224Y37862I-328J-228D01*
G02X710054Y39634I-1123J839D01*
G03Y40166I-298J266D01*
G02X712250Y41902I1046J933D01*
G03X712899Y41891I328J228D01*
G02X713154Y42154I1126J-836D01*
G03X713149Y42786I-247J314D01*
G02X713067Y44947I851J1114D01*
G03X712995Y45595I-266J298D01*
G02X714647Y47831I679J1227D01*
G03X715203I278J288D01*
G02X717077Y47896I973J-1009D01*
G03X717615Y47918I257J307D01*
G02X718193Y48263I987J-996D01*
G03X718471Y48718I-115J383D01*
G02X720796Y50005I1379J252D01*
G03X721342Y50011I270J295D01*
G02X723690Y48740I970J-1012D01*
G03X723976Y48280I393J-75D01*
G02X722657Y45894I-373J-1351D01*
G03X722111Y45888I-270J-295D01*
G02X720144Y45914I-970J1012D01*
G03X719580Y45919I-285J-281D01*
G02X717699Y45847I-980J1002D01*
G03X717161Y45825I-257J-307D01*
G02X717105Y45772I-991J991D01*
G03X717222Y45101I265J-299D01*
G02X717628Y42749I-522J-1301D01*
G03X717637Y42141I264J-300D01*
G02X717786Y40126I-895J-1079D01*
G03X717821Y39557I298J-267D01*
G37*
G36*
G01X1825416Y39145D02*
G02X1824999Y40803I-1286J558D01*
G03X1825614Y40958I248J314D01*
G02X1826031Y39300I1286J-558D01*
G03X1825416Y39145I-248J-314D01*
G37*
G36*
G01X1637398Y38350D02*
X1632398D01*
G02X1630896Y39694I0J1512D01*
G03X1630473Y40049I-398J-44D01*
G02X1629531Y40337I-87J1399D01*
G03X1629211Y40150I-122J-159D01*
G02X1629219Y40082I-1497J-211D01*
G01X1629226Y40019D01*
X1629227Y39956D01*
G02Y39911I-1512J-23D01*
G01X1629226Y39910D01*
Y39900D01*
G02X1627725Y38423I-1511J34D01*
G01X1622645Y38389D01*
G02X1622625Y41411I-10J1511D01*
G01X1627704Y41445D01*
G02X1628410Y41277I13J-1512D01*
G03X1628991Y41591I183J355D01*
G02X1631767Y41690I1395J-143D01*
G03X1632211Y41362I394J69D01*
G02X1632398Y41374I190J-1500D01*
G01X1637399D01*
G02X1638910Y39872I-1J-1512D01*
G01Y39777D01*
X1638900Y39693D01*
G02X1637398Y38350I-1502J169D01*
G37*
G36*
G01X1868660Y40718D02*
G02X1867396Y41163I-1041J-939D01*
G03X1867629Y41826I-64J395D01*
G02X1868893Y41381I1041J939D01*
G03X1868660Y40718I64J-395D01*
G37*
G36*
G01X1350135Y39522D02*
G02X1350061Y41113I-1190J742D01*
G03X1350718Y41144I318J243D01*
G02X1350792Y39553I1190J-742D01*
G03X1350135Y39522I-318J-243D01*
G37*
G36*
G01X1856584Y40050D02*
G02X1856393Y41790I-1184J751D01*
G03X1857014Y41858I283J282D01*
G02X1859170Y42118I1184J-750D01*
G03X1859745Y42139I277J288D01*
G02X1859814Y40190I1041J-939D01*
G03X1859239Y40169I-277J-288D01*
G02X1857205Y40118I-1041J939D01*
G03X1856584Y40050I-283J-282D01*
G37*
G36*
G01X59973Y42490D02*
G02X58223Y44667I-972J1010D01*
G03Y45333I-222J333D01*
G02Y47667I777J1167D01*
G03Y48333I-222J333D01*
G02X59973Y50510I778J1167D01*
G03X60527I277J288D01*
G02X62667Y50277I973J-1010D01*
G03X63333I333J222D01*
G02X65667I1167J-777D01*
G03X66333I333J222D01*
G02X68667I1167J-777D01*
G03X69333I333J222D01*
G02X71667I1167J-777D01*
G03X72333I333J222D01*
G02X74667I1167J-777D01*
G03X75333I333J222D01*
G02X77667I1167J-777D01*
G03X78333I333J222D01*
G02X80277Y48333I1167J-777D01*
G03Y47667I222J-333D01*
G02Y45333I-777J-1167D01*
G03Y44667I222J-333D01*
G02X78333Y42723I-777J-1167D01*
G03X77667I-333J-222D01*
G02X75333I-1167J777D01*
G03X74667I-333J-222D01*
G02X72333I-1167J777D01*
G03X71667I-333J-222D01*
G02X69333I-1167J777D01*
G03X68667I-333J-222D01*
G02X66333I-1167J777D01*
G03X65667I-333J-222D01*
G02X63333I-1167J777D01*
G03X62667I-333J-222D01*
G02X60527Y42490I-1167J777D01*
G03X59973I-277J-288D01*
G37*
G36*
G01X657040Y43629D02*
G02X655290Y45806I-972J1010D01*
G03Y46472I-222J333D01*
G02X657040Y48649I778J1167D01*
G03X657594I277J288D01*
G02X659344Y46472I972J-1010D01*
G03Y45806I222J-333D01*
G02X657594Y43629I-778J-1167D01*
G03X657040I-277J-288D01*
G37*
G36*
G01X1378856Y46412D02*
G02X1377714Y45162I254J-1379D01*
G03X1377243Y45592I-398J37D01*
G02X1378385Y46842I-254J1379D01*
G03X1378856Y46412I398J-37D01*
G37*
G36*
G01X1266336Y46199D02*
G02X1266158Y47939I-1179J758D01*
G03X1266780Y48003I285J280D01*
G02X1266958Y46263I1179J-758D01*
G03X1266336Y46199I-285J-280D01*
G37*
G36*
G01X12409Y48226D02*
G02X10405Y47952I-870J-1099D01*
G03X10330Y48501I-323J235D01*
G02X10187Y48631I869J1100D01*
G03X9632Y48653I-289J-277D01*
G02X9713Y50669I-932J1047D01*
G03X10268Y50647I289J277D01*
G02X12303Y50466I932J-1047D01*
G03X12926Y50459I314J247D01*
G02X12773Y48910I1084J-889D01*
G03X12422Y48913I-176J-94D01*
G02X12334Y48775I-1224J684D01*
G03X12409Y48226I323J-235D01*
G37*
G36*
G01X-8844Y50087D02*
G02X-8845Y51712I-1143J812D01*
G03X-8193I326J232D01*
G02X-8192Y50087I1143J-812D01*
G03X-8844I-326J-232D01*
G37*
G36*
G01X114508Y56436D02*
G02X112892Y55842I-426J-1336D01*
G03X112674Y56434I-339J211D01*
G02X114290Y57028I426J1336D01*
G03X114508Y56436I339J-211D01*
G37*
G36*
G01X1393023Y54549D02*
G02X1391273Y56726I-972J1010D01*
G03Y57392I-222J333D01*
G02X1393023Y59569I778J1167D01*
G03X1393577I277J288D01*
G02X1395523I973J-1010D01*
G03X1396077I277J288D01*
G02X1397827Y57392I972J-1010D01*
G03Y56726I222J-333D01*
G02X1396077Y54549I-778J-1167D01*
G03X1395523I-277J-288D01*
G02X1393577I-973J1010D01*
G03X1393023I-277J-288D01*
G37*
G36*
G01X2629Y57596D02*
G02X1052Y57616I-803J-1149D01*
G03X1060Y58277I-221J333D01*
G02X2637Y58257I803J1149D01*
G03X2629Y57596I221J-333D01*
G37*
G36*
G01X81777Y59667D02*
G02X80223I-777J-1167D01*
G03Y60333I-222J333D01*
G02X81777I777J1167D01*
G03Y59667I222J-333D01*
G37*
G36*
G01X124524Y64627D02*
X124453Y64567D01*
Y64274D01*
X124722D01*
Y57172D01*
X122518D01*
Y64274D01*
X122787D01*
Y64567D01*
X122716Y64627D01*
G02X124524I904J1072D01*
G37*
G36*
G01X131217D02*
X131146Y64567D01*
Y64274D01*
X131414D01*
Y57172D01*
X129212D01*
Y64274D01*
X129480D01*
Y64567D01*
X129409Y64627D01*
G02X131217I904J1072D01*
G37*
G36*
G01X147949D02*
X147878Y64567D01*
Y64274D01*
X148146D01*
Y57172D01*
X145944D01*
Y64274D01*
X146212D01*
Y64567D01*
X146141Y64627D01*
G02X147949I904J1072D01*
G37*
G36*
G01X154642D02*
X154571Y64567D01*
Y64274D01*
X154840D01*
Y57172D01*
X152636D01*
Y64274D01*
X152905D01*
Y64567D01*
X152834Y64627D01*
G02X154642I904J1072D01*
G37*
G36*
G01X161335D02*
X161264Y64567D01*
Y64274D01*
X161532D01*
Y57172D01*
X159330D01*
Y64274D01*
X159598D01*
Y64567D01*
X159527Y64627D01*
G02X161335I904J1072D01*
G37*
G36*
G01X168028D02*
X167957Y64567D01*
Y64274D01*
X168226D01*
Y57172D01*
X166022D01*
Y64274D01*
X166291D01*
Y64567D01*
X166220Y64627D01*
G02X168028I904J1072D01*
G37*
G36*
G01X184760D02*
X184689Y64567D01*
Y64274D01*
X184958D01*
Y57172D01*
X182754D01*
Y64274D01*
X183023D01*
Y64567D01*
X182952Y64627D01*
G02X184760I904J1072D01*
G37*
G36*
G01X191453D02*
X191382Y64567D01*
Y64274D01*
X191650D01*
Y57172D01*
X189448D01*
Y64274D01*
X189716D01*
Y64567D01*
X189645Y64627D01*
G02X191453I904J1072D01*
G37*
G36*
G01X198146D02*
X198075Y64567D01*
Y64274D01*
X198344D01*
Y57172D01*
X196140D01*
Y64274D01*
X196409D01*
Y64567D01*
X196338Y64627D01*
G02X198146I904J1072D01*
G37*
G36*
G01X204839D02*
X204768Y64567D01*
Y64274D01*
X205036D01*
Y57172D01*
X202834D01*
Y64274D01*
X203102D01*
Y64567D01*
X203031Y64627D01*
G02X204839I904J1072D01*
G37*
G36*
G01X221571D02*
X221500Y64567D01*
Y64274D01*
X221768D01*
Y57172D01*
X219566D01*
Y64274D01*
X219834D01*
Y64567D01*
X219763Y64627D01*
G02X221571I904J1072D01*
G37*
G36*
G01X228264D02*
X228193Y64567D01*
Y64274D01*
X228462D01*
Y57172D01*
X226258D01*
Y64274D01*
X226527D01*
Y64567D01*
X226456Y64627D01*
G02X228264I904J1072D01*
G37*
G36*
G01X234957D02*
X234886Y64567D01*
Y64274D01*
X235154D01*
Y57172D01*
X232952D01*
Y64274D01*
X233220D01*
Y64567D01*
X233149Y64627D01*
G02X234957I904J1072D01*
G37*
G36*
G01X241650D02*
X241579Y64567D01*
Y64274D01*
X241848D01*
Y57172D01*
X239644D01*
Y64274D01*
X239913D01*
Y64567D01*
X239842Y64627D01*
G02X241650I904J1072D01*
G37*
G36*
G01X258382D02*
X258311Y64567D01*
Y64274D01*
X258580D01*
Y57172D01*
X256376D01*
Y64274D01*
X256645D01*
Y64567D01*
X256574Y64627D01*
G02X258382I904J1072D01*
G37*
G36*
G01X265075D02*
X265004Y64567D01*
Y64274D01*
X265272D01*
Y57172D01*
X263070D01*
Y64274D01*
X263338D01*
Y64567D01*
X263267Y64627D01*
G02X265075I904J1072D01*
G37*
G36*
G01X271768D02*
X271697Y64567D01*
Y64274D01*
X271966D01*
Y57172D01*
X269762D01*
Y64274D01*
X270031D01*
Y64567D01*
X269960Y64627D01*
G02X271768I904J1072D01*
G37*
G36*
G01X278461D02*
X278390Y64567D01*
Y64274D01*
X278658D01*
Y57172D01*
X276456D01*
Y64274D01*
X276724D01*
Y64567D01*
X276653Y64627D01*
G02X278461I904J1072D01*
G37*
G36*
G01X295193D02*
X295122Y64567D01*
Y64274D01*
X295390D01*
Y57172D01*
X293188D01*
Y64274D01*
X293456D01*
Y64567D01*
X293385Y64627D01*
G02X295193I904J1072D01*
G37*
G36*
G01X301886D02*
X301815Y64567D01*
Y64274D01*
X302084D01*
Y57172D01*
X299882D01*
Y64274D01*
X300149D01*
Y64567D01*
X300078Y64627D01*
G02X301886I904J1072D01*
G37*
G36*
G01X459170D02*
X459099Y64567D01*
Y64274D01*
X459366D01*
Y57172D01*
X457164D01*
Y64274D01*
X457433D01*
Y64567D01*
X457362Y64627D01*
G02X459170I904J1072D01*
G37*
G36*
G01X475902D02*
X475831Y64567D01*
Y64274D01*
X476100D01*
Y57172D01*
X473896D01*
Y64274D01*
X474165D01*
Y64567D01*
X474094Y64627D01*
G02X475902I904J1072D01*
G37*
G36*
G01X482595D02*
X482524Y64567D01*
Y64274D01*
X482792D01*
Y57172D01*
X480590D01*
Y64274D01*
X480858D01*
Y64567D01*
X480787Y64627D01*
G02X482595I904J1072D01*
G37*
G36*
G01X489288D02*
X489217Y64567D01*
Y64274D01*
X489484D01*
Y57172D01*
X487282D01*
Y64274D01*
X487551D01*
Y64567D01*
X487480Y64627D01*
G02X489288I904J1072D01*
G37*
G36*
G01X495981D02*
X495910Y64567D01*
Y64274D01*
X496178D01*
Y57172D01*
X493974D01*
Y64274D01*
X494244D01*
Y64567D01*
X494173Y64627D01*
G02X495981I904J1072D01*
G37*
G36*
G01X512713D02*
X512642Y64567D01*
Y64274D01*
X512910D01*
Y57172D01*
X510708D01*
Y64274D01*
X510976D01*
Y64567D01*
X510905Y64627D01*
G02X512713I904J1072D01*
G37*
G36*
G01X519406D02*
X519335Y64567D01*
Y64274D01*
X519604D01*
Y57172D01*
X517400D01*
Y64274D01*
X517669D01*
Y64567D01*
X517598Y64627D01*
G02X519406I904J1072D01*
G37*
G36*
G01X526099D02*
X526028Y64567D01*
Y64274D01*
X526296D01*
Y57172D01*
X524092D01*
Y64274D01*
X524362D01*
Y64567D01*
X524291Y64627D01*
G02X526099I904J1072D01*
G37*
G36*
G01X532792D02*
X532721Y64567D01*
Y64274D01*
X532988D01*
Y57172D01*
X530786D01*
Y64274D01*
X531055D01*
Y64567D01*
X530984Y64627D01*
G02X532792I904J1072D01*
G37*
G36*
G01X549524D02*
X549453Y64567D01*
Y64274D01*
X549722D01*
Y57172D01*
X547518D01*
Y64274D01*
X547787D01*
Y64567D01*
X547716Y64627D01*
G02X549524I904J1072D01*
G37*
G36*
G01X556217D02*
X556146Y64567D01*
Y64274D01*
X556414D01*
Y57172D01*
X554212D01*
Y64274D01*
X554480D01*
Y64567D01*
X554409Y64627D01*
G02X556217I904J1072D01*
G37*
G36*
G01X562910D02*
X562839Y64567D01*
Y64274D01*
X563106D01*
Y57172D01*
X560904D01*
Y64274D01*
X561173D01*
Y64567D01*
X561102Y64627D01*
G02X562910I904J1072D01*
G37*
G36*
G01X569603D02*
X569532Y64567D01*
Y64274D01*
X569800D01*
Y57172D01*
X567596D01*
Y64274D01*
X567866D01*
Y64567D01*
X567795Y64627D01*
G02X569603I904J1072D01*
G37*
G36*
G01X586335D02*
X586264Y64567D01*
Y64274D01*
X586532D01*
Y57172D01*
X584330D01*
Y64274D01*
X584598D01*
Y64567D01*
X584527Y64627D01*
G02X586335I904J1072D01*
G37*
G36*
G01X593028D02*
X592957Y64567D01*
Y64274D01*
X593226D01*
Y57172D01*
X591022D01*
Y64274D01*
X591291D01*
Y64567D01*
X591220Y64627D01*
G02X593028I904J1072D01*
G37*
G36*
G01X774132D02*
X774061Y64567D01*
Y64274D01*
X774330D01*
Y57172D01*
X772126D01*
Y64274D01*
X772395D01*
Y64567D01*
X772324Y64627D01*
G02X774132I904J1072D01*
G37*
G36*
G01X780825D02*
X780754Y64567D01*
Y64274D01*
X781022D01*
Y57172D01*
X778820D01*
Y64274D01*
X779088D01*
Y64567D01*
X779017Y64627D01*
G02X780825I904J1072D01*
G37*
G36*
G01X797557D02*
X797486Y64567D01*
Y64274D01*
X797754D01*
Y57172D01*
X795552D01*
Y64274D01*
X795820D01*
Y64567D01*
X795749Y64627D01*
G02X797557I904J1072D01*
G37*
G36*
G01X804250D02*
X804179Y64567D01*
Y64274D01*
X804448D01*
Y57172D01*
X802244D01*
Y64274D01*
X802513D01*
Y64567D01*
X802442Y64627D01*
G02X804250I904J1072D01*
G37*
G36*
G01X810943D02*
X810872Y64567D01*
Y64274D01*
X811140D01*
Y57172D01*
X808938D01*
Y64274D01*
X809206D01*
Y64567D01*
X809135Y64627D01*
G02X810943I904J1072D01*
G37*
G36*
G01X817636D02*
X817565Y64567D01*
Y64274D01*
X817834D01*
Y57172D01*
X815630D01*
Y64274D01*
X815899D01*
Y64567D01*
X815828Y64627D01*
G02X817636I904J1072D01*
G37*
G36*
G01X834368D02*
X834297Y64567D01*
Y64274D01*
X834566D01*
Y57172D01*
X832362D01*
Y64274D01*
X832631D01*
Y64567D01*
X832560Y64627D01*
G02X834368I904J1072D01*
G37*
G36*
G01X841061D02*
X840990Y64567D01*
Y64274D01*
X841258D01*
Y57172D01*
X839056D01*
Y64274D01*
X839324D01*
Y64567D01*
X839253Y64627D01*
G02X841061I904J1072D01*
G37*
G36*
G01X847754D02*
X847683Y64567D01*
Y64274D01*
X847952D01*
Y57172D01*
X845748D01*
Y64274D01*
X846017D01*
Y64567D01*
X845946Y64627D01*
G02X847754I904J1072D01*
G37*
G36*
G01X854447D02*
X854376Y64567D01*
Y64274D01*
X854644D01*
Y57172D01*
X852442D01*
Y64274D01*
X852710D01*
Y64567D01*
X852639Y64627D01*
G02X854447I904J1072D01*
G37*
G36*
G01X871179D02*
X871108Y64567D01*
Y64274D01*
X871376D01*
Y57172D01*
X869174D01*
Y64274D01*
X869442D01*
Y64567D01*
X869371Y64627D01*
G02X871179I904J1072D01*
G37*
G36*
G01X877872D02*
X877801Y64567D01*
Y64274D01*
X878070D01*
Y57172D01*
X875866D01*
Y64274D01*
X876135D01*
Y64567D01*
X876064Y64627D01*
G02X877872I904J1072D01*
G37*
G36*
G01X884565D02*
X884494Y64567D01*
Y64274D01*
X884762D01*
Y57172D01*
X882560D01*
Y64274D01*
X882828D01*
Y64567D01*
X882757Y64627D01*
G02X884565I904J1072D01*
G37*
G36*
G01X891258D02*
X891187Y64567D01*
Y64274D01*
X891456D01*
Y57172D01*
X889252D01*
Y64274D01*
X889521D01*
Y64567D01*
X889450Y64627D01*
G02X891258I904J1072D01*
G37*
G36*
G01X907990D02*
X907919Y64567D01*
Y64274D01*
X908188D01*
Y57172D01*
X905984D01*
Y64274D01*
X906253D01*
Y64567D01*
X906182Y64627D01*
G02X907990I904J1072D01*
G37*
G36*
G01X914683D02*
X914612Y64567D01*
Y64274D01*
X914880D01*
Y57172D01*
X912678D01*
Y64274D01*
X912946D01*
Y64567D01*
X912875Y64627D01*
G02X914683I904J1072D01*
G37*
G36*
G01X921376D02*
X921305Y64567D01*
Y64274D01*
X921574D01*
Y57172D01*
X919370D01*
Y64274D01*
X919639D01*
Y64567D01*
X919568Y64627D01*
G02X921376I904J1072D01*
G37*
G36*
G01X928069D02*
X927998Y64567D01*
Y64274D01*
X928266D01*
Y57172D01*
X926064D01*
Y64274D01*
X926332D01*
Y64567D01*
X926261Y64627D01*
G02X928069I904J1072D01*
G37*
G36*
G01X944801D02*
X944730Y64567D01*
Y64274D01*
X944998D01*
Y57172D01*
X942796D01*
Y64274D01*
X943064D01*
Y64567D01*
X942993Y64627D01*
G02X944801I904J1072D01*
G37*
G36*
G01X951494D02*
X951423Y64567D01*
Y64274D01*
X951692D01*
Y57172D01*
X949490D01*
Y64274D01*
X949757D01*
Y64567D01*
X949686Y64627D01*
G02X951494I904J1072D01*
G37*
G36*
G01X1102085D02*
X1102014Y64567D01*
Y64274D01*
X1102282D01*
Y57172D01*
X1100078D01*
Y64274D01*
X1100348D01*
Y64567D01*
X1100277Y64627D01*
G02X1102085I904J1072D01*
G37*
G36*
G01X1108778D02*
X1108707Y64567D01*
Y64274D01*
X1108974D01*
Y57172D01*
X1106772D01*
Y64274D01*
X1107041D01*
Y64567D01*
X1106970Y64627D01*
G02X1108778I904J1072D01*
G37*
G36*
G01X1125510D02*
X1125439Y64567D01*
Y64274D01*
X1125708D01*
Y57172D01*
X1123504D01*
Y64274D01*
X1123773D01*
Y64567D01*
X1123702Y64627D01*
G02X1125510I904J1072D01*
G37*
G36*
G01X1132203D02*
X1132132Y64567D01*
Y64274D01*
X1132400D01*
Y57172D01*
X1130198D01*
Y64274D01*
X1130466D01*
Y64567D01*
X1130395Y64627D01*
G02X1132203I904J1072D01*
G37*
G36*
G01X1138896D02*
X1138825Y64567D01*
Y64274D01*
X1139092D01*
Y57172D01*
X1136890D01*
Y64274D01*
X1137159D01*
Y64567D01*
X1137088Y64627D01*
G02X1138896I904J1072D01*
G37*
G36*
G01X1145589D02*
X1145518Y64567D01*
Y64274D01*
X1145786D01*
Y57172D01*
X1143582D01*
Y64274D01*
X1143852D01*
Y64567D01*
X1143781Y64627D01*
G02X1145589I904J1072D01*
G37*
G36*
G01X1162321D02*
X1162250Y64567D01*
Y64274D01*
X1162518D01*
Y57172D01*
X1160316D01*
Y64274D01*
X1160584D01*
Y64567D01*
X1160513Y64627D01*
G02X1162321I904J1072D01*
G37*
G36*
G01X1169014D02*
X1168943Y64567D01*
Y64274D01*
X1169212D01*
Y57172D01*
X1167008D01*
Y64274D01*
X1167277D01*
Y64567D01*
X1167206Y64627D01*
G02X1169014I904J1072D01*
G37*
G36*
G01X1175707D02*
X1175636Y64567D01*
Y64274D01*
X1175904D01*
Y57172D01*
X1173700D01*
Y64274D01*
X1173970D01*
Y64567D01*
X1173899Y64627D01*
G02X1175707I904J1072D01*
G37*
G36*
G01X1182400D02*
X1182329Y64567D01*
Y64274D01*
X1182596D01*
Y57172D01*
X1180394D01*
Y64274D01*
X1180663D01*
Y64567D01*
X1180592Y64627D01*
G02X1182400I904J1072D01*
G37*
G36*
G01X1199132D02*
X1199061Y64567D01*
Y64274D01*
X1199330D01*
Y57172D01*
X1197126D01*
Y64274D01*
X1197395D01*
Y64567D01*
X1197324Y64627D01*
G02X1199132I904J1072D01*
G37*
G36*
G01X1205825D02*
X1205754Y64567D01*
Y64274D01*
X1206022D01*
Y57172D01*
X1203820D01*
Y64274D01*
X1204088D01*
Y64567D01*
X1204017Y64627D01*
G02X1205825I904J1072D01*
G37*
G36*
G01X1212518D02*
X1212447Y64567D01*
Y64274D01*
X1212714D01*
Y57172D01*
X1210512D01*
Y64274D01*
X1210781D01*
Y64567D01*
X1210710Y64627D01*
G02X1212518I904J1072D01*
G37*
G36*
G01X1219211D02*
X1219140Y64567D01*
Y64274D01*
X1219408D01*
Y57172D01*
X1217204D01*
Y64274D01*
X1217474D01*
Y64567D01*
X1217403Y64627D01*
G02X1219211I904J1072D01*
G37*
G36*
G01X1235943D02*
X1235872Y64567D01*
Y64274D01*
X1236140D01*
Y57172D01*
X1233938D01*
Y64274D01*
X1234206D01*
Y64567D01*
X1234135Y64627D01*
G02X1235943I904J1072D01*
G37*
G36*
G01X1242636D02*
X1242565Y64567D01*
Y64274D01*
X1242834D01*
Y57172D01*
X1240630D01*
Y64274D01*
X1240899D01*
Y64567D01*
X1240828Y64627D01*
G02X1242636I904J1072D01*
G37*
G36*
G01X-7239Y59518D02*
G02X-9396Y60971I-1371J292D01*
G03X-9343Y61590I-224J331D01*
G02X-9771Y62657I973J1010D01*
G03X-10237Y63068I-400J16D01*
G02X-11672Y63728I-234J1382D01*
G03X-12369Y63708I-343J-206D01*
G02X-12408Y65082I-1241J652D01*
G03X-11711Y65102I343J206D01*
G02X-10689Y65835I1241J-652D01*
G03X-10449Y66492I-62J395D01*
G02X-9171Y66025I1060J918D01*
G03X-9411Y65368I62J-395D01*
G02X-9069Y64393I-1059J-919D01*
G03X-8603Y63982I400J-16D01*
G02X-6972Y62710I233J-1382D01*
G03X-6449Y62362I398J32D01*
G02X-6662Y59789I439J-1332D01*
G03X-7239Y59518I-186J-354D01*
G37*
G36*
G01X1875282Y59842D02*
G02X1875079Y61138I-1326J456D01*
G03X1875777Y61248I320J240D01*
G02X1875980Y59952I1326J-456D01*
G03X1875282Y59842I-320J-240D01*
G37*
G36*
G01X1393350Y64127D02*
G02X1391442Y66175I-1011J971D01*
G03X1391400Y66821I-256J308D01*
G02X1393262Y68858I749J1185D01*
G03X1393906Y68870I318J243D01*
G02X1396023Y69069I1144J-811D01*
G03X1396577I277J288D01*
G02X1398345Y66904I972J-1011D01*
G03X1398342Y66247I227J-330D01*
G02X1396528Y64127I-802J-1149D01*
G03X1395950I-289J-277D01*
G02X1393928I-1011J971D01*
G03X1393350I-289J-277D01*
G37*
G36*
G01X656573Y65090D02*
G02X654823Y67267I-972J1010D01*
G03Y67933I-222J333D01*
G02X656573Y70110I778J1167D01*
G03X657127I277J288D01*
G02X658877Y67933I972J-1010D01*
G03Y67267I222J-333D01*
G02X657127Y65090I-778J-1167D01*
G03X656573I-277J-288D01*
G37*
G36*
G01X1845071Y66284D02*
G02X1842659Y67986I-1046J1078D01*
G03X1842341Y68550I-364J167D01*
G02X1841469Y68964I174J1492D01*
G03X1840911I-279J-286D01*
G02X1838843Y68942I-1046J1078D01*
G03X1838274Y68917I-272J-293D01*
G02X1835783Y69328I-1113J1009D01*
G03X1835131Y69449I-367J-159D01*
G02X1832991Y69445I-1072J1052D01*
G03X1832445Y69466I-284J-281D01*
G02X1830402Y71666I-985J1134D01*
G03Y72234I-282J284D01*
G02X1832518I1058J1066D01*
G03Y71666I282J-284D01*
G02X1832528Y71656I-1057J-1067D01*
G03X1833074Y71635I284J281D01*
G02X1835531Y70802I985J-1134D01*
G03X1835895Y70734I196J40D01*
G02X1836052Y70939I1267J-807D01*
G03X1836045Y71486I-295J270D01*
G02X1835714Y73030I1084J1040D01*
G03X1835417Y73557I-377J135D01*
G02X1835353Y76487I297J1472D01*
G03X1835640Y76992I-96J388D01*
G02X1838194Y78433I1437J437D01*
G03X1838806Y78452I298J267D01*
G02X1841062Y78569I1179J-930D01*
G03X1841650Y78585I287J279D01*
G02X1844210Y77131I1133J-986D01*
G03X1844476Y76624I380J-124D01*
G02X1845115Y76242I-427J-1440D01*
G03X1845665Y76225I284J281D01*
G02X1846921Y73626I1002J-1119D01*
G03X1846605Y73118I68J-394D01*
G02X1846243Y71646I-1440J-426D01*
G03Y71088I286J-279D01*
G02X1846531Y69418I-1078J-1046D01*
G03X1846849Y68854I364J-167D01*
G02X1847721Y68440I-174J-1492D01*
G03X1848279I279J286D01*
G02Y66284I1046J-1078D01*
G03X1847721I-279J-286D01*
G02X1845629I-1046J1078D01*
G03X1845071I-279J-286D01*
G37*
G36*
G01X1665360Y70935D02*
G02X1663340I-1010J-973D01*
G03Y71489I-288J277D01*
G02X1663233Y71615I1013J969D01*
G03X1662885Y71561I-159J-121D01*
G02X1661123Y70697I-1322J467D01*
G03X1660598Y70311I-125J-380D01*
G02X1659636Y71622I-1402J-20D01*
G03X1660161Y72008I125J380D01*
G02X1660178Y72245I1402J19D01*
G03X1659870Y72443I-198J31D01*
G02X1658127Y72604I-771J1171D01*
G03X1657573I-277J-288D01*
G02Y74624I-973J1010D01*
G03X1658127I277J288D01*
G02X1660500Y73684I973J-1010D01*
G03X1661047Y73332I399J20D01*
G02X1662513Y73059I516J-1304D01*
G03X1663132Y73155I271J294D01*
G02X1665360Y71489I1219J-693D01*
G03Y70935I288J-277D01*
G37*
G36*
G01X1767991Y71341D02*
G02X1767899Y69490I1259J-990D01*
G03X1767268Y69547I-338J-215D01*
G02X1767358Y71346I-1028J953D01*
G03X1767991Y71341I318J242D01*
G37*
G36*
G01X1931256Y69430D02*
G02X1929064Y71484I-1106J1017D01*
G03X1929024Y72073I-289J276D01*
G02X1928738Y72375I937J1174D01*
G03X1928075Y72356I-325J-233D01*
G02X1928001Y73961I-1185J750D01*
G03X1928663Y74004I317J244D01*
G02X1931031Y74301I1298J-757D01*
G03X1931613Y74314I285J281D01*
G02X1933791Y74373I1117J-1004D01*
G03X1934342Y74360I282J284D01*
G02X1935084Y74725I1008J-1113D01*
G03X1935370Y75302I-70J394D01*
G02X1937793Y77024I1337J685D01*
G03X1938374Y77027I289J276D01*
G02X1940610Y76978I1096J-1027D01*
G03X1941224Y76987I303J261D01*
G02X1943420Y77133I1166J-947D01*
G03X1943973Y77137I274J291D01*
G02X1946398Y75462I1047J-1077D01*
G03X1946678Y74913I367J-159D01*
G02X1947377Y74543I-328J-1466D01*
G03X1947924Y74544I273J292D01*
G02Y72352I1027J-1096D01*
G03X1947377Y72351I-273J-292D01*
G02X1945281Y72392I-1027J1096D01*
G03X1944692Y72371I-285J-281D01*
G02X1944640Y72314I-1135J983D01*
G03X1944682Y71725I290J-275D01*
G02X1942644Y69530I-933J-1177D01*
G03X1942056I-294J-270D01*
G02X1939881Y69492I-1106J1017D01*
G03X1939292Y69471I-285J-281D01*
G02X1937123Y69351I-1142J976D01*
G03X1936577I-273J-292D01*
G02X1934523I-1027J1096D01*
G03X1933977I-273J-292D01*
G02X1931844Y69430I-1027J1096D01*
G03X1931256I-294J-270D01*
G37*
G36*
G01X1613948Y71562D02*
G02X1613859Y70164I1167J-776D01*
G03X1613167Y70208I-359J-178D01*
G02X1613256Y71606I-1167J776D01*
G03X1613948Y71562I359J178D01*
G37*
G36*
G01X1585945Y70110D02*
G02X1585874Y71675I-1197J730D01*
G03X1586537Y71704I322J238D01*
G02X1586608Y70139I1197J-730D01*
G03X1585945Y70110I-322J-238D01*
G37*
G36*
G01X650973Y71290D02*
G02X649223Y73467I-972J1010D01*
G03Y74133I-222J333D01*
G02X650973Y76310I778J1167D01*
G03X651527I277J288D01*
G02X653277Y74133I972J-1010D01*
G03Y73467I222J-333D01*
G02X651527Y71290I-778J-1167D01*
G03X650973I-277J-288D01*
G37*
G36*
G01X657473D02*
G02X655723Y73467I-972J1010D01*
G03Y74133I-222J333D01*
G02X657473Y76310I778J1167D01*
G03X658027I277J288D01*
G02X659777Y74133I972J-1010D01*
G03Y73467I222J-333D01*
G02X658027Y71290I-778J-1167D01*
G03X657473I-277J-288D01*
G37*
G36*
G01X1592905Y76213D02*
G02X1590493Y74840I-1305J-513D01*
G03X1589907Y74890I-316J-245D01*
G02X1590069Y76786I-945J1036D01*
G03X1590655Y76736I316J245D01*
G02X1591385Y77085I944J-1037D01*
G03X1591695Y77627I-62J395D01*
G02X1593215Y76755I1305J513D01*
G03X1592905Y76213I62J-395D01*
G37*
G36*
G01X80403Y77220D02*
G02X78872Y77105I-678J-1227D01*
G03X78822Y77773I-243J318D01*
G02X78723Y80167I678J1227D01*
G03Y80833I-222J333D01*
G02X80277I777J1167D01*
G03Y80167I222J-333D01*
G02X80353Y77888I-777J-1167D01*
G03X80403Y77220I243J-318D01*
G37*
G36*
G01X1408457Y76508D02*
G02X1406582Y78504I-1157J792D01*
G03X1406729Y79037I-205J343D01*
G02X1406651Y79208I1234J666D01*
G03X1406277I-187J-70D01*
G02X1403617Y80088I-1313J492D01*
G03X1403239Y80598I-385J110D01*
G02X1404431Y82777I25J1402D01*
G03X1405097I333J222D01*
G02X1407431I1167J-777D01*
G03X1408097I333J222D01*
G02X1409588Y80636I1167J-777D01*
G03X1409300Y80126I93J-389D01*
G02X1408682Y78496I-1336J-426D01*
G03X1408535Y77963I205J-343D01*
G02X1408549Y77938I-1216J-697D01*
G03X1408911Y77950I178J91D01*
G02X1409100Y76530I1289J-551D01*
G03X1408457Y76508I-313J-248D01*
G37*
G36*
G01X6314Y78585D02*
G02X4763Y78637I-815J-1141D01*
G03X4786Y79303I-210J341D01*
G02X6337Y79251I815J1141D01*
G03X6314Y78585I210J-341D01*
G37*
G36*
G01X764202Y79450D02*
G02X762559Y79422I-802J-1150D01*
G03X762548Y80070I-240J320D01*
G02X764191Y80098I802J1150D01*
G03X764202Y79450I240J-320D01*
G37*
G36*
G01X12658Y79649D02*
G02X10884Y79496I-794J-1155D01*
G03X10831Y80112I-280J286D01*
G02X10652Y80257I790J1158D01*
G03X10098I-277J-288D01*
G02X8520Y82532I-972J1010D01*
G03X8543Y83242I-172J361D01*
G02X8187Y83524I681J1226D01*
G03X7583Y83509I-296J-269D01*
G02X7538Y85343I-1083J891D01*
G03X8142Y85358I296J269D01*
G02X10198Y85477I1083J-891D01*
G03X10752I277J288D01*
G02X12330Y83202I972J-1010D01*
G03X12307Y82492I172J-361D01*
G02X12605Y80265I-682J-1225D01*
G03X12658Y79649I280J-286D01*
G37*
G36*
G01X1518409Y78143D02*
G02X1518368Y79500I-1247J641D01*
G03X1519067Y79521I344J204D01*
G02X1519077Y79539I1230J-672D01*
G03X1518914Y80079I-353J188D01*
G02X1520817Y80654I666J1234D01*
G03X1520980Y80114I353J-188D01*
G02X1519108Y78164I-666J-1234D01*
G03X1518409Y78143I-344J-204D01*
G37*
G36*
G01X-10313Y78490D02*
G02X-12501Y78378I-1139J818D01*
G03X-13089Y78389I-299J-266D01*
G02X-15075Y78348I-1013J969D01*
G03X-15629I-277J-288D01*
G02X-17612Y80331I-973J1010D01*
G03Y80885I-288J277D01*
G02X-15629Y82868I1010J973D01*
G03X-15075I277J288D01*
G02X-13053Y82788I973J-1010D01*
G03X-12465Y82777I299J266D01*
G02X-10342Y82665I1013J-969D01*
G03X-9701Y82676I316J244D01*
G02X-9678Y82707I1137J-820D01*
G03X-9733Y83251I-318J243D01*
G02X-7669Y85121I922J1057D01*
G03X-7026Y85109I326J232D01*
G02X-4846Y83347I1114J-852D01*
G03X-4835Y82814I304J-260D01*
G02X-4878Y80857I-1025J-956D01*
G03X-4894Y80302I280J-286D01*
G02X-6954Y78400I-1036J-944D01*
G03X-7538I-292J-273D01*
G02X-9672Y78501I-1024J958D01*
G03X-10313Y78490I-316J-244D01*
G37*
G36*
G01X733908Y81859D02*
G02X733868Y83450I-1174J766D01*
G03X734526Y83467I323J236D01*
G02X734566Y81876I1174J-766D01*
G03X733908Y81859I-323J-236D01*
G37*
G36*
G01X1355474Y87998D02*
X1351501D01*
X1349001Y85498D01*
X1344001D01*
X1342501Y83998D01*
X1339499D01*
X1338498Y84999D01*
Y87501D01*
X1339499Y88502D01*
X1340499D01*
X1341498Y89501D01*
Y91499D01*
X1340999Y91998D01*
X1332500D01*
X1330000Y89998D01*
X1328234D01*
Y90120D01*
G03X1327914Y90279I-200J-1D01*
G02X1327073Y89998I-842J1121D01*
G01X1323998D01*
Y95501D01*
X1326499Y98002D01*
X1338499D01*
X1339998Y99501D01*
Y101501D01*
X1341499Y103002D01*
X1343801D01*
G02X1344065Y102976I-5J-1401D01*
G03X1344215Y103338I38J196D01*
G02X1344470Y105798I785J1162D01*
G03X1344581Y106470I-151J370D01*
G02X1346030Y106231I919J1059D01*
G03X1345919Y105559I151J-370D01*
G02X1345170Y103108I-919J-1059D01*
G03X1344904Y102465I49J-397D01*
G02X1345202Y101596I-1103J-864D01*
G03X1345384Y101396I200J-1D01*
G02X1345556Y101370I-123J-1397D01*
G03X1345798Y101570I42J195D01*
G02X1347199Y103002I1401J30D01*
G01X1359501D01*
X1363502Y99001D01*
Y98055D01*
G03X1364079Y97697I400J0D01*
G02Y95183I621J-1257D01*
G03X1363502Y94825I-177J-358D01*
G01Y92999D01*
X1363002Y92499D01*
Y85999D01*
X1361501Y84498D01*
X1360928D01*
G03X1360611Y83855I0J-400D01*
G02X1358886Y84260I-1111J-855D01*
G01X1358998Y84315D01*
Y87499D01*
X1358499Y87998D01*
X1358106D01*
G03X1357968Y87654I0J-200D01*
G02X1355813Y87386I-968J-1014D01*
G03X1355474Y87998I-339J212D01*
G37*
G36*
G01X99998Y84565D02*
G02X98747Y83325I142J-1395D01*
G03X98122Y83698I-398J44D01*
G02X99631Y85193I-3439J4980D01*
G03X99998Y84565I327J-230D01*
G37*
G36*
G01X1574210Y83318D02*
G02X1574165Y84982I-1150J802D01*
G03X1574809Y85000I315J246D01*
G02X1574854Y83336I1150J-802D01*
G03X1574210Y83318I-315J-246D01*
G37*
G36*
G01X648982Y84439D02*
G02X646223Y84462I-1382J-239D01*
G03X645912Y84928I-393J74D01*
G02X645190Y87273I288J1372D01*
G03Y87827I-288J277D01*
G02X647367Y89577I1010J972D01*
G03X648033I333J222D01*
G02X648721Y90117I1166J-778D01*
G03X648943Y90668I-137J376D01*
G02X648914Y90733I1266J604D01*
G03X648270Y90866I-368J-157D01*
G02X646161Y91070I-966J1016D01*
G03X645628Y91181I-326J-231D01*
G02X646047Y93194I-724J1201D01*
G03X646580Y93083I326J231D01*
G02X648594Y92431I724J-1201D01*
G03X649238Y92298I368J157D01*
G02X651486Y91850I966J-1016D01*
G03X652063Y91672I366J162D01*
G02X651522Y89914I741J-1190D01*
G03X650945Y90092I-366J-162D01*
G02X650683Y89965I-739J1191D01*
G03X650461Y89414I137J-376D01*
G02X650210Y87827I-1261J-614D01*
G03Y87273I288J-277D01*
G02X649337Y84905I-1010J-973D01*
G03X648982Y84439I39J-398D01*
G37*
G36*
G01X1318622Y84134D02*
G02X1316250Y85529I-1322J466D01*
G03X1316227Y86084I-299J266D01*
G02X1316228Y88114I968J1015D01*
G03X1316252Y88669I-275J290D01*
G02X1318267Y88584I1049J931D01*
G03X1318243Y88029I275J-290D01*
G02X1318245Y86169I-1048J-931D01*
G03X1318268Y85614I299J-266D01*
G02X1318278Y85605I-933J-1047D01*
G03X1318615Y85717I140J143D01*
G02X1319222Y84334I1385J-217D01*
G03X1318622Y84134I-222J-333D01*
G37*
G36*
G01X768798Y85914D02*
G02X768120Y84453I702J-1214D01*
G03X767526Y84729I-394J-70D01*
G02X765913Y84877I-702J1214D01*
G03X765271Y84690I-260J-304D01*
G02X764841Y86166I-1341J410D01*
G03X765483Y86353I260J304D01*
G02X768204Y86190I1341J-410D01*
G03X768798Y85914I394J70D01*
G37*
G36*
G01X1758640Y84149D02*
G02X1758460Y85705I-1245J644D01*
G03X1759119Y85781I304J260D01*
G02X1759299Y84225I1245J-644D01*
G03X1758640Y84149I-304J-260D01*
G37*
G36*
G01X714182Y87090D02*
G02X712274Y86956I-882J-1090D01*
G03X712233Y87539I-293J272D01*
G02X714330Y89329I882J1090D01*
G03X715030Y89341I347J199D01*
G02X715053Y87983I1238J-658D01*
G03X714353Y87971I-347J-199D01*
G02X714141Y87673I-1239J657D01*
G03X714182Y87090I293J-272D01*
G37*
G36*
G01X707312Y87073D02*
G02X704606Y86976I-1340J-413D01*
G03X704134Y87458I-389J91D01*
G02X705211Y88514I-289J1372D01*
G03X705683Y88032I389J-91D01*
G02X705688Y88033I277J-1374D01*
G03X705989Y88542I-81J392D01*
G02X707613Y87582I1340J413D01*
G03X707312Y87073I81J-392D01*
G37*
G36*
G01X1676511Y87846D02*
G02X1676437Y86108I1062J-916D01*
G03X1675811Y86134I-323J-235D01*
G02X1675885Y87872I-1062J916D01*
G03X1676511Y87846I323J235D01*
G37*
G36*
G01X7750Y87098D02*
G02X7648Y88832I-1150J802D01*
G03X8275Y88869I299J265D01*
G02X10398Y89077I1150J-802D01*
G03X10952I277J288D01*
G02Y87057I973J-1010D01*
G03X10398I-277J-288D01*
G02X8377Y87135I-973J1010D01*
G03X7750Y87098I-299J-265D01*
G37*
G36*
G01X1312558Y92415D02*
G02X1310554Y92409I-999J-984D01*
G03X1310552Y92968I-287J278D01*
G02X1310472Y93057I1002J981D01*
G03X1310152Y93039I-153J-128D01*
G02X1308161Y94950I-1168J775D01*
G03X1308159Y95600I-234J324D01*
G02X1309794Y95606I813J1142D01*
G03X1309796Y94956I234J-324D01*
G02X1309929Y94848I-815J-1140D01*
G03X1310499Y94879I270J295D01*
G02X1312556Y92974I1052J-927D01*
G03X1312558Y92415I287J-278D01*
G37*
G36*
G01X1377332Y92806D02*
G02X1377230Y91313I1132J-827D01*
G03X1376554Y91358I-352J-190D01*
G02X1376656Y92853I-1142J829D01*
G03X1377332Y92806I353J189D01*
G37*
G36*
G01X1455416Y93465D02*
G02X1454081Y92667I-69J-1400D01*
G03X1453740Y93239I-361J172D01*
G02X1455075Y94037I69J1400D01*
G03X1455416Y93465I361J-172D01*
G37*
G36*
G01X692056Y93537D02*
G02X691687Y92008I944J-1037D01*
G03X691044Y92163I-374J-141D01*
G02X691413Y93692I-944J1037D01*
G03X692056Y93537I374J141D01*
G37*
G36*
G01X110302Y92129D02*
G02X110107Y93703I-1245J645D01*
G03X110762Y93784I300J265D01*
G02X110957Y92210I1245J-645D01*
G03X110302Y92129I-300J-265D01*
G37*
G36*
G01X733219Y93291D02*
G02X732024Y94187I-1309J-501D01*
G03X732431Y94729I33J399D01*
G02X733626Y93833I1309J501D01*
G03X733219Y93291I-33J-399D01*
G37*
G36*
G01X1919149Y94521D02*
G02X1917153Y94597I-1035J-945D01*
G03X1917174Y95158I-274J291D01*
G02X1917252Y97127I1036J945D01*
G03X1917206Y97748I-273J292D01*
G02X1918960Y97878I796J1154D01*
G03X1919006Y97257I273J-292D01*
G02X1919170Y95082I-796J-1154D01*
G03X1919149Y94521I274J-291D01*
G37*
G36*
G01X1296358Y95487D02*
G02X1294804I-777J-1167D01*
G03Y96153I-222J333D01*
G02X1296358I777J1167D01*
G03Y95487I222J-333D01*
G37*
G36*
G01X1693483Y93884D02*
G02X1693432Y95418I-1198J728D01*
G03X1694102Y95440I328J229D01*
G02X1696313Y95681I1198J-728D01*
G03X1696868Y95659I289J277D01*
G02X1696787Y93643I932J-1047D01*
G03X1696232Y93665I-289J-277D01*
G02X1694153Y93906I-932J1047D01*
G03X1693483Y93884I-328J-229D01*
G37*
G36*
G01X1573433Y96756D02*
G02X1571776Y96784I-848J-1117D01*
G03X1571787Y97429I-231J327D01*
G02X1573444Y97401I848J1117D01*
G03X1573433Y96756I231J-327D01*
G37*
G36*
G01X1745442Y96580D02*
G02X1745127Y95325I1049J-930D01*
G03X1744447Y95507I-389J-93D01*
G02X1743673Y97690I-947J893D01*
G03X1744111Y98196I53J397D01*
G02X1745191Y97260I1253J354D01*
G03X1744753Y96754I-53J-397D01*
G02X1744757Y96741I-1242J-389D01*
G03X1745442Y96580I386J104D01*
G37*
G36*
G01X1289548Y96543D02*
G02Y98097I-1167J777D01*
G03X1290214I333J222D01*
G02Y96543I1167J-777D01*
G03X1289548I-333J-222D01*
G37*
G36*
G01X59343Y97351D02*
X59303Y97498D01*
X53698D01*
Y99502D01*
X59290D01*
Y100998D01*
X53698D01*
Y103002D01*
X59303D01*
X59343Y103149D01*
G02X62312Y102760I1458J-399D01*
G01Y97665D01*
X62303Y97581D01*
G02X59343Y97351I-1502J169D01*
G37*
G36*
G01X1945567Y98870D02*
G02X1945553Y97453I1203J-720D01*
G03X1944863Y97460I-347J-199D01*
G02X1944877Y98877I-1203J720D01*
G03X1945567Y98870I347J199D01*
G37*
G36*
G01X1269667Y101323D02*
G02X1267570Y103149I-1167J777D01*
G03X1267592Y103726I-266J299D01*
G02X1269724Y105538I1008J975D01*
G03X1270366I321J239D01*
G02X1272465Y103692I1124J-839D01*
G03X1272467Y103115I278J-288D01*
G02X1270333Y101323I-967J-1015D01*
G03X1269667I-333J-222D01*
G37*
G36*
G01X1875618Y103538D02*
G02X1874255Y104598I-1360J-342D01*
G03X1874641Y105096I-2J400D01*
G02X1876004Y104036I1360J342D01*
G03X1875618Y103538I2J-400D01*
G37*
G36*
G01X74915Y103760D02*
G02Y106240I-2115J1240D01*
G03X75606I346J202D01*
G02X79837Y106239I2115J-1240D01*
G03X80527I345J202D01*
G02X84758Y106240I2116J-1239D01*
G03X85449I345J202D01*
G02X89679I2115J-1240D01*
G03X90370I346J202D01*
G02X94600I2115J-1240D01*
G03X95291I345J202D01*
G02X99522Y106239I2115J-1240D01*
G03X100212I345J202D01*
G02X104443Y106240I2116J-1239D01*
G03X105134I345J202D01*
G02Y103760I2115J-1240D01*
G03X104443I-345J-202D01*
G02X100212Y103761I-2115J1240D01*
G03X99522I-345J-202D01*
G02X95291Y103760I-2116J1239D01*
G03X94600I-345J-202D01*
G02X90370I-2115J1240D01*
G03X89679I-345J-202D01*
G02X85449I-2115J1240D01*
G03X84758I-345J-202D01*
G02X80527Y103761I-2115J1240D01*
G03X79837I-345J-202D01*
G02X75606Y103760I-2116J1239D01*
G03X74915I-345J-202D01*
G37*
G36*
G01X121118Y107644D02*
G02X119537Y107824I-921J-1057D01*
G03X119612Y108478I-188J353D01*
G02X121193Y108298I921J1057D01*
G03X121118Y107644I188J-353D01*
G37*
G36*
G01X1392517Y107705D02*
G02X1392488Y109327I-1158J791D01*
G03X1393140Y109339I322J237D01*
G02X1393502Y109702I1157J-792D01*
G03X1393504Y110359I-227J329D01*
G02X1395106Y110352I806J1147D01*
G03X1395104Y109695I227J-329D01*
G02X1393169Y107717I-806J-1147D01*
G03X1392517Y107705I-322J-237D01*
G37*
G36*
G01X1452447Y110885D02*
G02X1451038Y110235I-215J-1385D01*
G03X1450758Y110840I-341J210D01*
G02X1452167Y111490I215J1385D01*
G03X1452447Y110885I341J-210D01*
G37*
G36*
G01X1489010Y114086D02*
X1485298D01*
Y116090D01*
X1494302D01*
Y114086D01*
X1491346D01*
G03X1491087Y113382I1J-400D01*
G02X1489269I-909J-1067D01*
G03X1489010Y114086I-260J304D01*
G37*
G36*
G01X1512424Y120143D02*
G02X1515446Y120153I1511J0D01*
G01Y116258D01*
X1515437Y116174D01*
G02X1514779Y115089I-1502J169D01*
G03X1514753Y114445I224J-332D01*
G02X1513046Y114477I-874J-1096D01*
G03X1513044Y115122I-237J322D01*
G02X1512424Y116343I892J1221D01*
G01Y120143D01*
G37*
G36*
G01X1258565Y115056D02*
G02X1257135I-715J-1206D01*
G03Y115744I-204J344D01*
G02X1258565I715J1206D01*
G03Y115056I204J-344D01*
G37*
G36*
G01X619388Y115330D02*
G02X618655Y114188I666J-1234D01*
G03X618066Y114566I-399J26D01*
G02X618799Y115708I-666J1234D01*
G03X619388Y115330I399J-26D01*
G37*
G36*
G01X1286893Y117099D02*
G02X1285339I-777J-1167D01*
G03Y117765I-222J333D01*
G02X1286893I777J1167D01*
G03Y117099I222J-333D01*
G37*
G36*
G01X1398444Y117893D02*
G02X1397340Y117114I156J-1393D01*
G03X1396936Y117687I-360J175D01*
G02X1398040Y118466I-156J1393D01*
G03X1398444Y117893I360J-175D01*
G37*
G36*
G01X1554838Y121420D02*
G02X1554273Y122169I-1337J-421D01*
G03X1554545Y122454I111J167D01*
G02X1554398Y122705I1130J830D01*
G03X1553883Y122911I-364J-164D01*
G02X1554631Y124787I-530J1298D01*
G03X1555146Y124581I364J164D01*
G02X1556219Y124576I530J-1298D01*
G03X1556757Y124830I155J369D01*
G02X1557557Y123134I1343J-403D01*
G03X1557019Y122880I-155J-369D01*
G02X1555321Y121927I-1343J403D01*
G03X1554838Y121420I-102J-387D01*
G37*
G36*
G01X1928184Y121747D02*
G02X1926314Y122480I-1292J-544D01*
G03X1926518Y123000I-165J365D01*
G02X1926888Y124600I1292J544D01*
G03X1926912Y125180I-263J301D01*
G02X1927962Y127557I1006J976D01*
G03X1928366Y128041I13J400D01*
G02X1928815Y129394I1370J296D01*
G03X1928820Y129994I-262J302D01*
G02X1930677Y129980I936J1043D01*
G03X1930672Y129380I262J-302D01*
G02X1929692Y126936I-936J-1043D01*
G03X1929288Y126452I-13J-400D01*
G02X1928840Y125100I-1370J-296D01*
G03X1928816Y124520I263J-301D01*
G02X1928388Y122267I-1006J-976D01*
G03X1928184Y121747I165J-365D01*
G37*
G36*
G01X1401422Y122341D02*
G02X1399879Y122837I-1122J-841D01*
G03X1400078Y123459I-121J381D01*
G02X1399817Y124532I1122J841D01*
G03X1399418Y124998I-394J66D01*
G02X1400783Y126168I-18J1402D01*
G03X1401182Y125702I394J-66D01*
G02X1401621Y122963I18J-1402D01*
G03X1401422Y122341I121J-381D01*
G37*
G36*
G01X1392867Y122173D02*
G02X1390923Y124117I-1167J777D01*
G03Y124783I-222J333D01*
G02Y127117I777J1167D01*
G03Y127783I-222J333D01*
G02X1392867Y129727I777J1167D01*
G03X1393533I333J222D01*
G02X1395477Y127783I1167J-777D01*
G03Y127117I222J-333D01*
G02Y124783I-777J-1167D01*
G03Y124117I222J-333D01*
G02X1393533Y122173I-777J-1167D01*
G03X1392867I-333J-222D01*
G37*
G36*
G01X1525319Y122826D02*
G02X1524803Y124449I-1319J474D01*
G03X1525409Y124642I229J328D01*
G02X1525925Y123019I1319J-474D01*
G03X1525319Y122826I-229J-328D01*
G37*
G36*
G01X3938Y126754D02*
G03X5205Y127157I-2J2199D01*
G02X9264Y125823I1488J-2314D01*
G03X10004Y125805I374J143D01*
G02Y123881I2201J-962D01*
G03X9264Y123863I-366J-161D01*
G02X5221Y122519I-2571J980D01*
G03X3967Y122932I-1283J-1786D01*
G01X3936D01*
G03X2669Y122529I2J-2199D01*
G02X2653Y127167I-1488J2314D01*
G03X3907Y126754I1283J1786D01*
G01X3938D01*
G37*
G36*
G01X1864351Y125131D02*
G02X1864331Y123808I1226J-680D01*
G03X1863626Y123819I-355J-183D01*
G02X1863646Y125142I-1226J680D01*
G03X1864351Y125131I355J183D01*
G37*
G36*
G01X59373Y125351D02*
X59333Y125498D01*
X53698D01*
Y127502D01*
X59320D01*
Y128998D01*
X53698D01*
Y131002D01*
X59333D01*
X59373Y131149D01*
G02X62342Y130760I1458J-399D01*
G01Y125665D01*
X62333Y125581D01*
G02X59373Y125351I-1502J169D01*
G37*
G36*
G01X1857797Y127786D02*
G02X1856243I-777J-1167D01*
G03Y128452I-222J333D01*
G02X1857797I777J1167D01*
G03Y127786I222J-333D01*
G37*
G36*
G01X1513634Y127666D02*
G02X1513388Y125945I966J-1016D01*
G03X1512766Y126034I-346J-201D01*
G02X1513012Y127755I-966J1016D01*
G03X1513634Y127666I346J201D01*
G37*
G36*
G01X1473905Y130098D02*
G02X1472295I-805J-1148D01*
G03Y130752I-230J327D01*
G02X1473905I805J1148D01*
G03Y130098I230J-327D01*
G37*
G36*
G01X1861800Y131977D02*
G02X1860194Y131952I-785J-1162D01*
G03X1860184Y132607I-234J324D01*
G02X1859998Y134780I785J1162D01*
G03Y135358I-277J289D01*
G02X1861940I971J1011D01*
G03Y134780I277J-289D01*
G02X1861790Y132632I-971J-1011D01*
G03X1861800Y131977I234J-324D01*
G37*
G36*
G01X1531353Y133302D02*
G02X1530076Y134073I-1252J-631D01*
G03X1530426Y134653I-7J400D01*
G02X1530308Y135583I1252J631D01*
G03X1529813Y136054I-391J85D01*
G02X1530819Y137109I-364J1354D01*
G03X1531314Y136638I391J-85D01*
G02X1531703Y133882I364J-1354D01*
G03X1531353Y133302I7J-400D01*
G37*
G36*
G01X1324193Y132546D02*
G02Y134100I-1167J777D01*
G03X1324859I333J222D01*
G02Y132546I1167J-777D01*
G03X1324193I-333J-222D01*
G37*
G36*
G01X1262697Y134362D02*
G02X1262517Y132923I1101J-868D01*
G03X1261838Y133008I-365J-163D01*
G02X1262018Y134447I-1101J868D01*
G03X1262697Y134362I365J163D01*
G37*
G36*
G01X1590927Y135783D02*
G02X1588569Y134355I-1047J-932D01*
G03X1588067Y134592I-374J-142D01*
G02X1588931Y136417I-447J1329D01*
G03X1589433Y136180I374J142D01*
G02X1589549Y136213I441J-1331D01*
G03X1589753Y136868I-95J389D01*
G02X1591850Y138729I1047J932D01*
G03X1592450I300J265D01*
G02Y136871I1050J-929D01*
G03X1591850I-300J-265D01*
G02X1591131Y136438I-1050J929D01*
G03X1590927Y135783I95J-389D01*
G37*
G36*
G01X1568792Y137816D02*
G02X1567154Y137824I-825J-1134D01*
G03X1567157Y138473I-232J326D01*
G02X1568795Y138465I825J1134D01*
G03X1568792Y137816I232J-326D01*
G37*
G36*
G01X1513514Y139046D02*
G02X1513185Y137327I911J-1065D01*
G03X1512571Y137444I-354J-187D01*
G02X1512900Y139163I-911J1065D01*
G03X1513514Y139046I354J187D01*
G37*
G36*
G01X59373Y139351D02*
X59333Y139498D01*
X53698D01*
Y141502D01*
X59320D01*
Y142998D01*
X53698D01*
Y145002D01*
X59333D01*
X59373Y145149D01*
G02X62342Y144760I1458J-399D01*
G01Y139665D01*
X62333Y139581D01*
G02X59373Y139351I-1502J169D01*
G37*
G36*
G01X1952235Y142296D02*
G02X1950569Y141828I-535J-1296D01*
G03X1950399Y142434I-323J236D01*
G02X1952065Y142902I535J1296D01*
G03X1952235Y142296I323J-236D01*
G37*
G36*
G01X1240805Y142936D02*
G02X1239229Y142929I-783J-1163D01*
G03X1239227Y143591I-226J330D01*
G02X1240803Y143598I783J1163D01*
G03X1240805Y142936I226J-330D01*
G37*
G36*
G01X1822623Y142854D02*
G02X1822532Y144188I-1275J583D01*
G03X1823234Y144236I338J214D01*
G02X1823325Y142902I1275J-583D01*
G03X1822623Y142854I-338J-214D01*
G37*
G36*
G01X1937319Y144841D02*
G02X1935737Y145341I-1132J-828D01*
G03X1935922Y145968I-128J379D01*
G02X1935778Y146188I1180J929D01*
G03X1935109Y146242I-352J-190D01*
G02X1935210Y147808I-1109J858D01*
G03X1935880Y147776I345J202D01*
G02X1937528Y145460I1220J-876D01*
G03X1937319Y144841I114J-383D01*
G37*
G36*
G01X1542460Y150283D02*
G02X1540828Y150010I-629J-1253D01*
G03X1540722Y150647I-286J280D01*
G02X1542354Y150920I629J1253D01*
G03X1542460Y150283I286J-280D01*
G37*
G36*
G01X1715223Y148268D02*
G02Y149632I-1109J682D01*
G03X1715905I341J209D01*
G02Y148268I1109J-682D01*
G03X1715223I-341J-209D01*
G37*
G36*
G01X1914609Y148685D02*
G02X1914445Y150306I-1217J696D01*
G03X1915093Y150372I300J264D01*
G02X1917581Y150267I1217J-696D01*
G03X1918286Y150228I363J169D01*
G02X1918213Y148909I1198J-728D01*
G03X1917508Y148948I-363J-169D01*
G02X1915257Y148751I-1198J728D01*
G03X1914609Y148685I-300J-264D01*
G37*
G36*
G01X1578563Y150675D02*
G02X1577117Y150760I-793J-1156D01*
G03X1577157Y151444I-186J354D01*
G02X1576957Y153590I793J1156D01*
G03X1576901Y154201I-283J282D01*
G02X1578693Y154363I799J1152D01*
G03X1578749Y153752I283J-282D01*
G02X1578603Y151359I-799J-1152D01*
G03X1578563Y150675I186J-354D01*
G37*
G36*
G01X1829274Y151006D02*
G02X1827889Y151287I-933J-1046D01*
G03X1828026Y151964I-129J379D01*
G02X1829411Y151683I933J1046D01*
G03X1829274Y151006I129J-379D01*
G37*
G36*
G01X1906106Y151138D02*
G02X1904426Y151404I-1014J-968D01*
G03X1904526Y152032I-190J352D01*
G02X1906206Y151766I1014J968D01*
G03X1906106Y151138I190J-352D01*
G37*
G36*
G01X1493400Y154196D02*
G02X1491916Y153632I-331J-1362D01*
G03X1491682Y154248I-329J227D01*
G02X1493166Y154812I331J1362D01*
G03X1493400Y154196I329J-227D01*
G37*
G36*
G01X1263621Y155695D02*
G02X1263522Y154039I1079J-895D01*
G03X1262879Y154078I-336J-217D01*
G02X1262978Y155734I-1079J895D01*
G03X1263621Y155695I336J217D01*
G37*
G36*
G01X1808218Y163430D02*
G02X1806662I-778J-1400D01*
G03Y164130I-194J350D01*
G02Y166930I778J1400D01*
G03Y167630I-194J350D01*
G02X1808218I778J1400D01*
G03Y166930I194J-350D01*
G02Y164130I-778J-1400D01*
G03Y163430I194J-350D01*
G37*
G36*
G01X-14373Y161787D02*
G02X-14902Y163024I-1395J135D01*
G03X-14256Y163300I248J315D01*
G02X-13727Y162063I1395J-135D01*
G03X-14373Y161787I-248J-315D01*
G37*
G36*
G01X1455114Y164296D02*
G02X1453485Y164634I-1044J-936D01*
G03X1453616Y165264I-167J363D01*
G02X1455245Y164926I1044J936D01*
G03X1455114Y164296I167J-363D01*
G37*
G36*
G01X1929290Y171119D02*
G02X1929132Y169372I1010J-972D01*
G03X1928510Y169428I-333J-221D01*
G02X1928668Y171175I-1010J972D01*
G03X1929290Y171119I333J221D01*
G37*
G36*
G01X1452032Y171551D02*
G02X1450714Y171560I-667J-1233D01*
G03X1450719Y172266I-185J354D01*
G02X1450374Y174469I667J1233D01*
G03X1450369Y175027I-289J276D01*
G02X1450089Y176595I996J987D01*
G03X1449904Y177118I-364J165D01*
G02X1451808Y177791I628J1254D01*
G03X1451993Y177268I364J-165D01*
G02X1452377Y175044I-628J-1254D01*
G03X1452382Y174486I289J-276D01*
G02X1452037Y172257I-996J-987D01*
G03X1452032Y171551I185J-354D01*
G37*
G36*
G01X1675688Y171990D02*
G02X1675669Y173359I-1233J668D01*
G03X1676367Y173368I346J200D01*
G02X1676386Y171999I1233J-668D01*
G03X1675688Y171990I-346J-200D01*
G37*
G36*
G01X1929349Y174614D02*
G02X1927318Y176518I-1131J829D01*
G03X1927325Y177125I-257J307D01*
G02X1929149Y177104I924J1054D01*
G03X1929142Y176497I257J-307D01*
G02X1929302Y176332I-923J-1055D01*
G03X1929934Y176349I309J253D01*
G02X1930489Y176798I1130J-830D01*
G03X1930617Y177437I-164J365D01*
G02X1932215Y177118I1022J959D01*
G03X1932087Y176479I164J-365D01*
G02X1929981Y174631I-1022J-959D01*
G03X1929349Y174614I-309J-253D01*
G37*
G36*
G01X1720013Y177316D02*
G02X1718316Y177397I-913J-1316D01*
G03X1718371Y178058I-195J349D01*
G02X1720021Y177979I879J1092D01*
G03X1720013Y177316I220J-334D01*
G37*
G36*
G01X1752390Y178036D02*
X1757391D01*
G02X1758902Y176535I0J-1512D01*
G01Y176440D01*
X1758892Y176356D01*
G02X1757390Y175014I-1502J169D01*
G01X1752390D01*
G02X1751337Y175442I1J1511D01*
G03X1750706Y175345I-279J-287D01*
G02X1750451Y177213I-1411J759D01*
G03X1751086Y177288I289J276D01*
G02X1752390Y178036I1304J-763D01*
G37*
G36*
G01X1884675Y177325D02*
G02X1883084Y177255I-745J-1188D01*
G03X1883055Y177912I-242J318D01*
G02X1884957Y179892I745J1188D01*
G03X1885534Y179803I330J226D01*
G02X1885243Y177908I866J-1103D01*
G03X1884666Y177997I-330J-226D01*
G02X1884646Y177982I-851J1114D01*
G03X1884675Y177325I242J-318D01*
G37*
G36*
G01X63421Y177506D02*
G02X62786Y176279I766J-1174D01*
G03X62168Y176599I-400J-15D01*
G02X62803Y177826I-766J1174D01*
G03X63421Y177506I400J15D01*
G37*
G36*
G01X1489739Y177922D02*
G02X1488381Y177890I-650J-1242D01*
G03X1488364Y178590I-202J345D01*
G02X1489722Y178622I650J1242D01*
G03X1489739Y177922I202J-345D01*
G37*
G36*
G01X1227947Y178203D02*
G02X1226003Y180147I-1167J777D01*
G03Y180813I-222J333D01*
G02X1225919Y183086I777J1167D01*
G03X1225948Y183692I-246J315D01*
G02X1227775Y183602I966J1016D01*
G03X1227746Y182996I246J-315D01*
G02X1227947Y182757I-966J-1016D01*
G03X1228613I333J222D01*
G02X1230947I1167J-777D01*
G03X1231613I333J222D01*
G02X1233557Y180813I1167J-777D01*
G03Y180147I222J-333D01*
G02X1231613Y178203I-777J-1167D01*
G03X1230947I-333J-222D01*
G02X1228613I-1167J777D01*
G03X1227947I-333J-222D01*
G37*
G36*
G01X1597025Y179619D02*
G02Y180981I-1225J681D01*
G03X1597725I350J194D01*
G02Y179619I1225J-681D01*
G03X1597025I-350J-194D01*
G37*
G36*
G01X1855682Y182846D02*
G02X1854144Y182808I-740J-1191D01*
G03X1854128Y183476I-228J329D01*
G02X1855666Y183514I740J1191D01*
G03X1855682Y182846I228J-329D01*
G37*
G36*
G01X87704Y182904D02*
G02X86355Y182989I-752J-1183D01*
G03X86399Y183689I-170J362D01*
G02X87748Y183604I752J1183D01*
G03X87704Y182904I170J-362D01*
G37*
G36*
G01X767754Y183850D02*
G02X765216Y182837I-1386J-214D01*
G03X764664Y182940I-328J-229D01*
G02X762508Y184389I-783J1163D01*
G03X762239Y184851I-391J81D01*
G02X761777Y185103I428J1335D01*
G03X761242Y185079I-254J-309D01*
G02X759160Y186949I-984J999D01*
G03X759122Y187489I-313J249D01*
G02X759037Y187575I954J1028D01*
G03X758734Y187570I-149J-133D01*
G02X756760Y187384I-1080J894D01*
G03X756226Y187363I-255J-308D01*
G02X754226Y187408I-978J1005D01*
G03X753662Y187428I-292J-273D01*
G02X751706Y187475I-954J1027D01*
G03X751142Y187482I-286J-280D01*
G02X749159Y187515I-975J1008D01*
G03X748561Y187488I-287J-278D01*
G02X746453Y187402I-1092J880D01*
G03X745889Y187417I-290J-276D01*
G02X743856Y187534I-961J1021D01*
G03X743227Y187511I-305J-258D01*
G02X741097Y187344I-1136J822D01*
G03X740491Y187298I-283J-282D01*
G02X737962Y188013I-1132J827D01*
G03X737509Y188377I-399J-32D01*
G02X737404Y188367I-185J1389D01*
G03X737028Y187967I24J-399D01*
G02X734269Y187614I-1402J-2D01*
G03X733811Y187908I-387J-100D01*
G02X732641Y188233I-247J1380D01*
G03X732106Y188226I-264J-301D01*
G02X732078Y190311I-951J1030D01*
G03X732613Y190318I264J301D01*
G02X734921Y189639I951J-1030D01*
G03X735379Y189345I387J100D01*
G02X735541Y189364I244J-1380D01*
G03X735917Y189764I-24J399D01*
G02X736450Y190866I1402J2D01*
G03X736498Y191449I-248J314D01*
G02X738938Y192406I1038J943D01*
G03X739405Y192016I400J4D01*
G02X740525Y189546I236J-1382D01*
G03X740463Y188989I253J-310D01*
G02X740499Y188941I-1103J-865D01*
G03X740840Y188967I163J116D01*
G02X743163Y189237I1251J-634D01*
G03X743792Y189260I305J258D01*
G02X745944Y189404I1136J-822D01*
G03X746508Y189389I290J276D01*
G02X748477Y189343I961J-1021D01*
G03X749075Y189370I287J278D01*
G02X751169Y189470I1091J-880D01*
G03X751733Y189463I286J280D01*
G02X753730Y189415I975J-1008D01*
G03X754294Y189395I292J273D01*
G02X756142Y189448I954J-1027D01*
G03X756676Y189469I255J308D01*
G02X758581Y189516I978J-1005D01*
G03X759120Y189526I264J300D01*
G02X760987Y189580I964J-1018D01*
G03X761531Y189606I258J306D01*
G02X763513Y189628I1002J-980D01*
G03X764062Y189619I279J286D01*
G02X766074Y189493I945J-1036D01*
G03X766622Y189435I304J259D01*
G02X768495Y187360I854J-1112D01*
G03X768543Y186768I291J-274D01*
G02X768047Y184298I-851J-1114D01*
G03X767754Y183850I102J-387D01*
G37*
G36*
G01X1643138Y183981D02*
G02X1640433Y184087I-1338J419D01*
G03X1639869Y184358I-390J-89D01*
G02X1640658Y185686I-611J1262D01*
G03X1640976Y185534I200J10D01*
G02X1641128Y185630I823J-1135D01*
G03X1641274Y186196I-192J351D01*
G02X1643844Y187149I1183J752D01*
G03X1644283Y186809I396J58D01*
G02X1643722Y184206I150J-1394D01*
G03X1643138Y183981I-203J-345D01*
G37*
G36*
G01X1703257Y188180D02*
G02X1701704Y188154I-757J-1180D01*
G03X1701693Y188820I-227J329D01*
G02X1703246Y188846I757J1180D01*
G03X1703257Y188180I227J-329D01*
G37*
G36*
G01X1709077Y188435D02*
G02X1708544Y186943I823J-1135D01*
G03X1707923Y187165I-387J-102D01*
G02X1708456Y188657I-823J1135D01*
G03X1709077Y188435I387J102D01*
G37*
G36*
G01X726687Y189694D02*
G02X726618Y188021I1089J-883D01*
G03X725977Y188047I-330J-226D01*
G02X726046Y189720I-1089J883D01*
G03X726687Y189694I330J226D01*
G37*
G36*
G01X1945242Y191496D02*
G02X1943626Y191653I-942J-1296D01*
G03X1943713Y192323I-169J363D01*
G02X1945285Y192170I898J1077D01*
G03X1945242Y191496I192J-351D01*
G37*
G36*
G01X1264031Y192350D02*
G02X1261842Y190662I-951J-1030D01*
G03X1261189Y190740I-354J-187D01*
G02X1258828Y191177I-1049J930D01*
G03X1258177Y191325I-374J-141D01*
G02X1255826Y192116I-967J1015D01*
G03X1255404Y192451I-395J-64D01*
G02X1254628Y192625I-94J1399D01*
G03X1254099Y192497I-196J-349D01*
G02X1251543Y193067I-1169J773D01*
G03X1251134Y193409I-396J-58D01*
G02X1249691Y194909I-45J1401D01*
G03X1249354Y195333I-399J29D01*
G02X1248169Y196692I217J1385D01*
G03X1247777Y197084I-400J-8D01*
G02X1246401Y198520I26J1402D01*
G03X1246021Y198930I-400J11D01*
G02X1244688Y200354I69J1400D01*
G03X1244309Y200760I-400J7D01*
G02X1242987Y202316I71J1400D01*
G03X1242636Y202758I-398J45D01*
G02X1242119Y205375I164J1392D01*
G03X1242207Y206008I-194J350D01*
G02X1241812Y206781I990J993D01*
G03X1241202Y207056I-395J-63D01*
G02X1239442Y209213I-750J1184D01*
G03Y209767I-288J277D01*
G02Y211713I1010J973D01*
G03Y212267I-288J277D01*
G02Y214213I1010J973D01*
G03Y214767I-288J277D01*
G02X1239446Y216717I1010J973D01*
G03X1239457Y217263I-287J279D01*
G02X1241506Y217223I1043J937D01*
G03X1241495Y216677I287J-279D01*
G02X1241462Y214767I-1043J-937D01*
G03Y214213I288J-277D01*
G02Y212267I-1010J-973D01*
G03Y211713I288J-277D01*
G02Y209767I-1010J-973D01*
G03Y209213I288J-277D01*
G02X1241836Y208461I-1011J-972D01*
G03X1242446Y208186I395J63D01*
G02X1244589Y207161I750J-1184D01*
G03X1244992Y206807I397J46D01*
G02X1246416Y205371I22J-1402D01*
G03X1246772Y204964I400J-10D01*
G02X1248021Y203529I-152J-1394D01*
G03X1248392Y203118I400J-12D01*
G02X1248785Y203032I-100J-1398D01*
G03X1249304Y203272I142J374D01*
G02X1252027Y202824I1321J-468D01*
G03X1252405Y202430I400J5D01*
G02X1252469Y202425I-77J-1400D01*
G03X1252908Y202827I39J398D01*
G02X1255088Y204006I1402J13D01*
G03X1255643Y204117I222J333D01*
G02X1256982Y204731I1167J-777D01*
G03X1257426Y205064I49J397D01*
G02X1258739Y206240I1384J-224D01*
G03X1259117Y206684I-20J400D01*
G02X1260386Y208236I1393J156D01*
G03X1260734Y208747I-36J398D01*
G02X1262016Y210541I1346J393D01*
G03X1262382Y211052I-18J399D01*
G02X1265099Y211149I1346J392D01*
G03X1265481Y210665I391J-84D01*
G02X1266852Y209289I-31J-1402D01*
G03X1267244Y208897I400J8D01*
G02X1268620Y207521I-26J-1402D01*
G03X1269012Y207129I400J8D01*
G02X1270388Y205753I-26J-1402D01*
G03X1270780Y205361I400J8D01*
G02X1272156Y203985I-26J-1402D01*
G03X1272548Y203593I400J8D01*
G02X1272678Y200798I-26J-1402D01*
G03X1272325Y200360I45J-398D01*
G02X1270974Y198819I-1395J-140D01*
G03X1270602Y198309I13J-400D01*
G02X1269325Y196523I-1348J-386D01*
G03X1268947Y196079I20J-400D01*
G02X1267382Y194532I-1393J-156D01*
G03X1266941Y194218I-50J-397D01*
G02X1264803Y193336I-1371J292D01*
G03X1264242Y193208I-219J-335D01*
G02X1264022Y192929I-1202J722D01*
G03X1264031Y192350I280J-285D01*
G37*
G36*
G01X706309Y191605D02*
G02X705545Y192886I-1402J32D01*
G03X706127Y193233I182J356D01*
G02X707720Y194589I1402J-33D01*
G03X708135Y195158I54J396D01*
G02X710728Y196211I1264J605D01*
G03X711280Y195978I379J128D01*
G02X712356Y196035I606J-1264D01*
G03X712855Y196250I133J377D01*
G02X715433Y196217I1282J-568D01*
G03X715953Y195999I370J153D01*
G02X715184Y194165I527J-1299D01*
G03X714664Y194383I-370J-153D01*
G02X713667Y194361I-527J1299D01*
G03X713168Y194146I-133J-377D01*
G02X710558Y194266I-1282J568D01*
G03X710006Y194499I-379J-128D01*
G02X709209Y194374I-607J1264D01*
G03X708794Y193805I-54J-396D01*
G02X706891Y191952I-1265J-605D01*
G03X706309Y191605I-182J-356D01*
G37*
G36*
G01X698454Y194415D02*
G02X696900Y194323I-708J-1210D01*
G03X696860Y194987I-242J319D01*
G02X698414Y195079I708J1210D01*
G03X698454Y194415I242J-319D01*
G37*
G36*
G01X98575Y195729D02*
G02X97147Y195683I-675J-1229D01*
G03X97125Y196371I-214J337D01*
G02X97155Y198845I675J1229D01*
G03Y199555I-184J355D01*
G02X98445I645J1245D01*
G03Y198845I184J-355D01*
G02X98553Y196417I-645J-1245D01*
G03X98575Y195729I214J-337D01*
G37*
G36*
G01X1630836Y196158D02*
G02X1630732Y196162I2J1402D01*
G03X1630314Y195670I-29J-399D01*
G02X1629054Y196742I-1364J-326D01*
G03X1629472Y197234I29J399D01*
G02X1632121Y197000I1364J326D01*
G03X1632340Y196724I184J-79D01*
G02X1632363Y196727I193J-1387D01*
G03X1632691Y197196I-65J395D01*
G02X1634296Y196071I1378J258D01*
G03X1633968Y195602I65J-395D01*
G02X1631226Y195666I-1378J-258D01*
G03X1630837Y196158I-389J92D01*
G01X1630836D01*
G37*
G36*
G01X105535Y196906D02*
G02X104105I-715J-1206D01*
G03Y197594I-204J344D01*
G02X105535I715J1206D01*
G03Y196906I204J-344D01*
G37*
G36*
G01X1731771Y195558D02*
G02X1731397Y196835I-1371J292D01*
G03X1732076Y197045I285J281D01*
G02X1733563Y198288I1487J-268D01*
G01X1738564D01*
G02X1740074Y196786I-1J-1512D01*
G01Y196691D01*
X1740065Y196607D01*
G02X1738563Y195264I-1502J168D01*
G01X1733563D01*
G02X1732456Y195747I1J1512D01*
G03X1731771Y195558I-294J-272D01*
G37*
G36*
G01X607489Y199401D02*
G02X605767Y199172I-716J-1205D01*
G03X605684Y199795I-287J279D01*
G02X605006Y201146I716J1205D01*
G03X604573Y201586I-398J41D01*
G02X605847Y202837I-120J1397D01*
G03X606280Y202397I398J-41D01*
G02X607406Y200024I120J-1397D01*
G03X607489Y199401I287J-279D01*
G37*
G36*
G01X1916583Y202212D02*
G02Y200218I985J-997D01*
G03X1915902Y199934I-281J-285D01*
G01Y196848D01*
X1913898D01*
Y202352D01*
X1915929D01*
G03X1916583Y202212I373J145D01*
G37*
G36*
G01X799325Y200502D02*
G02X798088Y199804I-24J-1402D01*
G03X797737Y200405I-346J201D01*
G02X798992Y201113I-20J1502D01*
G03X799325Y200502I340J-211D01*
G37*
G36*
G01X1894193Y200047D02*
G02X1893186Y201414I-1402J22D01*
G03X1893698Y201792I112J384D01*
G02X1894569Y203068I1402J-22D01*
G03X1894683Y203737I-152J370D01*
G02X1896145Y203487I932J1048D01*
G03X1896031Y202818I152J-370D01*
G02X1894705Y200425I-931J-1048D01*
G03X1894193Y200047I-112J-384D01*
G37*
G36*
G01X579220Y203377D02*
G02X578123Y202280I277J-1374D01*
G03X577652Y202751I-392J79D01*
G02X578749Y203848I-277J1374D01*
G03X579220Y203377I392J-79D01*
G37*
G36*
G01X1403833Y206100D02*
G02X1402555Y205885I-433J-1334D01*
G03X1402437Y206584I-241J319D01*
G02X1403715Y206799I433J1334D01*
G03X1403833Y206100I241J-319D01*
G37*
G36*
G01X562584Y206877D02*
G02X561487Y205780I277J-1374D01*
G03X561016Y206251I-392J79D01*
G02X562113Y207348I-277J1374D01*
G03X562584Y206877I392J-79D01*
G37*
G36*
G01X1955487Y214076D02*
G03X1955651Y214607I-193J350D01*
G02X1956220Y216466I1250J634D01*
G03Y217166I-194J350D01*
G02X1957582I681J1225D01*
G03Y216466I194J-350D01*
G02X1958147Y214599I-681J-1225D01*
G03X1958308Y214067I356J-183D01*
G02X1959541Y212715I-1418J-2532D01*
G03X1960200Y212606I365J163D01*
G02X1959928Y209839I1690J-1563D01*
G03X1959260Y209861I-341J-209D01*
G02X1957697Y208747I-2371J1673D01*
G01X1957552Y208706D01*
Y204492D01*
X1946598D01*
Y213346D01*
X1954623D01*
G02X1955487Y214076I2269J-1809D01*
G37*
G36*
G01X1330337Y207982D02*
G02X1330256Y209998I-1013J969D01*
G03X1330811Y210020I266J299D01*
G02X1332952Y209883I1013J-969D01*
G03X1333596I322J238D01*
G02Y208219I1128J-832D01*
G03X1332952I-322J-238D01*
G02X1330892Y208004I-1128J832D01*
G03X1330337Y207982I-266J-299D01*
G37*
G36*
G01X1884653Y211688D02*
G02X1882947I-853J-1113D01*
G03Y212323I-243J317D01*
G02X1885092Y213981I853J1113D01*
G03X1885791Y213912I368J155D01*
G02X1885660Y212580I1161J-787D01*
G03X1884961Y212649I-368J-155D01*
G02X1884653Y212323I-1160J788D01*
G03Y211688I243J-318D01*
G37*
G36*
G01X565773Y212929D02*
G02X564656Y211694I278J-1374D01*
G03X564178Y212126I-398J40D01*
G02X565295Y213361I-278J1374D01*
G03X565773Y212929I398J-40D01*
G37*
G36*
G01X174485Y210977D02*
G02X172328Y213045I-1185J923D01*
G03Y213655I-259J305D01*
G02Y215945I972J1145D01*
G03Y216555I-259J305D01*
G02X174603Y218448I972J1145D01*
G03X175233Y218366I346J199D01*
G02X177779Y217570I1067J-1058D01*
G03X178410Y217318I394J70D01*
G02X180485Y217031I890J-1210D01*
G03X181115I315J246D01*
G02Y215185I1185J-923D01*
G03X180485I-315J-246D01*
G02X180272Y214963I-1185J923D01*
G03Y214353I259J-305D01*
G02X178421Y211990I-972J-1145D01*
G03X177791Y211715I-233J-325D01*
G02X175115Y210977I-1491J185D01*
G03X174485I-315J-246D01*
G37*
G36*
G01X1848935Y212284D02*
G02Y213608I-1236J662D01*
G03X1849640I353J189D01*
G02Y212284I1236J-662D01*
G03X1848935I-352J-189D01*
G37*
G36*
G01X116300Y214684D02*
G02X114751Y214669I-763J-1176D01*
G03X114744Y215336I-224J331D01*
G02X116293Y215351I763J1176D01*
G03X116300Y214684I224J-331D01*
G37*
G36*
G01X765908D02*
G02X764359Y214669I-763J-1176D01*
G03X764352Y215336I-224J331D01*
G02X765901Y215351I763J1176D01*
G03X765908Y214684I224J-331D01*
G37*
G36*
G01X1220270Y214898D02*
G02X1218893Y216271I-1402J-29D01*
G03X1219300Y216679I7J400D01*
G02X1219317Y216923I1402J25D01*
G03X1218979Y217097I-198J31D01*
G02X1219396Y218228I-979J1003D01*
G03X1219996Y217919I398J37D01*
G02X1220677Y215306I706J-1211D01*
G03X1220270Y214898I-7J-400D01*
G37*
G36*
G01X1331241Y215723D02*
G02Y217277I-1167J777D01*
G03X1331907I333J222D01*
G02X1334241I1167J-777D01*
G03X1334907I333J222D01*
G02Y215723I1167J-777D01*
G03X1334241I-333J-222D01*
G02X1331907I-1167J777D01*
G03X1331241I-333J-222D01*
G37*
G36*
G01X580354Y218161D02*
G02X579257Y219258I-1374J-277D01*
G03X579728Y219729I79J392D01*
G02X580825Y218632I1374J277D01*
G03X580354Y218161I-79J-392D01*
G37*
G36*
G01X743908Y222185D02*
G02X741579Y220827I-971J-1011D01*
G03X741024Y221091I-388J-99D01*
G02X739426Y221393I-587J1273D01*
G03X738848I-289J-277D01*
G02X736866Y223375I-1011J971D01*
G03Y223953I-277J289D01*
G02X738848Y225935I971J1011D01*
G03X739426I289J277D01*
G02X739696Y226154I1011J-971D01*
G03X739665Y226850I-212J339D01*
G02X741685Y228317I635J1250D01*
G03X742262Y228023I395J62D01*
G02X743690Y225617I635J-1250D01*
G03X743699Y224951I226J-330D01*
G02X743908Y222763I-762J-1177D01*
G03Y222185I277J-289D01*
G37*
G36*
G01X642696Y222427D02*
G02X640504I-1096J-1027D01*
G03Y222973I-292J273D01*
G02Y225027I1096J1027D01*
G03Y225573I-292J273D01*
G02Y227627I1096J1027D01*
G03Y228173I-292J273D01*
G02Y230227I1096J1027D01*
G03Y230773I-292J273D01*
G02X642745Y232772I1096J1027D01*
G03X643355I305J259D01*
G02X645724Y232670I1145J-972D01*
G03X646376I326J232D01*
G02X648824I1224J-870D01*
G03X649476I326J232D01*
G02X651796Y230773I1225J-869D01*
G03Y230227I292J-273D01*
G02Y228173I-1096J-1027D01*
G03Y227627I292J-273D01*
G02X652171Y226905I-1096J-1027D01*
G03X652812Y226673I392J81D01*
G02X652843Y224303I938J-1173D01*
G03X652202Y223987I-241J-319D01*
G02X649476Y223130I-1502J13D01*
G03X648824I-326J-232D01*
G02X646376I-1224J870D01*
G03X645724I-326J-232D01*
G02X643355Y223028I-1224J870D01*
G03X642745I-305J-259D01*
G02X642696Y222973I-1146J971D01*
G03Y222427I292J-273D01*
G37*
G36*
G01X1903999Y226780D02*
G02X1902051Y226789I-979J-1004D01*
G03X1902053Y227364I-277J288D01*
G02X1902167Y229471I979J1004D01*
G03X1902139Y230121I-247J315D01*
G02X1903772Y230191I768J1173D01*
G03X1903800Y229541I247J-315D01*
G02X1904001Y227355I-768J-1173D01*
G03X1903999Y226780I277J-288D01*
G37*
G36*
G01X1398440Y226716D02*
G02X1395924Y225485I-1229J-675D01*
G03X1395407Y225697I-367J-159D01*
G02X1396168Y227553I-526J1300D01*
G03X1396685Y227341I367J159D01*
G02X1397063Y227435I524J-1300D01*
G03X1397371Y228025I-43J398D01*
G02X1399574Y229708I1229J675D01*
G03X1400233Y229871I279J287D01*
G02X1400591Y228427I1332J-436D01*
G03X1399932Y228264I-279J-287D01*
G02X1398748Y227306I-1332J436D01*
G03X1398440Y226716I43J-398D01*
G37*
G36*
G01X602200Y227570D02*
G02X602143Y225908I1100J-870D01*
G03X601500Y225930I-330J-226D01*
G02X601557Y227592I-1100J870D01*
G03X602200Y227570I330J226D01*
G37*
G36*
G01X1279850Y230736D02*
G02X1278675Y229922I99J-1398D01*
G03X1278283Y230488I-363J167D01*
G02X1276858Y232344I-100J1398D01*
G03X1276513Y232873I-378J130D01*
G02X1275240Y234465I115J1397D01*
G03X1274912Y234915I-396J56D01*
G02X1276542Y236101I242J1381D01*
G03X1276870Y235651I396J-56D01*
G02X1277953Y233812I-242J-1381D01*
G03X1278298Y233283I378J-130D01*
G02X1279458Y231302I-115J-1397D01*
G03X1279850Y230736I363J-167D01*
G37*
G36*
G01X1967564Y228788D02*
G02Y230412I-1264J812D01*
G03X1968236I336J216D01*
G02Y228788I1264J-812D01*
G03X1967564I-336J-216D01*
G37*
G36*
G01X1398802Y232142D02*
G02X1398004Y233383I-1402J-24D01*
G03X1398576Y233751I172J361D01*
G02X1399003Y234783I1402J24D01*
G03X1399023Y235337I-278J287D01*
G02X1398664Y236309I1043J937D01*
G03X1398073Y236670I-400J10D01*
G02X1398802Y237865I-673J1230D01*
G03X1399393Y237504I400J-10D01*
G02X1401041Y235266I674J-1230D01*
G03X1401021Y234712I278J-287D01*
G02X1399374Y232510I-1043J-937D01*
G03X1398802Y232142I-172J-361D01*
G37*
G36*
G01X1837228Y234063D02*
G02X1835822Y233596I-328J-1363D01*
G03X1835608Y234241I-307J256D01*
G02X1837014Y234708I328J1363D01*
G03X1837228Y234063I307J-256D01*
G37*
G36*
G01X1735168Y232256D02*
G02X1734900Y233771I-1288J553D01*
G03X1735559Y233888I291J274D01*
G02X1738014Y234111I1288J-554D01*
G03X1738680I333J222D01*
G02X1740447Y234601I1167J-777D01*
G03X1741013Y234900I171J362D01*
G02X1741191Y235395I1385J-219D01*
G03X1741020Y235959I-344J204D01*
G02X1740644Y236215I648J1355D01*
G03X1740093Y236209I-272J-293D01*
G02X1737939Y236267I-1049J1075D01*
G03X1737368Y236286I-295J-270D01*
G02X1735427Y236290I-968J1014D01*
G03X1734873I-277J-288D01*
G02Y238310I-973J1010D01*
G03X1735427I277J288D01*
G02X1737380Y238302I972J-1010D01*
G03X1737951Y238314I280J286D01*
G02X1740068Y238383I1093J-1030D01*
G03X1740619Y238389I272J293D01*
G02X1742718Y238388I1049J-1075D01*
G03X1743273Y238384I280J286D01*
G02X1745454Y238266I1035J-1089D01*
G03X1746068Y238270I305J258D01*
G02X1746081Y236343I1159J-956D01*
G03X1745467Y236339I-305J-258D01*
G02X1744101Y235807I-1159J956D01*
G03X1743680Y235249I-56J-396D01*
G02X1741798Y233414I-1282J-568D01*
G03X1741232Y233115I-171J-362D01*
G02X1738680Y232557I-1385J219D01*
G03X1738014I-333J-222D01*
G02X1735827Y232373I-1167J777D01*
G03X1735168Y232256I-291J-274D01*
G37*
G36*
G01X123238Y235830D02*
G02X121540Y236050I-1008J-1114D01*
G03X121625Y236702I-183J355D01*
G02X123790Y238773I1007J1114D01*
G03X124406I308J255D01*
G02Y236859I1158J-957D01*
G03X123790I-308J-255D01*
G02X123323Y236482I-1158J957D01*
G03X123238Y235830I183J-355D01*
G37*
G36*
G01X1608415Y241546D02*
G02X1607183Y242777I-1566J-336D01*
G03X1607662Y243223I83J391D01*
G02X1608861Y242026I1389J192D01*
G03X1608415Y241546I-55J-396D01*
G37*
G36*
G01X1667018Y243217D02*
G02X1665659Y243210I-673J-1230D01*
G03X1665656Y243909I-196J349D01*
G02X1667015Y243916I673J1230D01*
G03X1667018Y243217I196J-349D01*
G37*
G36*
G01X1682647Y243237D02*
G02X1682508Y241656I1082J-892D01*
G03X1681851Y241714I-348J-196D01*
G02X1680454Y243971I-1082J891D01*
G03X1680674Y244614I-90J390D01*
G02X1682786Y246455I1086J886D01*
G03X1683397Y246484I293J272D01*
G02X1683483Y244676I1112J-853D01*
G03X1682872Y244647I-293J-272D01*
G02X1682075Y244134I-1113J853D01*
G03X1681855Y243491I90J-390D01*
G02X1681990Y243295I-1083J-890D01*
G03X1682647Y243237I348J196D01*
G37*
G36*
G01X128755Y242876D02*
G02X128442Y244539I-1255J625D01*
G03X129069Y244657I269J296D01*
G02X129382Y242994I1255J-625D01*
G03X128755Y242876I-269J-296D01*
G37*
G36*
G01X778282Y242932D02*
G02X778000Y244483I-1282J568D01*
G03X778650Y244601I285J281D01*
G02X778932Y243050I1282J-568D01*
G03X778282Y242932I-285J-281D01*
G37*
G36*
G01X1437365Y245552D02*
G02X1436078Y244616I35J-1402D01*
G03X1435690Y245148I-377J132D01*
G02X1436977Y246084I-35J1402D01*
G03X1437365Y245552I377J-132D01*
G37*
G36*
G01X116289Y246548D02*
G02X114740Y246533I-763J-1176D01*
G03X114733Y247200I-224J331D01*
G02X116282Y247215I763J1176D01*
G03X116289Y246548I224J-331D01*
G37*
G36*
G01X765908Y246684D02*
G02X764359Y246669I-763J-1176D01*
G03X764352Y247336I-224J331D01*
G02X765901Y247351I763J1176D01*
G03X765908Y246684I224J-331D01*
G37*
G36*
G01X849467Y245504D02*
G02X847186Y247454I-1185J923D01*
G03Y248000I-292J273D01*
G02X847224Y250093I1096J1027D01*
G03Y250661I-282J284D01*
G02X846884Y251179I1059J1065D01*
G03X846204Y251289I-373J-146D01*
G02X846448Y252798I-1154J961D01*
G03X847128Y252688I373J146D01*
G02X847186Y252754I1157J-958D01*
G03Y253300I-292J273D01*
G02X849467Y255250I1096J1027D01*
G03X850097I315J246D01*
G02X852467I1185J-923D01*
G03X853097I315J246D01*
G02X855467I1185J-923D01*
G03X856097I315J246D01*
G02X858378Y253300I1185J-923D01*
G03Y252754I292J-273D01*
G02X858340Y250661I-1096J-1027D01*
G03Y250093I282J-284D01*
G02X858378Y248000I-1058J-1066D01*
G03Y247454I292J-273D01*
G02X856097Y245504I-1096J-1027D01*
G03X855467I-315J-246D01*
G02X853097I-1185J923D01*
G03X852467I-315J-246D01*
G02X850097I-1185J923D01*
G03X849467I-315J-246D01*
G37*
G36*
G01X199345Y245528D02*
G02X197277Y247685I-1145J972D01*
G03Y248315I-246J315D01*
G02Y250685I923J1185D01*
G03Y251315I-246J315D01*
G02X197111Y251466I925J1183D01*
G03X196459Y251360I-290J-276D01*
G02X196189Y253034I-1359J640D01*
G03X196841Y253140I290J276D01*
G02X199385Y253423I1359J-640D01*
G03X200015I315J246D01*
G02X202385I1185J-923D01*
G03X203015I315J246D01*
G02X205385I1185J-923D01*
G03X206015I315J246D01*
G02X208123Y251315I1185J-923D01*
G03Y250685I246J-315D01*
G02X207871Y248156I-923J-1185D01*
G03X207772Y247510I179J-358D01*
G02X205722Y245604I-972J-1010D01*
G03X205096Y245591I-308J-255D01*
G02X202794Y245483I-1196J909D01*
G03X202206I-294J-270D01*
G02X199955Y245528I-1106J1017D01*
G03X199345I-305J-259D01*
G37*
G36*
G01X1663900Y249338D02*
G02X1662940Y248226I424J-1336D01*
G03X1662424Y248672I-395J65D01*
G02X1663384Y249784I-424J1336D01*
G03X1663900Y249338I395J-65D01*
G37*
G36*
G01X718606Y249173D02*
G02X718591Y250691I-1186J747D01*
G03X719264Y250697I335J219D01*
G02X721584Y250774I1186J-747D01*
G03X722239Y250786I323J236D01*
G02X724545Y250809I1161J-786D01*
G03X725195Y250805I326J231D01*
G02X725183Y249170I1133J-826D01*
G03X724533Y249174I-326J-231D01*
G02X722266Y249176I-1133J826D01*
G03X721611Y249164I-323J-236D01*
G02X719279Y249179I-1161J786D01*
G03X718606Y249173I-335J-219D01*
G37*
G36*
G01X658864Y249391D02*
G02X658783Y251062I-1164J781D01*
G03X659424Y251093I309J254D01*
G02X659505Y249422I1164J-781D01*
G03X658864Y249391I-309J-254D01*
G37*
G36*
G01X1500777Y249858D02*
G02X1500262Y251528I-1305J512D01*
G03X1500860Y251712I226J330D01*
G02X1501375Y250042I1305J-512D01*
G03X1500777Y249858I-226J-330D01*
G37*
G36*
G01X1588322Y250980D02*
G02X1587633Y252491I-1372J287D01*
G03X1588220Y252759I195J349D01*
G02X1588909Y251248I1372J-287D01*
G03X1588322Y250980I-195J-349D01*
G37*
G36*
G01X1440096Y254445D02*
G02X1438370Y253545I-396J-1345D01*
G03X1438104Y254055I-379J127D01*
G02X1437463Y256344I396J1345D01*
G03X1437308Y256987I-296J269D01*
G02X1438837Y257356I492J1313D01*
G03X1438992Y256713I296J-269D01*
G02X1439830Y254955I-492J-1313D01*
G03X1440096Y254445I379J-127D01*
G37*
G36*
G01X1859705Y253139D02*
G02X1859613Y254436I-1285J561D01*
G03X1860320Y254486I340J210D01*
G02X1862690Y254813I1285J-561D01*
G03X1863289Y254791I309J254D01*
G02X1863220Y252937I1016J-966D01*
G03X1862621Y252959I-309J-254D01*
G02X1860412Y253189I-1016J966D01*
G03X1859705Y253139I-340J-210D01*
G37*
G36*
G01X749809Y253142D02*
G02X749663Y255019I-1109J858D01*
G03X750254Y255065I275J291D01*
G02X752491Y255039I1109J-858D01*
G03X753135I322J238D01*
G02Y253375I1128J-832D01*
G03X752491I-322J-238D01*
G02X750400Y253188I-1128J832D01*
G03X749809Y253142I-275J-291D01*
G37*
G36*
G01X1671347Y255991D02*
G02X1669766Y255613I-525J-1300D01*
G03X1669615Y256247I-301J263D01*
G02X1669027Y256694I525J1300D01*
G03X1668478Y256777I-318J-243D01*
G02X1666532Y258743I-811J1144D01*
G03X1666377Y259340I-324J234D01*
G02X1668103Y259788I591J1271D01*
G03X1668258Y259191I324J-234D01*
G02X1668780Y258773I-590J-1272D01*
G03X1669329Y258690I318J243D01*
G02X1671196Y256625I810J-1144D01*
G03X1671347Y255991I301J-263D01*
G37*
G36*
G01X1621068Y255879D02*
G02X1619424Y255874I-819J-1138D01*
G03X1619422Y256522I-236J323D01*
G02X1621066Y256527I819J1138D01*
G03X1621068Y255879I236J-323D01*
G37*
G36*
G01X1309929Y256611D02*
G02X1309831Y254805I1021J-961D01*
G03X1309221Y254839I-319J-241D01*
G02X1306892Y256305I-1021J961D01*
G03X1306534Y256849I-373J144D01*
G02X1307893Y257745I51J1401D01*
G03X1308251Y257201I373J-144D01*
G02X1309319Y256645I-51J-1401D01*
G03X1309929Y256611I319J241D01*
G37*
G36*
G01X1592584Y258161D02*
G02X1590540Y255962I-985J-1133D01*
G03X1589993Y255978I-282J-284D01*
G02X1587974Y256006I-994J1126D01*
G03X1587428Y256005I-272J-293D01*
G02X1585060Y256418I-1029J1094D01*
G03X1584355Y256433I-357J-181D01*
G02X1582112Y258346I-1308J738D01*
G03X1582118Y258967I-249J313D01*
G02X1584464Y260702I960J1155D01*
G03X1585168Y260639I369J155D01*
G02X1587464Y260914I1262J-815D01*
G03X1588011Y260910I276J290D01*
G02X1590007Y260948I1019J-1103D01*
G03X1590553Y260973I260J304D01*
G02X1592590Y258770I1074J-1050D01*
G03X1592584Y258161I256J-307D01*
G37*
G36*
G01X1884646Y261214D02*
G02X1882480Y259185I-924J-1185D01*
G03X1881830Y259202I-331J-224D01*
G02X1879710Y261294I-1197J907D01*
G03Y261924I-246J315D01*
G02X1881876Y263953I924J1185D01*
G03X1882526Y263936I331J224D01*
G02X1884646Y261844I1197J-907D01*
G03Y261214I246J-315D01*
G37*
G36*
G01X643632Y262228D02*
G02X641968I-832J-1128D01*
G03Y262872I-238J322D01*
G02X642408Y265346I832J1128D01*
G03X642583Y266008I-112J384D01*
G02X642443Y267787I1008J974D01*
G03X642279Y268382I-328J230D01*
G02X644003Y268856I576J1278D01*
G03X644167Y268261I328J-230D01*
G02X643983Y265637I-576J-1278D01*
G03X643808Y264975I112J-384D01*
G02X643632Y262872I-1008J-975D01*
G03Y262228I238J-322D01*
G37*
G36*
G01X445821Y262562D02*
G02X444136Y262342I-698J-1216D01*
G03X444054Y262972I-282J284D01*
G02X443931Y265325I698J1216D01*
G03X443855Y266017I-234J325D01*
G02X445229Y266168I554J1288D01*
G03X445305Y265476I234J-325D01*
G02X445739Y263192I-553J-1288D01*
G03X445821Y262562I282J-284D01*
G37*
G36*
G01X1087133Y263352D02*
G02X1084941Y263301I-1072J-1052D01*
G03X1084928Y263848I-298J267D01*
G02X1087371Y265514I1072J1052D01*
G03X1088039Y265416I365J163D01*
G02X1088053Y265432I1062J-915D01*
G03X1088031Y265987I-299J266D01*
G02X1090047Y266068I969J1013D01*
G03X1090069Y265513I299J-266D01*
G02X1090267Y265277I-969J-1014D01*
G03X1090933I333J222D01*
G02X1091255Y265619I1167J-777D01*
G03X1091299Y266218I-241J319D01*
G02X1093145Y266081I1001J982D01*
G03X1093101Y265482I241J-319D01*
G02X1090933Y263723I-1001J-982D01*
G03X1090267I-333J-222D01*
G02X1087841Y263883I-1167J777D01*
G03X1087170Y263958I-359J-176D01*
G02X1087120Y263899I-1171J941D01*
G03X1087133Y263352I298J-267D01*
G37*
G36*
G01X440857Y264577D02*
G02X439243Y265001I-1093J-878D01*
G03X439407Y265622I-148J371D01*
G02X441021Y265198I1093J878D01*
G03X440857Y264577I148J-371D01*
G37*
G36*
G01X1065189Y265711D02*
G02X1065123Y263768I1111J-1010D01*
G03X1064513Y263788I-313J-249D01*
G02X1062217Y263876I-1111J1011D01*
G03X1061587I-315J-246D01*
G02X1059113Y264028I-1185J923D01*
G03X1058440Y264049I-343J-206D01*
G02X1056017Y263976I-1238J850D01*
G03X1055387I-315J-246D01*
G02Y265822I-1185J923D01*
G03X1056017I315J246D01*
G02X1058491Y265670I1185J-923D01*
G03X1059164Y265649I343J206D01*
G02X1061587Y265722I1238J-850D01*
G03X1062217I315J246D01*
G02X1064579Y265731I1185J-923D01*
G03X1065189Y265711I313J249D01*
G37*
G36*
G01X392061Y264122D02*
G02Y265676I-1167J777D01*
G03X392727I333J222D01*
G02Y264122I1167J-777D01*
G03X392061I-333J-222D01*
G37*
G36*
G01X398561D02*
G02Y265676I-1167J777D01*
G03X399227I333J222D01*
G02Y264122I1167J-777D01*
G03X398561I-333J-222D01*
G37*
G36*
G01X1041669D02*
G02Y265676I-1167J777D01*
G03X1042335I333J222D01*
G02Y264122I1167J-777D01*
G03X1041669I-333J-222D01*
G37*
G36*
G01X1048169D02*
G02Y265676I-1167J777D01*
G03X1048835I333J222D01*
G02Y264122I1167J-777D01*
G03X1048169I-333J-222D01*
G37*
G36*
G01X451230Y266487D02*
G02X450517Y264930I653J-1241D01*
G03X449941Y265194I-390J-90D01*
G02X450654Y266751I-653J1241D01*
G03X451230Y266487I390J90D01*
G37*
G36*
G01X1096538Y267024D02*
G02X1094862I-838J-1124D01*
G03Y267666I-239J321D01*
G02X1096538I838J1124D01*
G03Y267024I239J-321D01*
G37*
G36*
G01X123208Y267857D02*
G02X121491Y268023I-977J-1141D01*
G03X121554Y268675I-197J348D01*
G02X123689Y270773I978J1140D01*
G03X124305I308J255D01*
G02Y268859I1158J-957D01*
G03X123689I-308J-255D01*
G02X123271Y268509I-1157J958D01*
G03X123208Y267857I197J-348D01*
G37*
G36*
G01X186837Y269010D02*
G02X184675Y271095I-1069J1055D01*
G03X184672Y271647I-291J274D01*
G02X184782Y273834I1082J1042D01*
G03X184778Y274447I-259J305D01*
G02X184629Y274587I952J1162D01*
G03X184041I-294J-270D01*
G02X181820Y274597I-1106J1017D01*
G03X181169Y274513I-296J-268D01*
G02X178650Y274281I-1334J691D01*
G03X178020I-315J-246D01*
G02X175650I-1185J923D01*
G03X175020I-315J-246D01*
G02X172739Y276231I-1185J923D01*
G03Y276777I-292J273D01*
G02X175020Y278727I1096J1027D01*
G03X175650I315J246D01*
G02X178020I1185J-923D01*
G03X178650I315J246D01*
G02X180950Y278811I1185J-923D01*
G03X181601Y278895I296J268D01*
G02X184041Y279221I1334J-691D01*
G03X184629I294J270D01*
G02X186833Y279229I1106J-1017D01*
G03X187436Y279249I293J273D01*
G02X189669Y279355I1164J-949D01*
G03X190258Y279376I285J281D01*
G02X190331Y277345I1142J-976D01*
G03X189742Y277324I-285J-281D01*
G02X189633Y277210I-1139J980D01*
G03X189620Y276643I276J-290D01*
G02X189479Y274436I-1085J-1039D01*
G03X189474Y273818I251J-311D01*
G02X189592Y271624I-964J-1152D01*
G03X189585Y271077I288J-277D01*
G02X187406Y269010I-1110J-1012D01*
G03X186837I-285J-281D01*
G37*
G36*
G01X653393Y271818D02*
G02X651851Y271716I-694J-1218D01*
G03X651807Y272382I-242J318D01*
G02X653349Y272484I694J1218D01*
G03X653393Y271818I242J-318D01*
G37*
G36*
G01X710700Y273831D02*
G02X709004Y273683I-751J-1184D01*
G03X708949Y274316I-269J295D01*
G02X708692Y276474I751J1184D01*
G03X708670Y277051I-288J278D01*
G02X708511Y277217I930J1049D01*
G03X707889I-311J-252D01*
G02Y278983I-1089J883D01*
G03X708511I311J252D01*
G02X710608Y277126I1090J-882D01*
G03X710630Y276549I288J-278D01*
G02X710645Y274464I-930J-1049D01*
G03X710700Y273831I269J-295D01*
G37*
G36*
G01X1624564Y272426D02*
G02X1624542Y274148I-1117J847D01*
G03X1625174Y274156I313J249D01*
G02X1625196Y272434I1117J-847D01*
G03X1624564Y272426I-313J-249D01*
G37*
G36*
G01X755577Y274494D02*
G02X754007Y274540I-819J-1138D01*
G03X754027Y275202I-214J338D01*
G02X755597Y275156I819J1138D01*
G03X755577Y274494I214J-338D01*
G37*
G36*
G01X202032Y274010D02*
G02X199964Y276148I-1185J923D01*
G03X199985Y276779I-235J324D01*
G02X199794Y276970I962J1153D01*
G03X199192Y276983I-307J-257D01*
G02X197199Y279210I-1110J1012D01*
G03X197220Y279841I-235J324D01*
G02X199297Y282001I962J1154D01*
G03X199878Y281988I297J268D01*
G02X202180Y281790I1069J-1055D01*
G03X202828Y281778I328J229D01*
G02X204792Y279814I1119J-845D01*
G03X204804Y279166I241J-320D01*
G02X204830Y276718I-857J-1233D01*
G03X204809Y276087I235J-324D01*
G02X202662Y274010I-962J-1153D01*
G03X202032I-315J-246D01*
G37*
G36*
G01X128755Y274876D02*
G02X128442Y276539I-1255J625D01*
G03X129069Y276657I269J296D01*
G02X129382Y274994I1255J-625D01*
G03X128755Y274876I-269J-296D01*
G37*
G36*
G01X116300Y278684D02*
G02X114751Y278669I-763J-1176D01*
G03X114744Y279336I-224J331D01*
G02X116293Y279351I763J1176D01*
G03X116300Y278684I224J-331D01*
G37*
G36*
G01X765908D02*
G02X764359Y278669I-763J-1176D01*
G03X764352Y279336I-224J331D01*
G02X765901Y279351I763J1176D01*
G03X765908Y278684I224J-331D01*
G37*
G36*
G01X750187Y280386D02*
G02X748558Y280793I-1087J-886D01*
G03X748713Y281414I-155J369D01*
G02X750342Y281007I1087J886D01*
G03X750187Y280386I155J-369D01*
G37*
G36*
G01X690825Y282220D02*
G02X689271I-777J-1167D01*
G03Y282886I-222J333D01*
G02X690825I777J1167D01*
G03Y282220I222J-333D01*
G37*
G36*
G01X1495494Y282261D02*
G02X1495450Y280598I1106J-861D01*
G03X1494806Y280615I-328J-229D01*
G02X1494850Y282278I-1106J861D01*
G03X1495494Y282261I328J229D01*
G37*
G36*
G01X1405610Y282190D02*
G02X1402952Y282162I-1324J-461D01*
G03X1402465Y282671I-380J124D01*
G02X1403191Y283152I-373J1351D01*
G03X1403465Y282866I157J-124D01*
G02X1403822Y283052I820J-1138D01*
G03X1404068Y283561I-132J378D01*
G02X1405856Y282699I1324J461D01*
G03X1405610Y282190I132J-378D01*
G37*
G36*
G01X684678Y281366D02*
G02X684620Y282940I-1188J744D01*
G03X685282Y282964I323J236D01*
G02X685340Y281390I1188J-744D01*
G03X684678Y281366I-323J-236D01*
G37*
G36*
G01X766364Y284716D02*
G02X765442Y285696I-1357J-353D01*
G03X765953Y286177I124J380D01*
G02X765923Y286323I1357J355D01*
G03X765406Y286644I-395J-60D01*
G02X766367Y288187I-426J1336D01*
G03X766884Y287866I395J60D01*
G02X766875Y285197I426J-1336D01*
G03X766364Y284716I-124J-380D01*
G37*
G36*
G01X656121Y285442D02*
G02X654689Y285967I-1121J-842D01*
G03X654921Y286597I-88J390D01*
G02X656353Y286072I1121J842D01*
G03X656121Y285442I88J-390D01*
G37*
G36*
G01X1357775Y285582D02*
G02X1357735Y284295I1225J-682D01*
G03X1357025Y284318I-361J-172D01*
G02X1357065Y285605I-1225J682D01*
G03X1357775Y285582I361J172D01*
G37*
G36*
G01X1116937Y288227D02*
G02X1115684Y287313I62J-1401D01*
G03X1115292Y287851I-375J139D01*
G02X1116545Y288765I-62J1401D01*
G03X1116937Y288227I375J-139D01*
G37*
G36*
G01X465845Y293836D02*
G02X464680Y292661I221J-1384D01*
G03X464221Y293116I-396J60D01*
G02X465386Y294291I-221J1384D01*
G03X465845Y293836I396J-60D01*
G37*
G36*
G01X1455422Y293767D02*
G02X1454196Y293829I-671J-1116D01*
G03X1454231Y294533I-171J361D01*
G02X1455457Y294471I671J1116D01*
G03X1455422Y293767I171J-361D01*
G37*
G36*
G01X391445Y293739D02*
G02X391442Y292074I1249J-835D01*
G03X390777Y292075I-333J-221D01*
G02X390780Y293740I-1249J835D01*
G03X391445Y293739I333J221D01*
G37*
G36*
G01X1019491Y293792D02*
G02X1019487Y292021I1211J-888D01*
G03X1018841Y292022I-323J-236D01*
G02X1018845Y293793I-1211J888D01*
G03X1019491Y293792I323J236D01*
G37*
G36*
G01X1033860Y293749D02*
G02X1033857Y292064I1242J-845D01*
G03X1033195Y292065I-331J-224D01*
G02X1033198Y293750I-1242J845D01*
G03X1033860Y293749I331J224D01*
G37*
G36*
G01X1041074Y293769D02*
G02X1041066Y292051I1228J-865D01*
G03X1040410Y292054I-329J-227D01*
G02X1040418Y293772I-1228J865D01*
G03X1041074Y293769I329J227D01*
G37*
G36*
G01X1048230Y293702D02*
G02X1048227Y292110I1272J-798D01*
G03X1047548Y292112I-340J-211D01*
G02X1047551Y293704I-1272J798D01*
G03X1048230Y293702I340J211D01*
G37*
G36*
G01X1055512Y293821D02*
G02X1055509Y291992I1190J-916D01*
G03X1054874Y291993I-318J-243D01*
G02X1054877Y293822I-1190J916D01*
G03X1055512Y293821I318J243D01*
G37*
G36*
G01X412461Y292127D02*
G02Y293681I-1167J777D01*
G03X413127I333J222D01*
G02Y292127I1167J-777D01*
G03X412461I-333J-222D01*
G37*
G36*
G01X419661D02*
G02Y293681I-1167J777D01*
G03X420327I333J222D01*
G02Y292127I1167J-777D01*
G03X419661I-333J-222D01*
G37*
G36*
G01X426861D02*
G02Y293681I-1167J777D01*
G03X427527I333J222D01*
G02Y292127I1167J-777D01*
G03X426861I-333J-222D01*
G37*
G36*
G01X434061D02*
G02Y293681I-1167J777D01*
G03X434727I333J222D01*
G02Y292127I1167J-777D01*
G03X434061I-333J-222D01*
G37*
G36*
G01X441261D02*
G02Y293681I-1167J777D01*
G03X441927I333J222D01*
G02Y292127I1167J-777D01*
G03X441261I-333J-222D01*
G37*
G36*
G01X1062069D02*
G02Y293681I-1167J777D01*
G03X1062735I333J222D01*
G02Y292127I1167J-777D01*
G03X1062069I-333J-222D01*
G37*
G36*
G01X1069269D02*
G02Y293681I-1167J777D01*
G03X1069935I333J222D01*
G02Y292127I1167J-777D01*
G03X1069269I-333J-222D01*
G37*
G36*
G01X1076469D02*
G02Y293681I-1167J777D01*
G03X1077135I333J222D01*
G02Y292127I1167J-777D01*
G03X1076469I-333J-222D01*
G37*
G36*
G01X1083669D02*
G02Y293681I-1167J777D01*
G03X1084335I333J222D01*
G02Y292127I1167J-777D01*
G03X1083669I-333J-222D01*
G37*
G36*
G01X1090869D02*
G02Y293681I-1167J777D01*
G03X1091535I333J222D01*
G02Y292127I1167J-777D01*
G03X1090869I-333J-222D01*
G37*
G36*
G01X1321162Y296032D02*
G02X1320246Y295063I438J-1332D01*
G03X1319735Y295546I-387J103D01*
G02X1320651Y296515I-438J1332D01*
G03X1321162Y296032I387J-103D01*
G37*
G36*
G01X173985Y294577D02*
G02X171828Y296645I-1185J923D01*
G03Y297255I-259J305D01*
G02X171742Y299466I972J1145D01*
G03Y300034I-282J284D01*
G02X171828Y302245I1058J1066D01*
G03Y302855I-259J305D01*
G02X173985Y304923I972J1145D01*
G03X174615I315J246D01*
G02X176985I1185J-923D01*
G03X177615I315J246D01*
G02X179985I1185J-923D01*
G03X180615I315J246D01*
G02X182985I1185J-923D01*
G03X183615I315J246D01*
G02X185985I1185J-923D01*
G03X186615I315J246D01*
G02X186869Y305179I1186J-922D01*
G03X186890Y305788I-248J313D01*
G02X189000Y307922I1009J1113D01*
G03X189582Y307918I293J273D01*
G02X189689Y308018I1078J-1046D01*
G03X189677Y308331I-130J152D01*
G02X191679Y308526I893J1208D01*
G03X191699Y307966I295J-270D01*
G02X189565Y305855I-1034J-1089D01*
G03X188983Y305859I-293J-273D01*
G02X188831Y305721I-1083J1041D01*
G03X188810Y305112I248J-313D01*
G02X188772Y302855I-1010J-1112D01*
G03Y302245I259J-305D01*
G02X188858Y300034I-972J-1145D01*
G03Y299466I282J-284D01*
G02X188868Y297343I-1058J-1067D01*
G03X188900Y296751I284J-282D01*
G02X189108Y296547I-943J-1169D01*
G03X189706Y296529I307J256D01*
G02X191985Y296423I1094J-1029D01*
G03X192615I315J246D01*
G02X195024Y296370I1185J-923D01*
G03X195688Y296388I326J232D01*
G02X195732Y294713I1268J-805D01*
G03X195068Y294695I-326J-232D01*
G02X192615Y294577I-1268J805D01*
G03X191985I-315J-246D01*
G02X189648Y294536I-1185J923D01*
G03X189050Y294554I-307J-256D01*
G02X186732Y294713I-1094J1029D01*
G03X186068Y294695I-326J-232D01*
G02X183615Y294577I-1268J805D01*
G03X182985I-315J-246D01*
G02X180648Y294536I-1185J923D01*
G03X180050Y294554I-307J-256D01*
G02X177732Y294713I-1094J1029D01*
G03X177068Y294695I-326J-232D01*
G02X174615Y294577I-1268J805D01*
G03X173985I-315J-246D01*
G37*
G36*
G01X823867Y294604D02*
G02X821759Y296712I-1185J923D01*
G03Y297342I-246J315D01*
G02X821624Y299593I923J1185D01*
G03Y300161I-282J284D01*
G02Y302293I1058J1066D01*
G03Y302861I-282J284D01*
G02X823867Y304850I1058J1066D01*
G03X824497I315J246D01*
G02X826867I1185J-923D01*
G03X827497I315J246D01*
G02X829867I1185J-923D01*
G03X830497I315J246D01*
G02X832867I1185J-923D01*
G03X833497I315J246D01*
G02X835906Y304797I1185J-923D01*
G03X836558I326J232D01*
G02X838754Y302782I1224J-870D01*
G03Y302172I259J-305D01*
G02Y299882I-972J-1145D01*
G03Y299272I259J-305D01*
G02X836448Y297436I-972J-1145D01*
G03X835797Y297520I-355J-184D01*
G02X833497Y297604I-1115J1007D01*
G03X832867I-315J-246D01*
G02X830497I-1185J923D01*
G03X829867I-315J-246D01*
G02X827497I-1185J923D01*
G03X826867I-315J-246D01*
G02X826605Y297342I-1185J923D01*
G03Y296712I246J-315D01*
G02X824497Y294604I-923J-1185D01*
G03X823867I-315J-246D01*
G37*
G36*
G01X1115777Y297174D02*
G02X1114706Y295993I319J-1365D01*
G03X1114219Y296435I-397J52D01*
G02X1115290Y297616I-319J1365D01*
G03X1115777Y297174I397J-52D01*
G37*
G36*
G01X672778Y298889D02*
G02X672637Y297518I1144J-810D01*
G03X671944Y297589I-367J-160D01*
G02X669711Y297517I-1144J811D01*
G03X669089I-311J-252D01*
G02Y299283I-1089J883D01*
G03X669711I311J252D01*
G02X672085Y298960I1089J-883D01*
G03X672778Y298889I367J160D01*
G37*
G36*
G01X776085Y299379D02*
G02X773826Y297921I-914J-1063D01*
G03X773223Y298143I-384J-112D01*
G02X771430Y298253I-823J1257D01*
G03X770807Y298114I-259J-305D01*
G02X768259Y299663I-1368J620D01*
G03X768017Y300303I-315J247D01*
G02X769312Y302881I273J1477D01*
G03X769861Y302885I272J293D01*
G02X772343Y301384I1039J-1085D01*
G03X772659Y300880I384J-110D01*
G02X773112Y300722I-262J-1479D01*
G03X773701Y301101I190J352D01*
G02X776105Y300001I1499J99D01*
G03X776085Y299379I241J-319D01*
G37*
G36*
G01X123318Y299752D02*
G02X121539Y300049I-1087J-1036D01*
G03X121644Y300680I-185J355D01*
G02X123889Y302673I1087J1037D01*
G03X124505I308J255D01*
G02Y300759I1158J-957D01*
G03X123889I-308J-255D01*
G02X123423Y300383I-1157J958D01*
G03X123318Y299752I185J-355D01*
G37*
G36*
G01X4973Y301570D02*
G02Y303124I-1167J777D01*
G03X5639I333J222D01*
G02Y301570I1167J-777D01*
G03X4973I-333J-222D01*
G37*
G36*
G01X1506795Y307781D02*
G02X1505065Y307774I-861J-1107D01*
G03X1505063Y308403I-248J314D01*
G02X1506793Y308410I861J1107D01*
G03X1506795Y307781I248J-314D01*
G37*
G36*
G01X777591Y306631D02*
G02X777150Y308191I-1321J469D01*
G03X777779Y308369I252J311D01*
G02X778220Y306809I1321J-469D01*
G03X777591Y306631I-252J-311D01*
G37*
G36*
G01X128755Y306876D02*
G02X128442Y308539I-1255J625D01*
G03X129069Y308657I269J296D01*
G02X129382Y306994I1255J-625D01*
G03X128755Y306876I-269J-296D01*
G37*
G36*
G01X1104766Y308814D02*
G02X1102437Y307365I-1010J-972D01*
G03X1101882Y307587I-376J-136D01*
G02X1099937Y308365I-626J1254D01*
G03X1099382Y308587I-376J-136D01*
G02X1097553Y309122I-626J1254D01*
G03X1096875Y309136I-343J-205D01*
G02X1094573Y309072I-1173J768D01*
G03X1093919Y309058I-322J-237D01*
G02X1091553Y309122I-1163J783D01*
G03X1090875Y309136I-343J-205D01*
G02X1090905Y310623I-1173J767D01*
G03X1091583Y310609I343J205D01*
G02X1093885Y310673I1173J-768D01*
G03X1094539Y310687I322J237D01*
G02X1096905Y310623I1163J-783D01*
G03X1097583Y310609I343J205D01*
G02X1100075Y310317I1173J-768D01*
G03X1100630Y310095I376J136D01*
G02X1101805Y310131I626J-1254D01*
G03X1102359Y310464I156J368D01*
G02X1104766Y309368I1397J-123D01*
G03Y308814I288J-277D01*
G37*
G36*
G01X116300Y310684D02*
G02X114751Y310669I-763J-1176D01*
G03X114744Y311336I-224J331D01*
G02X116293Y311351I763J1176D01*
G03X116300Y310684I224J-331D01*
G37*
G36*
G01X765908D02*
G02X764359Y310669I-763J-1176D01*
G03X764352Y311336I-224J331D01*
G02X765901Y311351I763J1176D01*
G03X765908Y310684I224J-331D01*
G37*
G36*
G01X1022322Y308938D02*
G02X1022236Y310700I-1257J822D01*
G03X1022883Y310731I312J250D01*
G02X1022969Y308969I1257J-822D01*
G03X1022322Y308938I-312J-250D01*
G37*
G36*
G01X369939Y310602D02*
G02X369911Y309141I1298J-756D01*
G03X369212Y309154I-353J-188D01*
G02X369240Y310615I-1298J756D01*
G03X369939Y310602I353J188D01*
G37*
G36*
G01X391435Y310723D02*
G02X391432Y309089I1259J-819D01*
G03X390761Y309091I-336J-217D01*
G02X390764Y310725I-1259J819D01*
G03X391435Y310723I336J217D01*
G37*
G36*
G01X398638Y310728D02*
G02X398635Y309085I1256J-824D01*
G03X397965Y309086I-335J-218D01*
G02X397968Y310729I-1256J824D01*
G03X398638Y310728I335J218D01*
G37*
G36*
G01X1033923Y310774D02*
G02X1033919Y309039I1224J-870D01*
G03X1033266Y309040I-327J-231D01*
G02X1033270Y310775I-1224J870D01*
G03X1033923Y310774I327J231D01*
G37*
G36*
G01X1055504Y310747D02*
G02X1055500Y309066I1243J-843D01*
G03X1054837Y309067I-332J-223D01*
G02X1054841Y310748I-1243J843D01*
G03X1055504Y310747I332J223D01*
G37*
G36*
G01X441282Y309097D02*
G02Y310585I-1188J744D01*
G03X441960I339J213D01*
G02Y309097I1188J-744D01*
G03X441282I-339J-213D01*
G37*
G36*
G01X412461Y309127D02*
G02Y310681I-1167J777D01*
G03X413127I333J222D01*
G02Y309127I1167J-777D01*
G03X412461I-333J-222D01*
G37*
G36*
G01X419661D02*
G02Y310681I-1167J777D01*
G03X420327I333J222D01*
G02Y309127I1167J-777D01*
G03X419661I-333J-222D01*
G37*
G36*
G01X426861D02*
G02Y310681I-1167J777D01*
G03X427527I333J222D01*
G02Y309127I1167J-777D01*
G03X426861I-333J-222D01*
G37*
G36*
G01X434061D02*
G02Y310681I-1167J777D01*
G03X434727I333J222D01*
G02Y309127I1167J-777D01*
G03X434061I-333J-222D01*
G37*
G36*
G01X1062069D02*
G02Y310681I-1167J777D01*
G03X1062735I333J222D01*
G02Y309127I1167J-777D01*
G03X1062069I-333J-222D01*
G37*
G36*
G01X1069269D02*
G02Y310681I-1167J777D01*
G03X1069935I333J222D01*
G02Y309127I1167J-777D01*
G03X1069269I-333J-222D01*
G37*
G36*
G01X1076469D02*
G02Y310681I-1167J777D01*
G03X1077135I333J222D01*
G02Y309127I1167J-777D01*
G03X1076469I-333J-222D01*
G37*
G36*
G01X1083669D02*
G02Y310681I-1167J777D01*
G03X1084335I333J222D01*
G02Y309127I1167J-777D01*
G03X1083669I-333J-222D01*
G37*
G36*
G01X1494528Y312009D02*
G02X1494517Y310711I1123J-659D01*
G03X1493823Y310717I-349J-196D01*
G02X1493834Y312015I-1123J659D01*
G03X1494528Y312009I349J196D01*
G37*
G36*
G01X1493845Y313933D02*
G02Y315159I-1149J613D01*
G03X1494550I352J188D01*
G02Y313933I1149J-613D01*
G03X1493845I-352J-188D01*
G37*
G36*
G01X766382Y316635D02*
G02X765182Y317754I-1375J-272D01*
G03X765625Y318228I50J397D01*
G02X765973Y319454I1375J272D01*
G03X765913Y320051I-293J272D01*
G02X767759Y320235I819J1138D01*
G03X767819Y319638I293J-272D01*
G02X766825Y317109I-819J-1138D01*
G03X766382Y316635I-50J-397D01*
G37*
G36*
G01X688114Y326341D02*
G02X686563Y326393I-815J-1141D01*
G03X686586Y327059I-210J341D01*
G02X688137Y327007I815J1141D01*
G03X688114Y326341I210J-341D01*
G37*
G36*
G01X637472Y328363D02*
G02X636003Y327816I-329J-1363D01*
G03X635771Y328437I-326J232D01*
G02X636069Y331202I328J1363D01*
G03X636420Y331777I-8J400D01*
G02X637712Y330988I1261J613D01*
G03X637361Y330413I8J-400D01*
G02X637240Y328984I-1261J-613D01*
G03X637472Y328363I326J-232D01*
G37*
G36*
G01X1514594Y328782D02*
G02X1513308Y328680I-545J-1292D01*
G03X1513252Y329388I-211J340D01*
G02X1514538Y329490I545J1292D01*
G03X1514594Y328782I211J-340D01*
G37*
G36*
G01X195977Y326720D02*
G02X193577Y326760I-1185J923D01*
G03X192946Y326781I-324J-235D01*
G02X190491Y326992I-1154J962D01*
G03X189831Y327040I-346J-200D01*
G02X187731Y329158I-1177J933D01*
G03Y329788I-246J315D01*
G02X187696Y332130I923J1185D01*
G03X187691Y332750I-255J308D01*
G02X187445Y333000I940J1171D01*
G03X186815I-315J-246D01*
G02X184579Y334996I-1185J923D01*
G03X184510Y335623I-279J287D01*
G02X184085Y336017I789J1278D01*
G03X183454Y336038I-324J-235D01*
G02X181115Y336077I-1154J962D01*
G03X180485I-315J-246D01*
G02X178115I-1185J923D01*
G03X177485I-315J-246D01*
G02X175115I-1185J923D01*
G03X174485I-315J-246D01*
G02X172328Y338145I-1185J923D01*
G03Y338755I-259J305D01*
G02X174485Y340823I972J1145D01*
G03X175115I315J246D01*
G02X177485I1185J-923D01*
G03X178115I315J246D01*
G02X180485I1185J-923D01*
G03X181115I315J246D01*
G02X183485I1185J-923D01*
G03X184115I315J246D01*
G02X186485I1185J-923D01*
G03X187115I315J246D01*
G02X189515Y340783I1185J-923D01*
G03X190146Y340762I324J235D01*
G02X190085Y338917I1154J-962D01*
G03X189454Y338938I-324J-235D01*
G02X189223Y338715I-1153J963D01*
G03Y338085I246J-315D01*
G02X189351Y335827I-923J-1185D01*
G03X189420Y335200I279J-287D01*
G02X189588Y332766I-790J-1277D01*
G03X189593Y332146I255J-308D01*
G02X189577Y329788I-939J-1173D01*
G03Y329158I246J-315D01*
G02X189955Y328724I-923J-1185D01*
G03X190615Y328676I346J200D01*
G02X193007Y328626I1177J-933D01*
G03X193638Y328605I324J235D01*
G02X195977Y328566I1154J-962D01*
G03X196607I315J246D01*
G02Y326720I1185J-923D01*
G03X195977I-315J-246D01*
G37*
G36*
G01X126275Y331524D02*
G02X124804Y331495I-712J-1208D01*
G03X124779Y332182I-217J336D01*
G02X124256Y332659I722J1317D01*
G03X123673Y332746I-331J-224D01*
G02X123312Y332531I-942J1170D01*
G03X123207Y331858I155J-369D01*
G02X121650Y332101I-976J-1142D01*
G03X121755Y332774I-155J369D01*
G02X123975Y334757I976J1142D01*
G03X124558Y334670I331J224D01*
G02X126272Y332212I942J-1169D01*
G03X126275Y331524I206J-343D01*
G37*
G36*
G01X202100Y331913D02*
G02X200254I-923J-1185D01*
G03Y332543I-246J315D01*
G02Y334913I923J1185D01*
G03Y335543I-246J315D01*
G02X200133Y337808I923J1185D01*
G03X200130Y338386I-278J288D01*
G02X199892Y338675I1031J1092D01*
G03X199252Y338724I-338J-213D01*
G02X197112Y340824I-1134J985D01*
G03X197133Y341396I-269J296D01*
G02X197289Y343607I1090J1034D01*
G03X197292Y344232I-248J314D01*
G02X197048Y344479I939J1172D01*
G03X196418I-315J-246D01*
G02X194376Y346635I-1185J923D01*
G03X194388Y347283I-229J328D01*
G02Y349521I845J1119D01*
G03X194376Y350169I-241J320D01*
G02X196418Y352325I857J1233D01*
G03X197048I315J246D01*
G02X199156Y350217I1185J-923D01*
G03Y349587I246J-315D01*
G02X199326Y349432I-924J-1184D01*
G03X199918Y349442I291J274D01*
G02X201968Y347264I1127J-993D01*
G03Y346634I246J-315D01*
G02X202212Y346395I-922J-1186D01*
G03X202846Y346411I311J252D01*
G02X204983Y344342I1214J-884D01*
G03Y343712I246J-315D01*
G02X204996Y341353I-923J-1185D01*
G03X205018Y340711I249J-313D01*
G02X205207Y338396I-855J-1235D01*
G03X205210Y337818I278J-288D01*
G02X202992Y335805I-1033J-1090D01*
G03X202362I-315J-246D01*
G02X202100Y335543I-1185J923D01*
G03Y334913I246J-315D01*
G02Y332543I-923J-1185D01*
G03Y331913I246J-315D01*
G37*
G36*
G01X1106728Y335132D02*
G02X1104994Y335070I-828J-1132D01*
G03X1104972Y335698I-258J305D01*
G02X1106706Y335760I828J1132D01*
G03X1106728Y335132I258J-305D01*
G37*
G36*
G01X451673Y334540D02*
G02X449473Y334871I-973J1010D01*
G03X448830Y334949I-350J-194D01*
G02X449027Y336579I-1030J951D01*
G03X449670Y336501I350J194D01*
G02X451673Y336560I1030J-951D01*
G03X452227I277J288D01*
G02Y334540I973J-1010D01*
G03X451673I-277J-288D01*
G37*
G36*
G01X1409740Y336269D02*
G02X1408622Y337811I-1392J167D01*
G03X1409097Y338155I78J392D01*
G02X1409130Y338332I1392J-168D01*
G03X1408866Y338568I-194J49D01*
G02X1409775Y339789I-490J1314D01*
G03X1410244Y339368I399J-27D01*
G02X1410215Y336613I245J-1380D01*
G03X1409740Y336269I-78J-392D01*
G37*
G36*
G01X1101253Y337632D02*
G02X1101084Y336002I1047J-932D01*
G03X1100438Y336069I-347J-199D01*
G02X1100607Y337699I-1047J932D01*
G03X1101253Y337632I347J199D01*
G37*
G36*
G01X1483734Y337311D02*
G02X1482776Y338273I-1348J-385D01*
G03X1483272Y338767I112J384D01*
G02X1483219Y339088I1348J387D01*
G03X1482768Y339466I-399J-18D01*
G02X1483986Y340920I-183J1390D01*
G03X1484437Y340542I399J18D01*
G02X1484230Y337805I183J-1390D01*
G03X1483734Y337311I-112J-384D01*
G37*
G36*
G01X1488712Y338646D02*
G02X1487060Y338620I-808J-1146D01*
G03X1487050Y339266I-240J319D01*
G02X1488702Y339292I808J1146D01*
G03X1488712Y338646I240J-319D01*
G37*
G36*
G01X99363Y339304D02*
G02X97886Y339236I-684J-1224D01*
G03X97855Y339915I-226J330D01*
G02X99332Y339983I684J1224D01*
G03X99363Y339304I226J-330D01*
G37*
G36*
G01X399315Y337564D02*
G02Y339118I-1167J777D01*
G03X399981I333J222D01*
G02X402121Y339351I1167J-777D01*
G03X402675I277J288D01*
G02Y337331I973J-1010D01*
G03X402121I-277J-288D01*
G02X399981Y337564I-973J1010D01*
G03X399315I-333J-222D01*
G37*
G36*
G01X1048923D02*
G02Y339118I-1167J777D01*
G03X1049589I333J222D01*
G02X1051885Y339173I1167J-777D01*
G03X1052539Y339187I322J237D01*
G02X1054790Y339289I1163J-783D01*
G03X1055456Y339359I310J252D01*
G02X1055594Y337767I1336J-686D01*
G03X1054926Y337720I-319J-242D01*
G02X1052573Y337572I-1224J684D01*
G03X1051919Y337558I-322J-237D01*
G02X1049589Y337564I-1163J783D01*
G03X1048923I-333J-222D01*
G37*
G36*
G01X1078467Y337610D02*
G02Y339456I-1185J923D01*
G03X1079097I315J246D01*
G02X1081382Y339556I1185J-923D01*
G03X1082017Y339620I293J272D01*
G02X1084446Y339813I1284J-779D01*
G03X1085040Y339796I305J259D01*
G02X1084981Y337786I1086J-1038D01*
G03X1084387Y337803I-305J-259D01*
G02X1082201Y337818I-1086J1038D01*
G03X1081566Y337754I-293J-272D01*
G02X1079097Y337610I-1284J779D01*
G03X1078467I-315J-246D01*
G37*
G36*
G01X418263Y339420D02*
G02X418240Y337812I1137J-820D01*
G03X417585Y337821I-331J-225D01*
G02X415475Y337631I-1137J820D01*
G03X414921I-277J-288D01*
G02X412781Y337864I-973J1010D01*
G03X412115I-333J-222D01*
G02Y339418I-1167J777D01*
G03X412781I333J222D01*
G02X414921Y339651I1167J-777D01*
G03X415475I277J288D01*
G02X417608Y339429I973J-1010D01*
G03X418263Y339420I331J225D01*
G37*
G36*
G01X128370Y338700D02*
G02X127731Y340196I-1370J299D01*
G03X128330Y340452I208J341D01*
G02X128969Y338956I1370J-299D01*
G03X128370Y338700I-208J-341D01*
G37*
G36*
G01X1564167Y340223D02*
G02Y341777I-1167J777D01*
G03X1564833I333J222D01*
G02Y340223I1167J-777D01*
G03X1564167I-333J-222D01*
G37*
G36*
G01X116300Y342684D02*
G02X114751Y342669I-763J-1176D01*
G03X114744Y343336I-224J331D01*
G02X116293Y343351I763J1176D01*
G03X116300Y342684I224J-331D01*
G37*
G36*
G01X765908D02*
G02X764359Y342669I-763J-1176D01*
G03X764352Y343336I-224J331D01*
G02X765901Y343351I763J1176D01*
G03X765908Y342684I224J-331D01*
G37*
G36*
G01X50027Y344982D02*
G02X48007I-1010J-973D01*
G03Y345536I-288J277D01*
G02X48048Y347522I1010J973D01*
G03X48070Y348077I-277J289D01*
G02X48097Y349971I1047J932D01*
G03X48091Y350526I-291J274D01*
G02X48312Y352675I1000J983D01*
G03X48314Y353339I-222J333D01*
G02X49879Y353334I786J1161D01*
G03X49877Y352670I222J-333D01*
G02X50336Y352153I-786J-1161D01*
G03X50960Y352040I355J184D01*
G02X50557Y350596I940J-1041D01*
G03X50207Y350660I-191J-57D01*
G02X50111Y350547I-1115J850D01*
G03X50117Y349992I291J-274D01*
G02X50086Y347996I-1000J-983D01*
G03X50064Y347441I277J-289D01*
G02X50244Y347187I-1047J-933D01*
G03X50889Y347111I350J194D01*
G02X50696Y345486I1034J-947D01*
G03X50051Y345562I-350J-194D01*
G02X50027Y345536I-1042J938D01*
G03Y344982I288J-277D01*
G37*
G36*
G01X102884Y347278D02*
G02X101000Y347391I-1004J-978D01*
G03X101036Y347982I-251J312D01*
G02X101165Y350055I1004J978D01*
G03X101169Y350676I-250J312D01*
G02X101336Y352959I891J1082D01*
G03X101358Y353630I-207J343D01*
G02X102884Y353580I802J1150D01*
G03X102862Y352909I207J-343D01*
G02X102935Y350664I-802J-1150D01*
G03X102931Y350043I250J-312D01*
G02X102920Y347869I-891J-1083D01*
G03X102884Y347278I251J-312D01*
G37*
G36*
G01X1331530Y347307D02*
G02X1331474Y345600I1083J-890D01*
G03X1330840Y345621I-325J-233D01*
G02X1330896Y347328I-1083J890D01*
G03X1331530Y347307I325J233D01*
G37*
G36*
G01X65595Y349131D02*
G02X65121Y347275I755J-1181D01*
G03X64555Y347419I-350J-193D01*
G02X62757Y347664I-755J1181D01*
G03X62113Y347597I-298J-267D01*
G02X61943Y349236I-1213J702D01*
G03X62587Y349303I298J267D01*
G02X65029Y349275I1213J-703D01*
G03X65595Y349131I350J193D01*
G37*
G36*
G01X1644113Y349711D02*
G02X1642615Y349988I-963J-1019D01*
G03X1642737Y350648I-153J370D01*
G02X1644235Y350371I963J1019D01*
G03X1644113Y349711I153J-370D01*
G37*
G36*
G01X1338882Y350962D02*
G02X1338203Y349606I715J-1206D01*
G03X1337601Y349907I-398J-43D01*
G02X1338280Y351263I-715J1206D01*
G03X1338882Y350962I398J43D01*
G37*
G36*
G01X1588979Y351651D02*
G02X1588978Y350340I1239J-656D01*
G03X1588271I-354J-187D01*
G02X1588272Y351651I-1239J656D01*
G03X1588979I354J187D01*
G37*
G36*
G01X1508004Y354215D02*
G02X1506340Y354241I-850J-1115D01*
G03X1506350Y354885I-232J326D01*
G02X1506271Y357050I850J1115D01*
G03Y357650I-265J300D01*
G02X1508129I929J1050D01*
G03Y357050I265J-300D01*
G02X1508014Y354859I-929J-1050D01*
G03X1508004Y354215I232J-326D01*
G37*
G36*
G01X1539469Y360376D02*
G02X1537451Y360293I-969J-1013D01*
G03X1537428Y360848I-299J266D01*
G02X1537462Y362906I969J1013D01*
G03X1537418Y363536I-267J298D01*
G02X1539135Y363655I782J1164D01*
G03X1539179Y363025I267J-298D01*
G02X1539446Y360931I-782J-1164D01*
G03X1539469Y360376I299J-266D01*
G37*
G36*
G01X1343883Y360683D02*
G02X1343419Y359074I848J-1116D01*
G03X1342802Y359252I-375J-141D01*
G02X1343266Y360861I-848J1116D01*
G03X1343883Y360683I375J141D01*
G37*
G36*
G01X102517Y361294D02*
G02X100999Y361304I-767J-1174D01*
G03X101003Y361976I-215J337D01*
G02X102521Y361966I767J1174D01*
G03X102517Y361294I215J-337D01*
G37*
G36*
G01X1357712Y360037D02*
G02X1357659Y361417I-1246J643D01*
G03X1358354Y361443I340J210D01*
G02X1358407Y360063I1246J-643D01*
G03X1357712Y360037I-340J-210D01*
G37*
G36*
G01X1608786Y360618D02*
G02X1608339Y361947I-1374J277D01*
G03X1608996Y362167I265J300D01*
G02X1609443Y360838I1374J-277D01*
G03X1608786Y360618I-265J-300D01*
G37*
G36*
G01X60254Y363533D02*
G02X59542Y362141I680J-1226D01*
G03X58951Y362443I-397J-48D01*
G02X59663Y363835I-680J1226D01*
G03X60254Y363533I397J48D01*
G37*
G36*
G01X126608Y363251D02*
G02X124265Y361785I-1045J-935D01*
G03X123566Y361861I-370J-151D01*
G02X121424Y363913I-1235J855D01*
G03X121481Y364499I-241J319D01*
G02X123960Y366138I1119J1002D01*
G03X124590Y366012I362J170D01*
G02X126631Y363808I1010J-1112D01*
G03X126608Y363251I275J-290D01*
G37*
G36*
G01X776095Y363370D02*
G02X774172Y363300I-924J-1054D01*
G03X774136Y363894I-285J281D01*
G02X773991Y364025I932J1178D01*
G03X773406Y364015I-288J-278D01*
G02X771506Y363739I-1116J1005D01*
G03X770906Y363485I-209J-341D01*
G02X768332Y364824I-1466J325D01*
G03X768319Y365377I-295J270D01*
G02X770875Y366588I1061J1063D01*
G03X771487Y366289I398J39D01*
G02X773369Y366065I803J-1269D01*
G03X773954Y366075I288J278D01*
G02X776088Y363965I1116J-1006D01*
G03X776095Y363370I271J-294D01*
G37*
G36*
G01X679038Y364209D02*
G02X677514Y363539I-308J-1368D01*
G03X677255Y364128I-347J199D01*
G02X678779Y364798I308J1368D01*
G03X679038Y364209I347J-199D01*
G37*
G36*
G01X1381129Y371450D02*
G02X1379271I-929J-1050D01*
G03Y372050I-265J300D01*
G02X1378921Y372526I929J1050D01*
G03X1378233Y372599I-365J-164D01*
G02X1377889Y372267I-1131J828D01*
G03X1377862Y371625I224J-331D01*
G02X1375667Y370041I-883J-1089D01*
G03X1375083Y370239I-374J-142D01*
G02X1373459Y372518I-739J1191D01*
G03X1373442Y373152I-252J310D01*
G02X1375602Y374716I826J1133D01*
G03X1376231Y374526I380J123D01*
G02X1378382Y374002I872J-1098D01*
G03X1379070Y373929I365J164D01*
G02X1381129Y372050I1131J-829D01*
G03Y371450I265J-300D01*
G37*
G36*
G01X128750Y371148D02*
G02X128552Y372417I-1330J442D01*
G03X129255Y372527I323J236D01*
G02X129453Y371258I1330J-442D01*
G03X128750Y371148I-323J-236D01*
G37*
G36*
G01X764923Y374919D02*
G02X763374Y374904I-763J-1176D01*
G03X763367Y375571I-224J331D01*
G02X764916Y375586I763J1176D01*
G03X764923Y374919I224J-331D01*
G37*
G36*
G01X1333536Y375536D02*
G02X1331725Y375503I-886J-1086D01*
G03X1331714Y376114I-264J301D01*
G02X1331623Y376195I886J1087D01*
G03X1331090Y376217I-279J-287D01*
G02X1329151Y376370I-890J1083D01*
G03X1328574Y376392I-299J-266D01*
G02X1326551Y376470I-974J1008D01*
G03X1325974Y376492I-299J-266D01*
G02X1323787Y376797I-974J1008D01*
G03X1323143Y376864I-346J-200D01*
G02X1320807Y377258I-1043J936D01*
G03X1320186Y377413I-369J-155D01*
G02X1320673Y378784I-886J1087D01*
G03X1321022Y378697I196J41D01*
G02X1321181Y378859I1077J-898D01*
G03X1321171Y379471I-262J302D01*
G02X1323113Y381479I883J1089D01*
G03X1323738Y381506I302J263D01*
G02X1324095Y381849I1135J-824D01*
G03Y382515I-222J333D01*
G02X1326062Y384424I777J1167D01*
G03X1326711Y384384I339J212D01*
G02X1328875Y384400I1089J-884D01*
G03X1329531Y384464I306J257D01*
G02X1329981Y384952I1226J-679D01*
G03Y385618I-222J333D01*
G02Y387952I777J1167D01*
G03Y388618I-222J333D01*
G02X1331535I777J1167D01*
G03Y387952I222J-333D01*
G02Y385618I-777J-1167D01*
G03Y384952I222J-333D01*
G02X1329683Y382885I-777J-1167D01*
G03X1329027Y382821I-306J-257D01*
G02X1328475Y382271I-1227J679D01*
G03X1328453Y381583I192J-351D01*
G02X1328666Y381416I-755J-1182D01*
G03X1329219Y381417I276J290D01*
G02X1331148Y381430I971J-1011D01*
G03X1331715Y381451I273J292D01*
G02X1331790Y379479I1033J-948D01*
G03X1331223Y379458I-273J-292D01*
G02X1330905Y379200I-1033J948D01*
G03X1330907Y378511I204J-344D01*
G02X1331177Y378305I-709J-1209D01*
G03X1331710Y378283I279J287D01*
G02X1333525Y376147I890J-1083D01*
G03X1333536Y375536I264J-301D01*
G37*
G36*
G01X1446261Y374114D02*
G02X1446234Y375724I-1161J786D01*
G03X1446889Y375736I323J236D01*
G02X1446916Y374126I1161J-786D01*
G03X1446261Y374114I-323J-236D01*
G37*
G36*
G01X1631819Y376659D02*
G02X1629911Y376593I-919J-1059D01*
G03X1629862Y377201I-283J283D01*
G02X1629557Y379511I938J1299D01*
G03X1629414Y380126I-310J252D01*
G02X1631156Y380607I586J1274D01*
G03X1631349Y380005I330J-226D01*
G02X1631825Y377269I-549J-1505D01*
G03X1631819Y376659I256J-308D01*
G37*
G36*
G01X1606696Y375469D02*
X1606641Y375582D01*
X1600818D01*
Y376044D01*
X1600468D01*
X1600426Y375899D01*
G02X1597266Y376346I-1548J447D01*
G01Y380344D01*
G02X1600426Y380791I1612J0D01*
G01X1600468Y380646D01*
X1600818D01*
Y381084D01*
X1606322D01*
Y380924D01*
X1606646D01*
X1606701Y381035D01*
G02X1609758Y380332I1445J-713D01*
G01Y376086D01*
X1609748Y376001D01*
G02X1606696Y375469I-1602J170D01*
G37*
G36*
G01X752570Y380608D02*
G02X752514Y379226I1304J-745D01*
G03X751804Y379255I-363J-169D01*
G02X751860Y380637I-1304J745D01*
G03X752570Y380608I363J169D01*
G37*
G36*
G01X766290Y380798D02*
G02X764936Y381765I-1333J-435D01*
G03X765310Y382289I-6J400D01*
G02X766009Y383974I1333J435D01*
G03X766122Y384602I-181J357D01*
G02X767789Y384300I1033J948D01*
G03X767676Y383672I181J-357D01*
G02X766664Y381322I-1033J-948D01*
G03X766290Y380798I6J-400D01*
G37*
G36*
G01X117981Y382436D02*
G02X117232Y381078I648J-1243D01*
G03X116648Y381400I-399J-33D01*
G02X115528Y383963I-649J1243D01*
G03X115764Y384490I-135J377D01*
G02X117535Y383696I1299J526D01*
G03X117299Y383169I135J-377D01*
G02X117397Y382758I-1299J-527D01*
G03X117981Y382436I399J33D01*
G37*
G36*
G01X701444Y383162D02*
G02X699108Y385037I-1240J848D01*
G03Y385583I-292J273D01*
G02X699427Y387896I1096J1027D01*
G03X699467Y388553I-207J342D01*
G02X699381Y390849I924J1184D01*
G03X699360Y391458I-269J296D01*
G02X699373Y393826I931J1179D01*
G03X699408Y394429I-244J317D01*
G02X701347Y396714I1050J1075D01*
G03X701917Y396815I237J322D01*
G02X704303Y396971I1252J-829D01*
G03X704933Y397004I302J262D01*
G02X707263Y397167I1231J-861D01*
G03X707854Y397174I292J273D01*
G02X710012Y397261I1121J-1000D01*
G03X710558Y397256I276J289D01*
G02X712498Y394965I1017J-1106D01*
G03Y394335I246J-315D01*
G02Y391965I-923J-1185D01*
G03Y391335I246J-315D01*
G02X712244Y388805I-923J-1185D01*
G03X712159Y388145I178J-358D01*
G02X712231Y385946I-986J-1133D01*
G03Y385378I282J-284D01*
G02X710031Y383336I-1059J-1066D01*
G03X709442Y383357I-304J-260D01*
G02X707307Y383354I-1069J1055D01*
G03X706739I-284J-282D01*
G02X704607I-1066J1058D01*
G03X704039I-284J-282D01*
G02X702026Y383246I-1066J1058D01*
G03X701444Y383162I-252J-310D01*
G37*
G36*
G01X1457707Y385768D02*
G02X1456192Y385728I-726J-1199D01*
G03X1456174Y386401I-225J331D01*
G02X1457689Y386441I726J1199D01*
G03X1457707Y385768I225J-331D01*
G37*
G36*
G01X680301Y386975D02*
G02X678638Y386895I-777J-1167D01*
G03X678607Y387538I-253J310D01*
G02X680270Y387618I777J1167D01*
G03X680301Y386975I253J-310D01*
G37*
G36*
G01X1381928Y391468D02*
G02Y393132I-1128J832D01*
G03X1382572I322J238D01*
G02Y391468I1128J-832D01*
G03X1381928I-322J-238D01*
G37*
G36*
G01X1470953Y393463D02*
G02X1469582Y393653I-853J-1113D01*
G03X1469737Y394285I-148J371D01*
G02X1469538Y395811I1063J915D01*
G03X1469332Y396354I-360J174D01*
G02X1468706Y396871I542J1293D01*
G03X1468040I-333J-222D01*
G02X1465862Y396677I-1167J777D01*
G03X1465284I-289J-277D01*
G02Y398619I-1011J971D01*
G03X1465862I289J277D01*
G02X1468040Y398425I1011J-971D01*
G03X1468706I333J222D01*
G02X1471135Y397037I1167J-777D01*
G03X1471341Y396494I360J-174D01*
G02X1472183Y395433I-541J-1294D01*
G03X1472689Y395116I394J67D01*
G02X1471700Y393537I394J-1346D01*
G03X1471194Y393854I-394J-67D01*
G02X1471040Y393819I-387J1348D01*
G03X1470953Y393463I34J-197D01*
G37*
G36*
G01X189179Y394187D02*
G02X188651Y392603I921J-1187D01*
G03X188021Y392813I-385J-106D01*
G02X188549Y394397I-921J1187D01*
G03X189179Y394187I385J106D01*
G37*
G36*
G01X776165Y395252D02*
G02X774299Y395452I-1044J-936D01*
G03X774350Y396056I-235J324D01*
G02X774323Y396084I1068J1056D01*
G03X773760Y396105I-292J-273D01*
G02X771863Y395991I-1018J1104D01*
G03X771238Y395752I-234J-324D01*
G02X768565Y395174I-1468J318D01*
G03X767953Y395210I-321J-239D01*
G02X768065Y397136I-1093J1030D01*
G03X768677Y397100I321J239D01*
G02X770649Y397288I1093J-1030D01*
G03X771274Y397527I234J324D01*
G02X773839Y398235I1468J-318D01*
G03X774402Y398214I292J273D01*
G02X776243Y395854I1019J-1103D01*
G03X776165Y395252I219J-334D01*
G37*
G36*
G01X123112Y395933D02*
G02X121168Y395777I-881J-1217D01*
G03X121119Y396383I-283J282D01*
G02X123280Y398385I881J1217D01*
G03X123974Y398406I341J209D01*
G02X124020Y396915I1326J-705D01*
G03X123326Y396894I-341J-209D01*
G02X123063Y396539I-1325J707D01*
G03X123112Y395933I283J-282D01*
G37*
G36*
G01X1631023Y396730D02*
G02X1629663Y396770I-723J-1430D01*
G03X1629703Y397484I-159J367D01*
G02X1629491Y399767I697J1216D01*
G03X1629524Y400344I-260J304D01*
G02X1631459Y400233I1026J956D01*
G03X1631426Y399656I260J-304D01*
G02X1631025Y397445I-1026J-956D01*
G03X1631023Y396730I178J-358D01*
G37*
G36*
G01X1244795Y398467D02*
G02X1244034Y399589I-1396J-128D01*
G03X1244614Y399982I182J356D01*
G02X1245375Y398860I1396J128D01*
G03X1244795Y398467I-182J-356D01*
G37*
G36*
G01X1332810Y400430D02*
G02X1330695Y398590I-1039J-941D01*
G03X1330094Y398605I-307J-256D01*
G02X1327897Y398779I-1030J951D01*
G03X1327231I-333J-222D01*
G02X1324897I-1167J777D01*
G03X1324231I-333J-222D01*
G02X1322028Y398611I-1167J777D01*
G03X1321442Y398616I-295J-270D01*
G02X1319229Y398844I-1019J963D01*
G03X1318644Y398952I-341J-209D01*
G02X1316778Y401035I-857J1110D01*
G03Y401589I-288J277D01*
G02X1319048Y403176I1010J973D01*
G03X1319361Y403113I180J87D01*
G02X1319442Y403180I933J-1046D01*
G03X1319456Y403487I-121J159D01*
G02X1321567Y405301I944J1037D01*
G03X1322233I333J222D01*
G02X1324567I1167J-777D01*
G03X1325233I333J222D01*
G02X1327567I1167J-777D01*
G03X1328233I333J222D01*
G02X1330380Y405527I1167J-777D01*
G03X1330951Y405539I280J286D01*
G02X1332902Y403530I1022J-959D01*
G03X1332876Y402956I265J-300D01*
G02X1332829Y400986I-1020J-961D01*
G03X1332810Y400430I278J-288D01*
G37*
G36*
G01X1466215Y401593D02*
G02Y403147I-1167J777D01*
G03X1466881I333J222D01*
G02Y401593I1167J-777D01*
G03X1466215I-333J-222D01*
G37*
G36*
G01X175831Y403321D02*
G02X175784Y404774I-1222J688D01*
G03X176467Y404797I335J219D01*
G02X178913Y404794I1222J-688D01*
G03X179603Y404780I349J195D01*
G02X179575Y403364I1196J-732D01*
G03X178885Y403378I-349J-195D01*
G02X176514Y403344I-1196J731D01*
G03X175831Y403321I-335J-219D01*
G37*
G36*
G01X1198437Y406752D02*
G02X1196898Y406240I-408J-1341D01*
G03X1196692Y406859I-323J236D01*
G02X1198231Y407371I408J1341D01*
G03X1198437Y406752I323J-236D01*
G37*
G36*
G01X105766Y407114D02*
G02X104251Y407757I-1248J-835D01*
G03X104512Y408373I-71J394D01*
G02X106070Y410678I1249J835D01*
G03X106543Y411155I83J391D01*
G02X107701Y410009I1467J324D01*
G03X107228Y409532I-83J-391D01*
G02X106027Y407730I-1467J-324D01*
G03X105766Y407114I71J-394D01*
G37*
G36*
G01X1467549Y405996D02*
G02Y407550I-1167J777D01*
G03X1468215I333J222D01*
G02Y405996I1167J-777D01*
G03X1467549I-333J-222D01*
G37*
G36*
G01X1513552Y408921D02*
G02X1511886Y408561I-598J-1268D01*
G03X1511752Y409182I-305J259D01*
G02X1511125Y409769I599J1268D01*
G03X1510425I-350J-194D01*
G02Y411131I-1225J681D01*
G03X1511125I350J194D01*
G02X1513418Y409542I1226J-680D01*
G03X1513552Y408921I305J-259D01*
G37*
G36*
G01X1613554Y410172D02*
G02X1611843Y409975I-729J-1198D01*
G03X1611771Y410602I-280J286D01*
G02X1613482Y410799I729J1198D01*
G03X1613554Y410172I280J-286D01*
G37*
G36*
G01X1440497Y410646D02*
G02X1439003Y410566I-684J-1224D01*
G03X1438967Y411242I-231J327D01*
G02X1440461Y411322I684J1224D01*
G03X1440497Y410646I231J-327D01*
G37*
G36*
G01X798376Y410593D02*
G02X797035Y411222I-1176J-763D01*
G03X797324Y411837I-47J397D01*
G02X798834Y413962I1176J763D01*
G03X799302Y414494I95J388D01*
G02X800276Y413638I1308J506D01*
G03X799808Y413106I-95J-388D01*
G02X798665Y411208I-1308J-506D01*
G03X798376Y410593I47J-397D01*
G37*
G36*
G01X1395067Y411723D02*
G02X1392890Y413473I-1167J778D01*
G03Y414027I-288J277D01*
G02X1393952Y416401I1010J973D01*
G03X1394357Y416888I14J400D01*
G02X1397076Y416819I1368J305D01*
G03X1397337Y416332I386J-107D01*
G02X1397910Y414027I-437J-1332D01*
G03Y413473I288J-277D01*
G02X1395733Y411723I-1010J-972D01*
G03X1395067I-333J-222D01*
G37*
G36*
G01X1535647Y412859D02*
G02X1535604Y414219I-1247J641D01*
G03X1536303Y414241I343J205D01*
G02X1536869Y414825I1246J-642D01*
G03Y415525I-194J350D01*
G02X1536325Y416069I681J1225D01*
G03X1535625I-350J-194D01*
G02Y417431I-1225J681D01*
G03X1536325I350J194D01*
G02X1538775I1225J-681D01*
G03X1539475I350J194D01*
G02X1541925I1225J-681D01*
G03X1542625I350J194D01*
G02X1545075I1225J-681D01*
G03X1545775I350J194D01*
G02Y416069I1225J-681D01*
G03X1545075I-350J-194D01*
G02X1544531Y415525I-1225J681D01*
G03Y414825I194J-350D01*
G02X1542625Y412919I-681J-1225D01*
G03X1541925I-350J-194D01*
G02X1539475I-1225J681D01*
G03X1538775I-350J-194D01*
G02X1536346Y412881I-1225J681D01*
G03X1535647Y412859I-343J-205D01*
G37*
G36*
G01X1516725Y412919D02*
G02Y414281I-1225J681D01*
G03X1517425I350J194D01*
G02X1517969Y414825I1225J-681D01*
G03Y415525I-194J350D01*
G02X1519331I681J1225D01*
G03Y414825I194J-350D01*
G02X1517425Y412919I-681J-1225D01*
G03X1516725I-350J-194D01*
G37*
G36*
G01X1526197Y412959D02*
G02X1524289Y414836I-1247J641D01*
G03X1524300Y415535I-189J353D01*
G02X1525661Y415514I699J1215D01*
G03X1525650Y414815I189J-353D01*
G02X1526154Y414319I-700J-1215D01*
G03X1526853Y414341I343J205D01*
G02X1526896Y412981I1247J-641D01*
G03X1526197Y412959I-343J-205D01*
G37*
G36*
G01X149308Y415575D02*
G02X147577Y415801I-1008J-975D01*
G03X147658Y416422I-206J343D01*
G02X149389Y416196I1008J975D01*
G03X149308Y415575I206J-343D01*
G37*
G36*
G01X621202Y416175D02*
G02X620188Y417547I-1402J25D01*
G03X620698Y417925I110J385D01*
G02X620711Y418092I1402J-25D01*
G03X620412Y418292I-198J28D01*
G02X618977Y420701I-712J1208D01*
G03X618973Y421389I-206J343D01*
G02X621066Y422810I707J1211D01*
G03X621537Y422477I396J60D01*
G02X622612Y422243I263J-1377D01*
G03X622924Y422368I116J163D01*
G02X622969Y422540I1376J-268D01*
G03X622794Y422802I-190J63D01*
G02X623345Y425530I107J1398D01*
G03X623855Y425796I127J379D01*
G02X626596Y425274I1345J-396D01*
G03X626996Y424838I398J-36D01*
G02X627621Y424693I4J-1402D01*
G03X628199Y425062I178J358D01*
G02X628979Y423843I1401J38D01*
G03X628401Y423474I-178J-358D01*
G02X627920Y422378I-1401J-39D01*
G03X627862Y421837I262J-302D01*
G02X626470Y419624I-1125J-837D01*
G03X625996Y419268I-76J-393D01*
G02X624051Y418110I-1396J132D01*
G03X623497Y417777I-156J-368D01*
G02X621712Y416553I-1397J123D01*
G03X621202Y416175I-110J-385D01*
G37*
G36*
G01X52868Y415596D02*
G02X52769Y417119I-1223J685D01*
G03X53439Y417163I321J239D01*
G02X53538Y415640I1223J-685D01*
G03X52868Y415596I-321J-239D01*
G37*
G36*
G01X1510425Y416069D02*
G02X1508519Y417975I-1225J681D01*
G03Y418675I-194J350D01*
G02Y421125I681J1225D01*
G03Y421825I-194J350D01*
G02Y424275I681J1225D01*
G03Y424975I-194J350D01*
G02Y427425I681J1225D01*
G03Y428125I-194J350D01*
G02X1508000Y428625I680J1226D01*
G03X1507303Y428602I-342J-207D01*
G02X1507259Y429974I-1244J647D01*
G03X1507956Y429997I342J207D01*
G02X1510425Y430031I1244J-647D01*
G03X1511125I350J194D01*
G02X1513575I1225J-681D01*
G03X1514275I350J194D01*
G02X1516725I1225J-681D01*
G03X1517425I350J194D01*
G02X1519331Y428125I1225J-681D01*
G03Y427425I194J-350D01*
G02Y424975I-681J-1225D01*
G03Y424275I194J-350D01*
G02X1517425Y422369I-681J-1225D01*
G03X1516725I-350J-194D01*
G02X1516181Y421825I-1225J681D01*
G03Y421125I194J-350D01*
G02X1514275Y419219I-681J-1225D01*
G03X1513575I-350J-194D01*
G02X1513031Y418675I-1225J681D01*
G03Y417975I194J-350D01*
G02X1511125Y416069I-681J-1225D01*
G03X1510425I-350J-194D01*
G37*
G36*
G01X1317793Y417890D02*
G02X1315810Y419873I-973J1010D01*
G03Y420427I-288J277D01*
G02X1317830I1010J973D01*
G03Y419873I288J-277D01*
G02X1317914Y419777I-1012J-970D01*
G03X1318226I156J125D01*
G02X1320417Y419773I1094J-877D01*
G03X1321060Y419796I313J249D01*
G02X1321233Y420003I1157J-791D01*
G03X1321267Y420535I-281J285D01*
G02X1323322Y422429I1104J864D01*
G03X1323881Y422445I271J294D01*
G02X1325879Y422462I1007J-975D01*
G03X1326434Y422453I282J284D01*
G02X1328372Y422426I955J-1027D01*
G03X1328927Y422420I281J285D01*
G02X1330862Y422410I962J-1020D01*
G03X1331416I277J288D01*
G02X1333362I973J-1010D01*
G03X1333916I277J288D01*
G02X1335965Y420501I973J-1010D01*
G03X1335982Y419968I306J-257D01*
G02X1333904Y418087I-1014J-968D01*
G03X1333297Y418088I-304J-260D01*
G02X1331263Y417994I-1062J916D01*
G03X1330709I-277J-288D01*
G02X1328753Y418004I-973J1010D01*
G03X1328198Y418010I-281J-285D01*
G02X1326246Y418038I-962J1020D01*
G03X1325691Y418047I-282J-284D01*
G02X1323784Y418045I-955J1027D01*
G03X1323225Y418029I-271J-294D01*
G02X1321120Y418131I-1008J975D01*
G03X1320477Y418108I-313J-249D01*
G02X1318347Y417890I-1157J792D01*
G03X1317793I-277J-288D01*
G37*
G36*
G01X123483Y419851D02*
G02X121934Y420567I-1241J-652D01*
G03X122200Y421143I-88J390D01*
G02X123749Y420427I1241J652D01*
G03X123483Y419851I88J-390D01*
G37*
G36*
G01X1468429Y419934D02*
G02Y421488I-1167J777D01*
G03X1469095I333J222D01*
G02Y419934I1167J-777D01*
G03X1468429I-333J-222D01*
G37*
G36*
G01X1525631Y424275D02*
G02X1524269I-681J-1225D01*
G03Y424975I-194J350D01*
G02Y427425I681J1225D01*
G03Y428125I-194J350D01*
G02X1525631I681J1225D01*
G03Y427425I194J-350D01*
G02Y424975I-681J-1225D01*
G03Y424275I194J-350D01*
G37*
G36*
G01X1532475Y422369D02*
G02X1530569Y424275I-1225J681D01*
G03Y424975I-194J350D01*
G02Y427425I681J1225D01*
G03Y428125I-194J350D01*
G02X1532475Y430031I681J1225D01*
G03X1533175I350J194D01*
G02X1535625I1225J-681D01*
G03X1536325I350J194D01*
G02X1538775I1225J-681D01*
G03X1539475I350J194D01*
G02X1541381Y428125I1225J-681D01*
G03Y427425I194J-350D01*
G02Y424975I-681J-1225D01*
G03Y424275I194J-350D01*
G02X1539475Y422369I-681J-1225D01*
G03X1538775I-350J-194D01*
G02X1536325I-1225J681D01*
G03X1535625I-350J-194D01*
G02X1533175I-1225J681D01*
G03X1532475I-350J-194D01*
G37*
G36*
G01X1668413Y425845D02*
G02X1667107Y425878I-684J-1224D01*
G03X1667125Y426585I-177J358D01*
G02X1666997Y428952I684J1224D01*
G03X1666962Y429627I-231J326D01*
G02X1668461Y429706I687J1222D01*
G03X1668496Y429031I231J-326D01*
G02X1668431Y426552I-687J-1222D01*
G03X1668413Y425845I177J-358D01*
G37*
G36*
G01X1612829Y430595D02*
G02X1611286Y430758I-894J-1080D01*
G03X1611356Y431420I-185J354D01*
G02X1611473Y433667I894J1080D01*
G03Y434333I-222J333D01*
G02X1613027I777J1167D01*
G03Y433667I222J-333D01*
G02X1612899Y431257I-777J-1167D01*
G03X1612829Y430595I185J-354D01*
G37*
G36*
G01X746945Y431271D02*
G02X745331Y431282I-815J-1141D01*
G03X745336Y431936I-228J329D01*
G02X746950Y431925I815J1141D01*
G03X746945Y431271I228J-329D01*
G37*
G36*
G01X1510425Y434969D02*
G02X1508519Y436875I-1225J681D01*
G03Y437575I-194J350D01*
G02Y440025I681J1225D01*
G03Y440725I-194J350D01*
G02X1510425Y442631I681J1225D01*
G03X1511125I350J194D01*
G02X1513575I1225J-681D01*
G03X1514275I350J194D01*
G02X1516181Y440725I1225J-681D01*
G03Y440025I194J-350D01*
G02X1516725Y439481I-681J-1225D01*
G03X1517425I350J194D01*
G02X1519331Y437575I1225J-681D01*
G03Y436875I194J-350D01*
G02X1517425Y434969I-681J-1225D01*
G03X1516725I-350J-194D01*
G02X1514275I-1225J681D01*
G03X1513575I-350J-194D01*
G02X1511125I-1225J681D01*
G03X1510425I-350J-194D01*
G37*
G36*
G01X1525631Y436875D02*
G02X1524269I-681J-1225D01*
G03Y437575I-194J350D01*
G02X1525631I681J1225D01*
G03Y436875I194J-350D01*
G37*
G36*
G01X1532475Y434969D02*
G02X1530569Y436875I-1225J681D01*
G03Y437575I-194J350D01*
G02X1532475Y439481I681J1225D01*
G03X1533175I350J194D01*
G02X1535625I1225J-681D01*
G03X1536325I350J194D01*
G02X1538775I1225J-681D01*
G03X1539475I350J194D01*
G02X1541381Y437575I1225J-681D01*
G03Y436875I194J-350D01*
G02X1540019I-681J-1225D01*
G03Y437575I-194J350D01*
G02X1539475Y438119I681J1225D01*
G03X1538775I-350J-194D01*
G02X1536325I-1225J681D01*
G03X1535625I-350J-194D01*
G02X1535081Y437575I-1225J681D01*
G03Y436875I194J-350D01*
G02X1533175Y434969I-681J-1225D01*
G03X1532475I-350J-194D01*
G37*
G36*
G01X1665691Y439085D02*
G02X1663833I-929J-1050D01*
G03Y439685I-265J300D01*
G02X1663985Y441902I929J1050D01*
G03Y442568I-222J333D01*
G02X1665539I777J1167D01*
G03Y441902I222J-333D01*
G02X1665812Y441664I-777J-1167D01*
G03X1666412I300J265D01*
G02X1668435Y441745I1050J-929D01*
G03X1668989I277J288D01*
G02X1670527Y439452I973J-1010D01*
G03X1670330Y438907I161J-366D01*
G02X1667769Y438789I-1254J-626D01*
G03X1667411Y439334I-373J145D01*
G02X1666412Y439806I51J1401D01*
G03X1665812I-300J-265D01*
G02X1665691Y439685I-1050J929D01*
G03Y439085I265J-300D01*
G37*
G36*
G01X1544591Y440047D02*
G02X1543231Y440004I-641J-1247D01*
G03X1543209Y440703I-205J343D01*
G02X1543169Y443175I641J1247D01*
G03Y443875I-194J350D01*
G02X1542625Y444419I681J1225D01*
G03X1541925I-350J-194D01*
G02X1539475I-1225J681D01*
G03X1538775I-350J-194D01*
G02X1536325I-1225J681D01*
G03X1535625I-350J-194D01*
G02X1533175I-1225J681D01*
G03X1532475I-350J-194D01*
G02X1530569Y446325I-1225J681D01*
G03Y447025I-194J350D01*
G02X1532475Y448931I681J1225D01*
G03X1533175I350J194D01*
G02X1535625I1225J-681D01*
G03X1536325I350J194D01*
G02X1538775I1225J-681D01*
G03X1539475I350J194D01*
G02X1541381Y447025I1225J-681D01*
G03Y446325I194J-350D01*
G02X1541925Y445781I-681J-1225D01*
G03X1542625I350J194D01*
G02X1544531Y443875I1225J-681D01*
G03Y443175I194J-350D01*
G02X1544569Y440746I-681J-1225D01*
G03X1544591Y440047I205J-343D01*
G37*
G36*
G01X1286805Y441007D02*
G02X1285559Y441448I-1036J-945D01*
G03X1285795Y442113I-60J395D01*
G02X1286911Y444458I1036J945D01*
G03X1287320Y444964I24J399D01*
G02X1288591Y443938I1351J374D01*
G03X1288182Y443432I-24J-399D01*
G02X1287041Y441672I-1351J-374D01*
G03X1286805Y441007I60J-395D01*
G37*
G36*
G01X1725270Y442675D02*
G02X1723640Y442799I-901J-1074D01*
G03X1723689Y443447I-208J342D01*
G02X1723579Y443550I902J1073D01*
G03X1723001I-289J-277D01*
G02Y445492I-1011J971D01*
G03X1723579I289J277D01*
G02X1725804Y445222I1011J-971D01*
G03X1726476Y445191I346J201D01*
G02X1726406Y443679I1144J-811D01*
G03X1725734Y443710I-346J-201D01*
G02X1725319Y443323I-1144J811D01*
G03X1725270Y442675I208J-342D01*
G37*
G36*
G01X1602290Y445654D02*
G02X1601199Y444330I310J-1367D01*
G03X1600710Y444733I-400J13D01*
G02X1601801Y446057I-310J1367D01*
G03X1602290Y445654I400J-13D01*
G37*
G36*
G01X1523025Y444419D02*
G02Y445781I-1225J681D01*
G03X1523725I350J194D01*
G02X1524269Y446325I1225J-681D01*
G03Y447025I-194J350D01*
G02X1525631I681J1225D01*
G03Y446325I194J-350D01*
G02X1523725Y444419I-681J-1225D01*
G03X1523025I-350J-194D01*
G37*
G36*
G01X1504495Y446629D02*
G02X1503769Y448171I-1370J297D01*
G03X1504344Y448442I184J355D01*
G02X1505070Y446900I1370J-297D01*
G03X1504495Y446629I-184J-355D01*
G37*
G36*
G01X1887393Y446949D02*
G02X1887357Y449106I-1063J1061D01*
G03X1887913Y449115I273J292D01*
G02X1890220Y448896I1063J-1061D01*
G03X1890882I331J224D01*
G02X1893369Y448897I1244J-842D01*
G03X1894032I332J224D01*
G02Y447211I1243J-843D01*
G03X1893369I-331J-224D01*
G02X1890882Y447212I-1243J843D01*
G03X1890220I-331J-224D01*
G02X1887949Y446958I-1244J842D01*
G03X1887393Y446949I-273J-292D01*
G37*
G36*
G01X1918547Y447249D02*
G02X1916039Y447364I-1225J681D01*
G03X1915340Y447424I-366J-162D01*
G02X1915456Y448766I-1167J777D01*
G03X1916155Y448706I366J162D01*
G02X1918547Y448611I1167J-776D01*
G03X1919247I350J194D01*
G02Y447249I1225J-681D01*
G03X1918547I-350J-194D01*
G37*
G36*
G01X1516725Y447569D02*
G02X1514777Y449451I-1225J681D01*
G03X1514753Y450151I-205J343D01*
G02X1516112Y450199I636J1249D01*
G03X1516136Y449499I205J-343D01*
G02X1516725Y448931I-636J-1249D01*
G03X1517425I350J194D01*
G02X1517996Y449490I1225J-681D01*
G03X1518002Y450195I-186J354D01*
G02X1519896Y452114I673J1230D01*
G03X1520590Y452108I349J196D01*
G02X1520579Y450711I1210J-708D01*
G03X1519885Y450717I-349J-196D01*
G02X1519329Y450185I-1210J708D01*
G03X1519323Y449480I186J-354D01*
G02X1517425Y447569I-673J-1230D01*
G03X1516725I-350J-194D01*
G37*
G36*
G01X1933562Y449612D02*
G02X1933835Y451960I-3243J1567D01*
G03X1934464Y451726I390J87D01*
G02X1934228Y449696I836J-1126D01*
G03X1933562Y449612I-306J-258D01*
G37*
G36*
G01X1887331Y453292D02*
G02X1887255Y455349I-1131J988D01*
G03X1887837Y455371I281J285D01*
G02X1890212Y455225I1131J-988D01*
G03X1890874I331J224D01*
G02Y453541I1244J-842D01*
G03X1890212I-331J-224D01*
G02X1887913Y453314I-1244J842D01*
G03X1887331Y453292I-281J-285D01*
G37*
G36*
G01X1842797Y453544D02*
G02Y455098I-1167J777D01*
G03X1843463I333J222D01*
G02Y453544I1167J-777D01*
G03X1842797I-333J-222D01*
G37*
G36*
G01X22025Y453470D02*
G02X20075Y455751I-1027J1096D01*
G03Y456381I-246J315D01*
G02X20300Y458896I923J1185D01*
G03X20326Y459590I-185J354D01*
G02X22145Y461962I792J1276D01*
G03X22691I273J292D01*
G02X24745I1027J-1096D01*
G03X25291I273J292D01*
G02X27368Y461940I1027J-1096D01*
G03X27930Y461942I280J286D01*
G02X29686Y459546I1058J-1066D01*
G03X29660Y458852I185J-354D01*
G02X29791Y456391I-792J-1276D01*
G03Y455761I246J-315D01*
G02X27818Y453502I-923J-1185D01*
G03X27256Y453500I-280J-286D01*
G02X25171Y453470I-1058J1066D01*
G03X24625I-273J-292D01*
G02X22571I-1027J1096D01*
G03X22025I-273J-292D01*
G37*
G36*
G01X1340024Y465338D02*
Y464952D01*
G03X1340669Y464636I400J0D01*
G02X1342485Y464552I859J-1108D01*
G03X1343054Y464575I273J292D01*
G02X1345126I1036J-945D01*
G03X1345714Y464571I296J269D01*
G02X1345703Y462670I1025J-956D01*
G03X1345115Y462674I-296J-269D01*
G02X1343133Y462606I-1025J956D01*
G03X1342564Y462583I-273J-292D01*
G02X1340169Y463185I-1036J945D01*
G01X1340131Y463336D01*
X1331020D01*
Y463761D01*
X1330703D01*
X1330646Y463658D01*
G02Y465016I-1227J679D01*
G01X1330703Y464913D01*
X1331020D01*
Y465338D01*
X1340024D01*
G37*
G36*
G01X620740Y465350D02*
G02X619173Y464668I-340J-1360D01*
G03X618920Y465250I-350J194D01*
G02X618450Y467754I340J1360D01*
G03X618479Y468385I-231J327D01*
G02X620200Y468306I911J1065D01*
G03X620171Y467675I231J-327D01*
G02X620487Y465932I-911J-1065D01*
G03X620740Y465350I350J-194D01*
G37*
G36*
G01X-5187Y465904D02*
G02X-6694Y466110I-913J-1064D01*
G03X-6603Y466776I-169J362D01*
G02X-5096Y466570I913J1064D01*
G03X-5187Y465904I169J-362D01*
G37*
G36*
G01X1916064Y467856D02*
G02Y466143I1234J-857D01*
G03X1915407I-329J-228D01*
G02X1912920Y466172I-1234J857D01*
G03X1912252I-334J-220D01*
G02Y467828I-1253J828D01*
G03X1912920I334J220D01*
G02X1915407Y467856I1253J-828D01*
G03X1916064I328J228D01*
G37*
G36*
G01X635060Y468734D02*
G02X633769Y469117I-1027J-1096D01*
G03X633980Y469794I-71J393D01*
G02X635277Y472157I987J996D01*
G03X635761Y472605I88J390D01*
G02X636838Y471442I1387J204D01*
G03X636354Y470994I-88J-390D01*
G02X635252Y469417I-1387J-204D01*
G03X635060Y468734I82J-391D01*
G37*
G36*
G01X1330646Y470016D02*
X1330703Y469913D01*
X1331020D01*
Y470338D01*
X1340024D01*
Y468336D01*
X1331020D01*
Y468761D01*
X1330703D01*
X1330646Y468658D01*
G02Y470016I-1227J679D01*
G37*
G36*
G01X1617774Y469168D02*
G02Y470722I-1167J777D01*
G03X1618440I333J222D01*
G02Y469168I1167J-777D01*
G03X1617774I-333J-222D01*
G37*
G36*
G01X1911277Y473167D02*
G02X1909723I-777J-1167D01*
G03Y473833I-222J333D01*
G02X1911277I777J1167D01*
G03Y473167I222J-333D01*
G37*
G36*
G01X1323587Y473271D02*
X1323644Y473168D01*
X1323962D01*
Y473594D01*
X1332964D01*
Y471590D01*
X1323962D01*
Y472016D01*
X1323644D01*
X1323587Y471913D01*
G02Y473271I-1227J679D01*
G37*
G36*
G01X607004Y472635D02*
G02X604816Y474367I-1179J759D01*
G03Y474921I-288J277D01*
G02X606836I1010J973D01*
G03Y474367I288J-277D01*
G02X606961Y474216I-1015J-967D01*
G03X607622Y474234I324J235D01*
G02X607665Y472653I1178J-759D01*
G03X607004Y472635I-324J-235D01*
G37*
G36*
G01X1273248Y472998D02*
Y473084D01*
G03X1272580Y473380I-400J-1D01*
G02X1272873Y475088I-940J1040D01*
G01X1272929Y474983D01*
X1273248D01*
Y475002D01*
X1282252D01*
Y472998D01*
X1273248D01*
G37*
G36*
G01X1259220Y473646D02*
G02Y475434I-1080J894D01*
G03X1259901Y475542I309J254D01*
G01X1268932D01*
Y473538D01*
X1259901D01*
G03X1259220Y473646I-372J-146D01*
G37*
G36*
G01X66784Y476042D02*
G02X65693Y476991I-1334J-432D01*
G03X66143Y477508I70J394D01*
G02X67234Y476559I1334J432D01*
G03X66784Y476042I-70J-394D01*
G37*
G36*
G01X1841917Y474947D02*
G02Y476501I-1167J777D01*
G03X1842583I333J222D01*
G02Y474947I1167J-777D01*
G03X1841917I-333J-222D01*
G37*
G36*
G01X1323487Y478171D02*
X1323544Y478068D01*
X1323862D01*
Y478494D01*
X1332864D01*
Y476490D01*
X1323862D01*
Y476916D01*
X1323544D01*
X1323487Y476813D01*
G02Y478171I-1227J679D01*
G37*
G36*
G01X4127Y479339D02*
G02X3786Y477842I973J-1009D01*
G03X3133Y477991I-375J-139D01*
G02X931Y478326I-973J1009D01*
G03X229I-351J-192D01*
G02Y479674I-1229J674D01*
G03X931I351J192D01*
G02X1566Y480270I1229J-674D01*
G03X1661Y480932I-170J362D01*
G02X3795Y482698I928J1051D01*
G03X4483I344J204D01*
G02Y481268I1206J-715D01*
G03X3795I-344J-204D01*
G02X3183Y480713I-1206J715D01*
G03X3088Y480051I170J-362D01*
G02X3474Y479488I-928J-1050D01*
G03X4127Y479339I375J139D01*
G37*
G36*
G01X1272864Y479542D02*
X1272915Y479419D01*
X1273248D01*
Y480002D01*
X1282252D01*
Y477998D01*
X1273248D01*
Y478581D01*
X1272915D01*
X1272864Y478458D01*
G02Y479542I-1293J542D01*
G37*
G36*
G01X90883Y478991D02*
G02X90312Y480342I-1386J210D01*
G03X90940Y480608I232J325D01*
G02X93029Y481611I1386J-210D01*
G03X93622Y481881I200J346D01*
G02X94295Y480399I1376J-269D01*
G03X93702Y480129I-200J-346D01*
G02X91511Y479257I-1376J269D01*
G03X90883Y478991I-232J-325D01*
G37*
G36*
G01X1599811Y478370D02*
G02Y480080I-1111J855D01*
G03X1600446I317J243D01*
G02Y478370I1111J-855D01*
G03X1599811I-317J-243D01*
G37*
G36*
G01X1570800Y480997D02*
G02X1569699Y482101I-1375J-271D01*
G03X1570170Y482571I78J392D01*
G02X1571271Y481467I1375J271D01*
G03X1570800Y480997I-78J-392D01*
G37*
G36*
G01X626879Y481069D02*
G02X626695Y482403I-1310J499D01*
G03X627390Y482499I321J239D01*
G02X627574Y481165I1310J-499D01*
G03X626879Y481069I-321J-239D01*
G37*
G36*
G01X1272874Y483179D02*
X1272931Y483076D01*
X1273248D01*
Y483502D01*
X1282252D01*
Y481498D01*
X1273248D01*
Y481924D01*
X1272931D01*
X1272874Y481821D01*
G02Y483179I-1227J679D01*
G37*
G36*
G01X32607Y481958D02*
G02X32544Y483698I-1130J830D01*
G03X33170Y483720I304J259D01*
G02X33233Y481980I1130J-830D01*
G03X32607Y481958I-304J-259D01*
G37*
G36*
G01X1688120Y485257D02*
G02X1686836Y485235I-621J-1257D01*
G03X1686823Y485946I-190J352D01*
G02X1688416Y488213I620J1257D01*
G03X1688970I277J288D01*
G02X1690893Y488234I973J-1010D01*
G03X1691448Y488247I271J294D01*
G02X1691493Y486228I995J-988D01*
G03X1690938Y486215I-271J-294D01*
G02X1688970Y486193I-995J988D01*
G03X1688416I-277J-288D01*
G02X1688107Y485968I-972J1010D01*
G03X1688120Y485257I190J-352D01*
G37*
G36*
G01X1457304Y487077D02*
G02X1455890Y487072I-703J-1213D01*
G03X1455888Y487763I-203J345D01*
G02X1457302Y487768I703J1213D01*
G03X1457304Y487077I203J-345D01*
G37*
G36*
G01X657051Y487930D02*
G02X655110Y487893I-951J-1030D01*
G03X655099Y488470I-282J283D01*
G02X657402Y489870I951J1030D01*
G03X658073Y489694I386J105D01*
G02X657718Y488339I997J-985D01*
G03X657047Y488515I-386J-105D01*
G02X657040Y488507I-1056J917D01*
G03X657051Y487930I282J-283D01*
G37*
G36*
G01X1272585Y488381D02*
G03X1273205Y488502I263J301D01*
G01X1282252D01*
Y486498D01*
X1273248D01*
Y486724D01*
X1272933D01*
X1272875Y486624D01*
G02X1272585Y488381I-1213J702D01*
G37*
G36*
G01X1642122Y488168D02*
G02X1641073Y489131I-1341J-408D01*
G03X1641539Y489639I83J391D01*
G02X1642588Y488676I1341J408D01*
G03X1642122Y488168I-83J-391D01*
G37*
G36*
G01X729744Y488062D02*
G02X729310Y489399I-1371J294D01*
G03X729968Y489613I267J298D01*
G02X730402Y488276I1371J-294D01*
G03X729744Y488062I-267J-298D01*
G37*
G36*
G01X1257395Y491560D02*
X1257455Y491488D01*
X1257748D01*
Y491502D01*
X1266752D01*
Y489498D01*
X1257748D01*
Y489832D01*
X1257455D01*
X1257395Y489760D01*
G02Y491560I-1075J900D01*
G37*
G36*
G01X1641064Y497040D02*
G02X1640645Y495487I899J-1076D01*
G03X1640012Y495658I-376J-136D01*
G02X1640431Y497211I-899J1076D01*
G03X1641064Y497040I376J136D01*
G37*
G36*
G01X1590192Y495198D02*
G02Y496752I-1167J777D01*
G03X1590858I333J222D01*
G02Y495198I1167J-777D01*
G03X1590192I-333J-222D01*
G37*
G36*
G01X1268014Y497007D02*
G02X1267785Y495327I992J-991D01*
G03X1267154Y495413I-348J-197D01*
G02X1267383Y497093I-992J991D01*
G03X1268014Y497007I348J197D01*
G37*
G36*
G01X1279705Y497522D02*
G02X1279311Y495877I890J-1083D01*
G03X1278690Y496025I-366J-161D01*
G02X1279084Y497670I-890J1083D01*
G03X1279705Y497522I366J161D01*
G37*
G36*
G01X1789242Y495925D02*
G02X1786803Y496003I-1197J729D01*
G03X1786100Y496014I-354J-185D01*
G02X1786120Y497352I-1222J687D01*
G03X1786823Y497341I354J185D01*
G02X1789235Y497396I1222J-687D01*
G03X1789916Y497399I340J211D01*
G02X1789923Y495928I1197J-730D01*
G03X1789242Y495925I-340J-211D01*
G37*
G36*
G01X1728638Y501596D02*
X1733639D01*
G02X1735150Y500095I0J-1511D01*
G01Y500000D01*
X1735141Y499916D01*
G02X1733639Y498574I-1502J169D01*
G01X1729462D01*
G03X1729184Y497886I0J-400D01*
G02X1726963Y495872I-1046J-1078D01*
G03X1726422Y495952I-313J-249D01*
G02X1724064Y497224I-856J1234D01*
G03X1723649Y497634I-400J11D01*
G02X1723676Y500635I-58J1501D01*
G03X1724098Y501027I22J399D01*
G02X1727036Y501439I1502J-27D01*
G03X1727674Y501248I383J117D01*
G02X1728638Y501596I965J-1163D01*
G37*
G36*
G01X689432Y497063D02*
G02X689149Y498770I-1230J673D01*
G03X689770Y498873I270J295D01*
G02X690053Y497166I1230J-673D01*
G03X689432Y497063I-270J-295D01*
G37*
G36*
G01X1616058Y497784D02*
G02X1615976Y499474I-1158J791D01*
G03X1616613Y499505I307J256D01*
G02X1616695Y497815I1158J-791D01*
G03X1616058Y497784I-307J-256D01*
G37*
G36*
G01X55164Y501438D02*
G02X53088Y503514I-1264J812D01*
G03Y504186I-216J336D01*
G02X55164Y506262I812J1264D01*
G03X55836I336J216D01*
G02X58364I1264J-812D01*
G03X59036I336J216D01*
G02X61112Y504186I1264J-812D01*
G03Y503514I216J-336D01*
G02X59036Y501438I-812J-1264D01*
G03X58364I-336J-216D01*
G02X55836I-1264J812D01*
G03X55164I-336J-216D01*
G37*
G36*
G01X1565777Y504496D02*
G02X1564223I-777J-1167D01*
G03Y505162I-222J333D01*
G02X1565777I777J1167D01*
G03Y504496I222J-333D01*
G37*
G36*
G01X680274Y503064D02*
G02X680159Y504602I-1225J682D01*
G03X680825Y504652I317J245D01*
G02X680940Y503114I1225J-682D01*
G03X680274Y503064I-317J-245D01*
G37*
G36*
G01X1689443Y505238D02*
G02X1688723Y503689I648J-1243D01*
G03X1688148Y503957I-391J-87D01*
G02X1686391Y504342I-648J1243D01*
G03X1685759I-316J-245D01*
G02Y506058I-1109J858D01*
G03X1686391I316J245D01*
G02X1688868Y505506I1109J-858D01*
G03X1689443Y505238I391J87D01*
G37*
G36*
G01X1534568Y510040D02*
G02X1532953Y510276I-972J-1010D01*
G03X1533047Y510920I-183J356D01*
G02X1534662Y510684I972J1010D01*
G03X1534568Y510040I183J-356D01*
G37*
G36*
G01X1401610Y509379D02*
G02X1401229Y511321I-1165J780D01*
G03X1401785Y511430I224J332D01*
G02X1404117Y511427I1165J-780D01*
G03X1404783I333J222D01*
G02X1406073Y512047I1167J-777D01*
G03X1406502Y512513I35J398D01*
G02X1407761Y511354I1382J238D01*
G03X1407332Y510888I-35J-398D01*
G02X1404783Y509873I-1382J-238D01*
G03X1404117I-333J-222D01*
G02X1402166Y509488I-1167J777D01*
G03X1401610Y509379I-224J-332D01*
G37*
G36*
G01X1910967Y509923D02*
G02Y511477I-1167J777D01*
G03X1911633I333J222D01*
G02Y509923I1167J-777D01*
G03X1910967I-333J-222D01*
G37*
G36*
G01X1296853Y509800D02*
G02X1294958Y511866I-973J1010D01*
G03X1294975Y512452I-263J301D01*
G02X1295183Y514617I985J998D01*
G03Y515283I-222J333D01*
G02Y517617I777J1167D01*
G03Y518283I-222J333D01*
G02X1296933Y520460I778J1167D01*
G03X1297487I277J288D01*
G02X1299237Y518283I972J-1010D01*
G03Y517617I222J-333D01*
G02Y515283I-777J-1167D01*
G03Y514617I222J-333D01*
G02X1299382Y512394I-777J-1167D01*
G03X1299365Y511808I263J-301D01*
G02X1297407Y509800I-985J-998D01*
G03X1296853I-277J-288D01*
G37*
G36*
G01X713293Y511963D02*
G02X713170Y513605I-1193J736D01*
G03X713816Y513654I305J259D01*
G02X713939Y512012I1193J-736D01*
G03X713293Y511963I-305J-259D01*
G37*
G36*
G01X1828753Y514383D02*
G02X1826598Y513175I-753J-1183D01*
G03X1826088Y513553I-400J-7D01*
G02X1826184Y516216I-388J1347D01*
G03X1826716Y516527I137J375D01*
G02X1827212Y517385I1384J-227D01*
G03X1827234Y517984I-254J309D01*
G02X1829088Y517915I966J1016D01*
G03X1829066Y517316I254J-309D01*
G02X1828775Y515071I-966J-1016D01*
G03X1828753Y514383I192J-351D01*
G37*
G36*
G01X1797553Y514117D02*
G02X1796878Y515400I-1400J83D01*
G03X1797483Y515719I206J343D01*
G02X1799952Y516543I1400J-83D01*
G03X1800555Y516535I305J259D01*
G02X1800531Y514693I1045J-935D01*
G03X1799928Y514701I-305J-259D01*
G02X1798158Y514436I-1045J935D01*
G03X1797553Y514117I-206J-343D01*
G37*
G36*
G01X1340419Y516938D02*
G02X1339015Y517074I-819J-1138D01*
G03X1339081Y517762I-167J363D01*
G02X1340485Y517626I819J1138D01*
G03X1340419Y516938I167J-363D01*
G37*
G36*
G01X1861057Y521367D02*
G02X1859312Y521214I-777J-1167D01*
G03X1859126Y521894I-276J290D01*
G02X1861122Y522069I728J3169D01*
G03X1861057Y521367I156J-368D01*
G37*
G36*
G01X41429Y521343D02*
G02X40279Y522116I-1318J-720D01*
G03X40675Y522705I45J397D01*
G02X41825Y521932I1318J720D01*
G03X41429Y521343I-45J-397D01*
G37*
G36*
G01X1804213Y522569D02*
G02X1802541Y526180I-3227J698D01*
G03X1803122Y526459I188J353D01*
G02X1803575Y527253I1378J-260D01*
G03X1803409Y527942I-264J301D01*
G02X1804677Y528248I343J1359D01*
G03X1804843Y527559I264J-301D01*
G02X1805726Y525521I-343J-1359D01*
G03X1806076Y524927I350J-194D01*
G02X1804931Y522716I0J-1402D01*
G03X1804213Y522569I-327J-231D01*
G37*
G36*
G01X1415993Y520663D02*
G02X1415941Y522214I-1193J736D01*
G03X1416607Y522237I325J233D01*
G02X1416659Y520686I1193J-736D01*
G03X1415993Y520663I-325J-233D01*
G37*
G36*
G01X124524Y527827D02*
X124453Y527767D01*
Y527474D01*
X124722D01*
Y520372D01*
X122518D01*
Y527474D01*
X122787D01*
Y527767D01*
X122716Y527827D01*
G02X124524I904J1072D01*
G37*
G36*
G01X131217D02*
X131146Y527767D01*
Y527474D01*
X131414D01*
Y520372D01*
X129212D01*
Y527474D01*
X129480D01*
Y527767D01*
X129409Y527827D01*
G02X131217I904J1072D01*
G37*
G36*
G01X147949D02*
X147878Y527767D01*
Y527474D01*
X148146D01*
Y520372D01*
X145944D01*
Y527474D01*
X146212D01*
Y527767D01*
X146141Y527827D01*
G02X147949I904J1072D01*
G37*
G36*
G01X154642D02*
X154571Y527767D01*
Y527474D01*
X154840D01*
Y520372D01*
X152636D01*
Y527474D01*
X152905D01*
Y527767D01*
X152834Y527827D01*
G02X154642I904J1072D01*
G37*
G36*
G01X161335D02*
X161264Y527767D01*
Y527474D01*
X161532D01*
Y520372D01*
X159330D01*
Y527474D01*
X159598D01*
Y527767D01*
X159527Y527827D01*
G02X161335I904J1072D01*
G37*
G36*
G01X168028D02*
X167957Y527767D01*
Y527474D01*
X168226D01*
Y520372D01*
X166022D01*
Y527474D01*
X166291D01*
Y527767D01*
X166220Y527827D01*
G02X168028I904J1072D01*
G37*
G36*
G01X184760D02*
X184689Y527767D01*
Y527474D01*
X184958D01*
Y520372D01*
X182754D01*
Y527474D01*
X183023D01*
Y527767D01*
X182952Y527827D01*
G02X184760I904J1072D01*
G37*
G36*
G01X191453D02*
X191382Y527767D01*
Y527474D01*
X191650D01*
Y520372D01*
X189448D01*
Y527474D01*
X189716D01*
Y527767D01*
X189645Y527827D01*
G02X191453I904J1072D01*
G37*
G36*
G01X198146D02*
X198075Y527767D01*
Y527474D01*
X198344D01*
Y520372D01*
X196140D01*
Y527474D01*
X196409D01*
Y527767D01*
X196338Y527827D01*
G02X198146I904J1072D01*
G37*
G36*
G01X204839D02*
X204768Y527767D01*
Y527474D01*
X205036D01*
Y520372D01*
X202834D01*
Y527474D01*
X203102D01*
Y527767D01*
X203031Y527827D01*
G02X204839I904J1072D01*
G37*
G36*
G01X221571D02*
X221500Y527767D01*
Y527474D01*
X221768D01*
Y520372D01*
X219566D01*
Y527474D01*
X219834D01*
Y527767D01*
X219763Y527827D01*
G02X221571I904J1072D01*
G37*
G36*
G01X228264D02*
X228193Y527767D01*
Y527474D01*
X228462D01*
Y520372D01*
X226258D01*
Y527474D01*
X226527D01*
Y527767D01*
X226456Y527827D01*
G02X228264I904J1072D01*
G37*
G36*
G01X234957D02*
X234886Y527767D01*
Y527474D01*
X235154D01*
Y520372D01*
X232952D01*
Y527474D01*
X233220D01*
Y527767D01*
X233149Y527827D01*
G02X234957I904J1072D01*
G37*
G36*
G01X241650D02*
X241579Y527767D01*
Y527474D01*
X241848D01*
Y520372D01*
X239644D01*
Y527474D01*
X239913D01*
Y527767D01*
X239842Y527827D01*
G02X241650I904J1072D01*
G37*
G36*
G01X258382D02*
X258311Y527767D01*
Y527474D01*
X258580D01*
Y520372D01*
X256376D01*
Y527474D01*
X256645D01*
Y527767D01*
X256574Y527827D01*
G02X258382I904J1072D01*
G37*
G36*
G01X265075D02*
X265004Y527767D01*
Y527474D01*
X265272D01*
Y520372D01*
X263070D01*
Y527474D01*
X263338D01*
Y527767D01*
X263267Y527827D01*
G02X265075I904J1072D01*
G37*
G36*
G01X271768D02*
X271697Y527767D01*
Y527474D01*
X271966D01*
Y520372D01*
X269762D01*
Y527474D01*
X270031D01*
Y527767D01*
X269960Y527827D01*
G02X271768I904J1072D01*
G37*
G36*
G01X278461D02*
X278390Y527767D01*
Y527474D01*
X278658D01*
Y520372D01*
X276456D01*
Y527474D01*
X276724D01*
Y527767D01*
X276653Y527827D01*
G02X278461I904J1072D01*
G37*
G36*
G01X295193D02*
X295122Y527767D01*
Y527474D01*
X295390D01*
Y520372D01*
X293188D01*
Y527474D01*
X293456D01*
Y527767D01*
X293385Y527827D01*
G02X295193I904J1072D01*
G37*
G36*
G01X301886D02*
X301815Y527767D01*
Y527474D01*
X302084D01*
Y520372D01*
X299882D01*
Y527474D01*
X300149D01*
Y527767D01*
X300078Y527827D01*
G02X301886I904J1072D01*
G37*
G36*
G01X452477D02*
X452406Y527767D01*
Y527474D01*
X452674D01*
Y520372D01*
X450470D01*
Y527474D01*
X450740D01*
Y527767D01*
X450669Y527827D01*
G02X452477I904J1072D01*
G37*
G36*
G01X459170D02*
X459099Y527767D01*
Y527474D01*
X459366D01*
Y520372D01*
X457164D01*
Y527474D01*
X457433D01*
Y527767D01*
X457362Y527827D01*
G02X459170I904J1072D01*
G37*
G36*
G01X475902D02*
X475831Y527767D01*
Y527474D01*
X476100D01*
Y520372D01*
X473896D01*
Y527474D01*
X474165D01*
Y527767D01*
X474094Y527827D01*
G02X475902I904J1072D01*
G37*
G36*
G01X482595D02*
X482524Y527767D01*
Y527474D01*
X482792D01*
Y520372D01*
X480590D01*
Y527474D01*
X480858D01*
Y527767D01*
X480787Y527827D01*
G02X482595I904J1072D01*
G37*
G36*
G01X489288D02*
X489217Y527767D01*
Y527474D01*
X489484D01*
Y520372D01*
X487282D01*
Y527474D01*
X487551D01*
Y527767D01*
X487480Y527827D01*
G02X489288I904J1072D01*
G37*
G36*
G01X495981D02*
X495910Y527767D01*
Y527474D01*
X496178D01*
Y520372D01*
X493974D01*
Y527474D01*
X494244D01*
Y527767D01*
X494173Y527827D01*
G02X495981I904J1072D01*
G37*
G36*
G01X512713D02*
X512642Y527767D01*
Y527474D01*
X512910D01*
Y520372D01*
X510708D01*
Y527474D01*
X510976D01*
Y527767D01*
X510905Y527827D01*
G02X512713I904J1072D01*
G37*
G36*
G01X519406D02*
X519335Y527767D01*
Y527474D01*
X519604D01*
Y520372D01*
X517400D01*
Y527474D01*
X517669D01*
Y527767D01*
X517598Y527827D01*
G02X519406I904J1072D01*
G37*
G36*
G01X526099D02*
X526028Y527767D01*
Y527474D01*
X526296D01*
Y520372D01*
X524092D01*
Y527474D01*
X524362D01*
Y527767D01*
X524291Y527827D01*
G02X526099I904J1072D01*
G37*
G36*
G01X532792D02*
X532721Y527767D01*
Y527474D01*
X532988D01*
Y520372D01*
X530786D01*
Y527474D01*
X531055D01*
Y527767D01*
X530984Y527827D01*
G02X532792I904J1072D01*
G37*
G36*
G01X549524D02*
X549453Y527767D01*
Y527474D01*
X549722D01*
Y520372D01*
X547518D01*
Y527474D01*
X547787D01*
Y527767D01*
X547716Y527827D01*
G02X549524I904J1072D01*
G37*
G36*
G01X556217D02*
X556146Y527767D01*
Y527474D01*
X556414D01*
Y520372D01*
X554212D01*
Y527474D01*
X554480D01*
Y527767D01*
X554409Y527827D01*
G02X556217I904J1072D01*
G37*
G36*
G01X562910D02*
X562839Y527767D01*
Y527474D01*
X563106D01*
Y520372D01*
X560904D01*
Y527474D01*
X561173D01*
Y527767D01*
X561102Y527827D01*
G02X562910I904J1072D01*
G37*
G36*
G01X569603D02*
X569532Y527767D01*
Y527474D01*
X569800D01*
Y520372D01*
X567596D01*
Y527474D01*
X567866D01*
Y527767D01*
X567795Y527827D01*
G02X569603I904J1072D01*
G37*
G36*
G01X586335D02*
X586264Y527767D01*
Y527474D01*
X586532D01*
Y520372D01*
X584330D01*
Y527474D01*
X584598D01*
Y527767D01*
X584527Y527827D01*
G02X586335I904J1072D01*
G37*
G36*
G01X593028D02*
X592957Y527767D01*
Y527474D01*
X593226D01*
Y520372D01*
X591022D01*
Y527474D01*
X591291D01*
Y527767D01*
X591220Y527827D01*
G02X593028I904J1072D01*
G37*
G36*
G01X774132D02*
X774061Y527767D01*
Y527474D01*
X774330D01*
Y520372D01*
X772126D01*
Y527474D01*
X772395D01*
Y527767D01*
X772324Y527827D01*
G02X774132I904J1072D01*
G37*
G36*
G01X780825D02*
X780754Y527767D01*
Y527474D01*
X781022D01*
Y520372D01*
X778820D01*
Y527474D01*
X779088D01*
Y527767D01*
X779017Y527827D01*
G02X780825I904J1072D01*
G37*
G36*
G01X797557D02*
X797486Y527767D01*
Y527474D01*
X797754D01*
Y520372D01*
X795552D01*
Y527474D01*
X795820D01*
Y527767D01*
X795749Y527827D01*
G02X797557I904J1072D01*
G37*
G36*
G01X804250D02*
X804179Y527767D01*
Y527474D01*
X804448D01*
Y520372D01*
X802244D01*
Y527474D01*
X802513D01*
Y527767D01*
X802442Y527827D01*
G02X804250I904J1072D01*
G37*
G36*
G01X810943D02*
X810872Y527767D01*
Y527474D01*
X811140D01*
Y520372D01*
X808938D01*
Y527474D01*
X809206D01*
Y527767D01*
X809135Y527827D01*
G02X810943I904J1072D01*
G37*
G36*
G01X817636D02*
X817565Y527767D01*
Y527474D01*
X817834D01*
Y520372D01*
X815630D01*
Y527474D01*
X815899D01*
Y527767D01*
X815828Y527827D01*
G02X817636I904J1072D01*
G37*
G36*
G01X834368D02*
X834297Y527767D01*
Y527474D01*
X834566D01*
Y520372D01*
X832362D01*
Y527474D01*
X832631D01*
Y527767D01*
X832560Y527827D01*
G02X834368I904J1072D01*
G37*
G36*
G01X841061D02*
X840990Y527767D01*
Y527474D01*
X841258D01*
Y520372D01*
X839056D01*
Y527474D01*
X839324D01*
Y527767D01*
X839253Y527827D01*
G02X841061I904J1072D01*
G37*
G36*
G01X847754D02*
X847683Y527767D01*
Y527474D01*
X847952D01*
Y520372D01*
X845748D01*
Y527474D01*
X846017D01*
Y527767D01*
X845946Y527827D01*
G02X847754I904J1072D01*
G37*
G36*
G01X854447D02*
X854376Y527767D01*
Y527474D01*
X854644D01*
Y520372D01*
X852442D01*
Y527474D01*
X852710D01*
Y527767D01*
X852639Y527827D01*
G02X854447I904J1072D01*
G37*
G36*
G01X871179D02*
X871108Y527767D01*
Y527474D01*
X871376D01*
Y520372D01*
X869174D01*
Y527474D01*
X869442D01*
Y527767D01*
X869371Y527827D01*
G02X871179I904J1072D01*
G37*
G36*
G01X877872D02*
X877801Y527767D01*
Y527474D01*
X878070D01*
Y520372D01*
X875866D01*
Y527474D01*
X876135D01*
Y527767D01*
X876064Y527827D01*
G02X877872I904J1072D01*
G37*
G36*
G01X884565D02*
X884494Y527767D01*
Y527474D01*
X884762D01*
Y520372D01*
X882560D01*
Y527474D01*
X882828D01*
Y527767D01*
X882757Y527827D01*
G02X884565I904J1072D01*
G37*
G36*
G01X891258D02*
X891187Y527767D01*
Y527474D01*
X891456D01*
Y520372D01*
X889252D01*
Y527474D01*
X889521D01*
Y527767D01*
X889450Y527827D01*
G02X891258I904J1072D01*
G37*
G36*
G01X907990D02*
X907919Y527767D01*
Y527474D01*
X908188D01*
Y520372D01*
X905984D01*
Y527474D01*
X906253D01*
Y527767D01*
X906182Y527827D01*
G02X907990I904J1072D01*
G37*
G36*
G01X914683D02*
X914612Y527767D01*
Y527474D01*
X914880D01*
Y520372D01*
X912678D01*
Y527474D01*
X912946D01*
Y527767D01*
X912875Y527827D01*
G02X914683I904J1072D01*
G37*
G36*
G01X921376D02*
X921305Y527767D01*
Y527474D01*
X921574D01*
Y520372D01*
X919370D01*
Y527474D01*
X919639D01*
Y527767D01*
X919568Y527827D01*
G02X921376I904J1072D01*
G37*
G36*
G01X928069D02*
X927998Y527767D01*
Y527474D01*
X928266D01*
Y520372D01*
X926064D01*
Y527474D01*
X926332D01*
Y527767D01*
X926261Y527827D01*
G02X928069I904J1072D01*
G37*
G36*
G01X944801D02*
X944730Y527767D01*
Y527474D01*
X944998D01*
Y520372D01*
X942796D01*
Y527474D01*
X943064D01*
Y527767D01*
X942993Y527827D01*
G02X944801I904J1072D01*
G37*
G36*
G01X951494D02*
X951423Y527767D01*
Y527474D01*
X951692D01*
Y520372D01*
X949490D01*
Y527474D01*
X949757D01*
Y527767D01*
X949686Y527827D01*
G02X951494I904J1072D01*
G37*
G36*
G01X1102085D02*
X1102014Y527767D01*
Y527474D01*
X1102282D01*
Y520372D01*
X1100078D01*
Y527474D01*
X1100348D01*
Y527767D01*
X1100277Y527827D01*
G02X1102085I904J1072D01*
G37*
G36*
G01X1108778D02*
X1108707Y527767D01*
Y527474D01*
X1108974D01*
Y520372D01*
X1106772D01*
Y527474D01*
X1107041D01*
Y527767D01*
X1106970Y527827D01*
G02X1108778I904J1072D01*
G37*
G36*
G01X1125510D02*
X1125439Y527767D01*
Y527474D01*
X1125708D01*
Y520372D01*
X1123504D01*
Y527474D01*
X1123773D01*
Y527767D01*
X1123702Y527827D01*
G02X1125510I904J1072D01*
G37*
G36*
G01X1132203D02*
X1132132Y527767D01*
Y527474D01*
X1132400D01*
Y520372D01*
X1130198D01*
Y527474D01*
X1130466D01*
Y527767D01*
X1130395Y527827D01*
G02X1132203I904J1072D01*
G37*
G36*
G01X1138896D02*
X1138825Y527767D01*
Y527474D01*
X1139092D01*
Y520372D01*
X1136890D01*
Y527474D01*
X1137159D01*
Y527767D01*
X1137088Y527827D01*
G02X1138896I904J1072D01*
G37*
G36*
G01X1145589D02*
X1145518Y527767D01*
Y527474D01*
X1145786D01*
Y520372D01*
X1143582D01*
Y527474D01*
X1143852D01*
Y527767D01*
X1143781Y527827D01*
G02X1145589I904J1072D01*
G37*
G36*
G01X1162321D02*
X1162250Y527767D01*
Y527474D01*
X1162518D01*
Y520372D01*
X1160316D01*
Y527474D01*
X1160584D01*
Y527767D01*
X1160513Y527827D01*
G02X1162321I904J1072D01*
G37*
G36*
G01X1169014D02*
X1168943Y527767D01*
Y527474D01*
X1169212D01*
Y520372D01*
X1167008D01*
Y527474D01*
X1167277D01*
Y527767D01*
X1167206Y527827D01*
G02X1169014I904J1072D01*
G37*
G36*
G01X1175707D02*
X1175636Y527767D01*
Y527474D01*
X1175904D01*
Y520372D01*
X1173700D01*
Y527474D01*
X1173970D01*
Y527767D01*
X1173899Y527827D01*
G02X1175707I904J1072D01*
G37*
G36*
G01X1182400D02*
X1182329Y527767D01*
Y527474D01*
X1182596D01*
Y520372D01*
X1180394D01*
Y527474D01*
X1180663D01*
Y527767D01*
X1180592Y527827D01*
G02X1182400I904J1072D01*
G37*
G36*
G01X1199132D02*
X1199061Y527767D01*
Y527474D01*
X1199330D01*
Y520372D01*
X1197126D01*
Y527474D01*
X1197395D01*
Y527767D01*
X1197324Y527827D01*
G02X1199132I904J1072D01*
G37*
G36*
G01X1205825D02*
X1205754Y527767D01*
Y527474D01*
X1206022D01*
Y520372D01*
X1203820D01*
Y527474D01*
X1204088D01*
Y527767D01*
X1204017Y527827D01*
G02X1205825I904J1072D01*
G37*
G36*
G01X1212518D02*
X1212447Y527767D01*
Y527474D01*
X1212714D01*
Y520372D01*
X1210512D01*
Y527474D01*
X1210781D01*
Y527767D01*
X1210710Y527827D01*
G02X1212518I904J1072D01*
G37*
G36*
G01X1219211D02*
X1219140Y527767D01*
Y527474D01*
X1219408D01*
Y520372D01*
X1217204D01*
Y527474D01*
X1217474D01*
Y527767D01*
X1217403Y527827D01*
G02X1219211I904J1072D01*
G37*
G36*
G01X1235943D02*
X1235872Y527767D01*
Y527474D01*
X1236140D01*
Y520372D01*
X1233938D01*
Y527474D01*
X1234206D01*
Y527767D01*
X1234135Y527827D01*
G02X1235943I904J1072D01*
G37*
G36*
G01X1242636D02*
X1242565Y527767D01*
Y527474D01*
X1242834D01*
Y520372D01*
X1240630D01*
Y527474D01*
X1240899D01*
Y527767D01*
X1240828Y527827D01*
G02X1242636I904J1072D01*
G37*
G36*
G01X90674Y523007D02*
G02X90451Y521273I976J-1007D01*
G03X89831Y521352I-342J-208D01*
G02X90054Y523086I-976J1007D01*
G03X90674Y523007I342J208D01*
G37*
G36*
G01X47646Y524933D02*
G02X46049Y525384I-1139J-980D01*
G03X46230Y526025I-122J381D01*
G02X47827Y525574I1139J980D01*
G03X47646Y524933I122J-381D01*
G37*
G36*
G01X1437747Y525335D02*
G02X1436550Y526531I-1389J-193D01*
G03X1437001Y526982I55J396D01*
G02X1438198Y525786I1389J193D01*
G03X1437747Y525335I-55J-396D01*
G37*
G36*
G01X717110Y526173D02*
G02X715090I-1010J-973D01*
G03Y526727I-288J277D01*
G02X715006Y526823I1012J970D01*
G03X714694I-156J-125D01*
G02X713488Y526302I-1094J877D01*
G03X713067Y525810I-32J-399D01*
G02X711816Y526881I-1363J-327D01*
G03X712237Y527373I32J399D01*
G02X712590Y528673I1363J328D01*
G03Y529227I-288J277D01*
G02Y531173I1010J973D01*
G03Y531727I-288J277D01*
G02X714573Y533710I1010J973D01*
G03X715127I277J288D01*
G02X717110Y531727I973J-1010D01*
G03Y531173I288J-277D01*
G02Y529227I-1010J-973D01*
G03Y528673I288J-277D01*
G02Y526727I-1010J-973D01*
G03Y526173I288J-277D01*
G37*
G36*
G01X1296749Y526817D02*
G02X1294883Y528867I-1089J883D01*
G03Y529533I-222J333D01*
G02Y531867I777J1167D01*
G03Y532533I-222J333D01*
G02Y534867I777J1167D01*
G03Y535533I-222J333D01*
G02X1296749Y537583I777J1167D01*
G03X1297371I311J252D01*
G02X1299237Y535533I1089J-883D01*
G03Y534867I222J-333D01*
G02Y532533I-777J-1167D01*
G03Y531867I222J-333D01*
G02Y529533I-777J-1167D01*
G03Y528867I222J-333D01*
G02X1297371Y526817I-777J-1167D01*
G03X1296749I-311J-252D01*
G37*
G36*
G01X652317Y529423D02*
G02X650121Y531152I-1167J777D01*
G03X650110Y531707I-293J272D01*
G02X652283Y533453I991J992D01*
G03X652971Y533475I337J214D01*
G02X655151Y531770I1229J-675D01*
G03X655140Y531193I271J-294D01*
G02X652983Y529423I-990J-993D01*
G03X652317I-333J-222D01*
G37*
G36*
G01X658223Y530290D02*
G02X656473Y532467I-972J1010D01*
G03Y533133I-222J333D01*
G02X658223Y535310I778J1167D01*
G03X658777I277J288D01*
G02X660527Y533133I972J-1010D01*
G03Y532467I222J-333D01*
G02X658777Y530290I-778J-1167D01*
G03X658223I-277J-288D01*
G37*
G36*
G01X1460414Y532386D02*
G02X1460352Y530695I1086J-886D01*
G03X1459715Y530718I-327J-230D01*
G02X1459777Y532409I-1086J886D01*
G03X1460414Y532386I327J230D01*
G37*
G36*
G01X726180Y532943D02*
G02X726154Y534496I-1180J757D01*
G03X726820Y534507I329J227D01*
G02X726846Y532954I1180J-757D01*
G03X726180Y532943I-329J-227D01*
G37*
G36*
G01X63667Y534723D02*
G02Y536277I-1167J777D01*
G03X64333I333J222D01*
G02X66667I1167J-777D01*
G03X67333I333J222D01*
G02Y534723I1167J-777D01*
G03X66667I-333J-222D01*
G02X64333I-1167J777D01*
G03X63667I-333J-222D01*
G37*
G36*
G01X1385303Y534550D02*
G02X1383533Y536707I-993J990D01*
G03Y537373I-222J333D01*
G02Y539707I777J1167D01*
G03Y540373I-222J333D01*
G02X1382961Y541923I777J1167D01*
G03X1382522Y542429I-384J110D01*
G02X1383680Y543435I-191J1389D01*
G03X1384119Y542929I384J-110D01*
G02X1385295Y542538I191J-1389D01*
G03X1385848Y542529I281J284D01*
G02X1386507Y542871I952J-1029D01*
G03X1386753Y543490I-83J391D01*
G02X1388200Y542915I1154J796D01*
G03X1387954Y542296I83J-391D01*
G02X1387577Y540333I-1154J-796D01*
G03Y539667I222J-333D01*
G02X1387632Y537372I-777J-1167D01*
G03Y536728I238J-322D01*
G02X1385856Y534564I-832J-1128D01*
G03X1385303Y534550I-269J-296D01*
G37*
G36*
G01X121003Y537838D02*
G02X119172Y538186I-1111J-855D01*
G01Y545584D01*
X121374D01*
Y538482D01*
X121320D01*
G03X121003Y537838I0J-400D01*
G37*
G36*
G01X770611D02*
G02X768780Y538186I-1111J-855D01*
G01Y545584D01*
X770982D01*
Y538482D01*
X770928D01*
G03X770611Y537838I0J-400D01*
G37*
G36*
G01X71506Y537405D02*
G02X69730Y539561I-984J999D01*
G03X69725Y540224I-226J330D01*
G02X71455Y542419I774J1169D01*
G03X72012Y542430I273J292D01*
G02X73953Y542481I997J-986D01*
G03X74497Y542486I269J296D01*
G02X76433Y542478I964J-1018D01*
G03X76988I277J288D01*
G02X78905Y542504I972J-1010D01*
G03X79444I270J295D01*
G02X81166Y540301I944J-1036D01*
G03Y539635I222J-333D01*
G02X79444Y537432I-778J-1167D01*
G03X78905I-270J-295D01*
G02X76988Y537458I-945J1036D01*
G03X76433I-277J-288D01*
G02X74517Y537431I-972J1010D01*
G03X73973Y537426I-269J-296D01*
G02X72058Y537414I-964J1018D01*
G03X71506Y537405I-271J-294D01*
G37*
G36*
G01X646927Y541517D02*
G02X645373I-777J-1167D01*
G03Y542183I-222J333D01*
G02Y544517I777J1167D01*
G03Y545183I-222J333D01*
G02X646927I777J1167D01*
G03Y544517I222J-333D01*
G02Y542183I-777J-1167D01*
G03Y541517I222J-333D01*
G37*
G36*
G01X1940620Y541958D02*
G02X1938484Y540203I-920J-1058D01*
G03X1937951Y540358I-347J-199D01*
G02X1938516Y542297I-651J1242D01*
G03X1939049Y542142I347J199D01*
G02X1939064Y542150I667J-1233D01*
G03X1939077Y542499I-91J178D01*
G02X1938408Y543537I723J1201D01*
G03X1937830Y543848I-398J-46D01*
G02X1937855Y546340I-630J1252D01*
G03X1938432Y546606I187J354D01*
G02X1940771Y545289I1368J-306D01*
G03Y544711I277J-289D01*
G02X1940642Y542579I-971J-1011D01*
G03X1940620Y541958I241J-319D01*
G37*
G36*
G01X1922965Y544767D02*
G02X1921424Y545028I-965J-1017D01*
G03X1921535Y545683I-164J365D01*
G02X1923076Y545422I965J1017D01*
G03X1922965Y544767I164J-365D01*
G37*
G36*
G01X1915609Y545971D02*
G02X1914125Y546118I-859J-1108D01*
G03X1914191Y546792I-179J358D01*
G02X1915675Y546645I859J1108D01*
G03X1915609Y545971I179J-358D01*
G37*
G36*
G01X1453744Y545652D02*
G02X1450890Y544963I-1352J-654D01*
G03X1450364Y545334I-400J-9D01*
G02X1448818Y545799I-443J1330D01*
G03X1448175Y545780I-314J-247D01*
G02X1448126Y547443I-1153J798D01*
G03X1448769Y547462I314J247D01*
G02X1451312Y546480I1153J-798D01*
G03X1451614Y546283I198J-26D01*
G02X1451651Y546305I786J-1280D01*
G03X1451814Y546827I-197J348D01*
G02X1454297Y548469I1352J654D01*
G03X1454910Y548482I301J263D01*
G02X1454949Y546552I1170J-942D01*
G03X1454336Y546539I-301J-263D01*
G02X1453907Y546174I-1171J941D01*
G03X1453744Y545652I197J-348D01*
G37*
G36*
G01X1811291Y544448D02*
G02X1811069Y546068I-1239J655D01*
G03X1811713Y546156I290J275D01*
G02X1811935Y544536I1239J-655D01*
G03X1811291Y544448I-290J-275D01*
G37*
G36*
G01X1278982Y546573D02*
G02X1277957Y545548I336J-1361D01*
G03X1277473Y546032I-389J95D01*
G02X1278498Y547057I-336J1361D01*
G03X1278982Y546573I389J-95D01*
G37*
G36*
G01X1899954Y546114D02*
G02X1898485Y546604I-1104J-864D01*
G03X1898696Y547236I-104J386D01*
G02X1898565Y547436I1103J865D01*
G03X1898010Y547591I-352J-190D01*
G02X1898535Y549464I-710J1209D01*
G03X1899090Y549309I352J190D01*
G02X1900165Y546746I710J-1209D01*
G03X1899954Y546114I104J-386D01*
G37*
G36*
G01X1857125Y548275D02*
G02X1855432Y549365I-1375J-275D01*
G03X1855733Y549833I-91J389D01*
G02X1856137Y551119I1375J275D01*
G03Y551697I-277J289D01*
G02X1856097Y551737I971J1011D01*
G03X1855519I-289J-277D01*
G02X1853146Y553039I-1011J971D01*
G03X1852678Y553526I-389J95D01*
G02X1853762Y554569I-278J1374D01*
G03X1854230Y554082I389J-95D01*
G02X1855519Y553679I278J-1374D01*
G03X1856097I289J277D01*
G02X1858119I1011J-971D01*
G03X1858697I289J277D01*
G02Y551737I1011J-971D01*
G03X1858119I-289J-277D01*
G02X1858079Y551697I-1011J971D01*
G03Y551119I277J-289D01*
G02X1857426Y548743I-971J-1011D01*
G03X1857125Y548275I91J-389D01*
G37*
G36*
G01X1849505Y549465D02*
G02X1848218Y549425I-605J-1265D01*
G03X1848195Y550135I-195J349D01*
G02X1849482Y550175I605J1265D01*
G03X1849505Y549465I195J-349D01*
G37*
G36*
G01X1836978Y550660D02*
G02X1836688Y549207I1022J-959D01*
G03X1836022Y549340I-374J-141D01*
G02X1836312Y550793I-1022J959D01*
G03X1836978Y550660I374J141D01*
G37*
G36*
G01X730541Y549008D02*
G02X728773Y551167I-991J992D01*
G03Y551833I-222J333D01*
G02Y554167I777J1167D01*
G03Y554833I-222J333D01*
G02X730541Y556992I777J1167D01*
G03X731107I283J282D01*
G02X732875Y554833I991J-992D01*
G03Y554167I222J-333D01*
G02Y551833I-777J-1167D01*
G03Y551167I222J-333D01*
G02X731107Y549008I-777J-1167D01*
G03X730541I-283J-282D01*
G37*
G36*
G01X1816995Y551606D02*
G02X1815565I-715J-1206D01*
G03Y552294I-204J344D01*
G02X1816995I715J1206D01*
G03Y551606I204J-344D01*
G37*
G36*
G01X1300777Y553567D02*
G02X1299223I-777J-1167D01*
G03Y554233I-222J333D01*
G02Y556567I777J1167D01*
G03Y557233I-222J333D01*
G02X1300777I777J1167D01*
G03Y556567I222J-333D01*
G02Y554233I-777J-1167D01*
G03Y553567I222J-333D01*
G37*
G36*
G01X1318667Y551623D02*
G02X1316723Y553567I-1167J777D01*
G03Y554233I-222J333D01*
G02Y556567I777J1167D01*
G03Y557233I-222J333D01*
G02X1318667Y559177I777J1167D01*
G03X1319333I333J222D01*
G02X1321667I1167J-777D01*
G03X1322333I333J222D01*
G02X1324277Y557233I1167J-777D01*
G03Y556567I222J-333D01*
G02Y554233I-777J-1167D01*
G03Y553567I222J-333D01*
G02X1322333Y551623I-777J-1167D01*
G03X1321667I-333J-222D01*
G02X1319333I-1167J777D01*
G03X1318667I-333J-222D01*
G37*
G36*
G01X658306Y551785D02*
G02Y553215I-1206J715D01*
G03X658994I344J204D01*
G02Y551785I1206J-715D01*
G03X658306I-344J-204D01*
G37*
G36*
G01X1755319Y553024D02*
G02X1754626Y554754I-1319J476D01*
G03X1755181Y554976I179J358D01*
G02X1757667Y555277I1319J-476D01*
G03X1758333I333J222D01*
G02Y553723I1167J-777D01*
G03X1757667I-333J-222D01*
G02X1755874Y553246I-1167J777D01*
G03X1755319Y553024I-179J-358D01*
G37*
G36*
G01X64667Y553723D02*
G02X62723Y555667I-1167J777D01*
G03Y556333I-222J333D01*
G02X64667Y558277I777J1167D01*
G03X65333I333J222D01*
G02X67667I1167J-777D01*
G03X68333I333J222D01*
G02X70667I1167J-777D01*
G03X71333I333J222D01*
G02X73667I1167J-777D01*
G03X74333I333J222D01*
G02X76667I1167J-777D01*
G03X77333I333J222D01*
G02X79667I1167J-777D01*
G03X80333I333J222D01*
G02X82277Y556333I1167J-777D01*
G03Y555667I222J-333D01*
G02X80333Y553723I-777J-1167D01*
G03X79667I-333J-222D01*
G02X77333I-1167J777D01*
G03X76667I-333J-222D01*
G02X74333I-1167J777D01*
G03X73667I-333J-222D01*
G02X71333I-1167J777D01*
G03X70667I-333J-222D01*
G02X68333I-1167J777D01*
G03X67667I-333J-222D01*
G02X65333I-1167J777D01*
G03X64667I-333J-222D01*
G37*
G36*
G01X1913006Y556655D02*
G02X1912416Y555278I794J-1155D01*
G03X1911794Y555545I-395J-63D01*
G02X1912384Y556922I-794J1155D01*
G03X1913006Y556655I395J63D01*
G37*
G36*
G01X124524Y565627D02*
X124453Y565567D01*
Y565274D01*
X124722D01*
Y558172D01*
X122518D01*
Y565274D01*
X122787D01*
Y565567D01*
X122716Y565627D01*
G02X124524I904J1072D01*
G37*
G36*
G01X131217D02*
X131146Y565567D01*
Y565274D01*
X131414D01*
Y558172D01*
X129212D01*
Y565274D01*
X129480D01*
Y565567D01*
X129409Y565627D01*
G02X131217I904J1072D01*
G37*
G36*
G01X147949D02*
X147878Y565567D01*
Y565274D01*
X148146D01*
Y558172D01*
X145944D01*
Y565274D01*
X146212D01*
Y565567D01*
X146141Y565627D01*
G02X147949I904J1072D01*
G37*
G36*
G01X154642D02*
X154571Y565567D01*
Y565274D01*
X154840D01*
Y558172D01*
X152636D01*
Y565274D01*
X152905D01*
Y565567D01*
X152834Y565627D01*
G02X154642I904J1072D01*
G37*
G36*
G01X161335D02*
X161264Y565567D01*
Y565274D01*
X161532D01*
Y558172D01*
X159330D01*
Y565274D01*
X159598D01*
Y565567D01*
X159527Y565627D01*
G02X161335I904J1072D01*
G37*
G36*
G01X168028D02*
X167957Y565567D01*
Y565274D01*
X168226D01*
Y558172D01*
X166022D01*
Y565274D01*
X166291D01*
Y565567D01*
X166220Y565627D01*
G02X168028I904J1072D01*
G37*
G36*
G01X184760D02*
X184689Y565567D01*
Y565274D01*
X184958D01*
Y558172D01*
X182754D01*
Y565274D01*
X183023D01*
Y565567D01*
X182952Y565627D01*
G02X184760I904J1072D01*
G37*
G36*
G01X191453D02*
X191382Y565567D01*
Y565274D01*
X191650D01*
Y558172D01*
X189448D01*
Y565274D01*
X189716D01*
Y565567D01*
X189645Y565627D01*
G02X191453I904J1072D01*
G37*
G36*
G01X198146D02*
X198075Y565567D01*
Y565274D01*
X198344D01*
Y558172D01*
X196140D01*
Y565274D01*
X196409D01*
Y565567D01*
X196338Y565627D01*
G02X198146I904J1072D01*
G37*
G36*
G01X204839D02*
X204768Y565567D01*
Y565274D01*
X205036D01*
Y558172D01*
X202834D01*
Y565274D01*
X203102D01*
Y565567D01*
X203031Y565627D01*
G02X204839I904J1072D01*
G37*
G36*
G01X221571D02*
X221500Y565567D01*
Y565274D01*
X221768D01*
Y558172D01*
X219566D01*
Y565274D01*
X219834D01*
Y565567D01*
X219763Y565627D01*
G02X221571I904J1072D01*
G37*
G36*
G01X228264D02*
X228193Y565567D01*
Y565274D01*
X228462D01*
Y558172D01*
X226258D01*
Y565274D01*
X226527D01*
Y565567D01*
X226456Y565627D01*
G02X228264I904J1072D01*
G37*
G36*
G01X234957D02*
X234886Y565567D01*
Y565274D01*
X235154D01*
Y558172D01*
X232952D01*
Y565274D01*
X233220D01*
Y565567D01*
X233149Y565627D01*
G02X234957I904J1072D01*
G37*
G36*
G01X241650D02*
X241579Y565567D01*
Y565274D01*
X241848D01*
Y558172D01*
X239644D01*
Y565274D01*
X239913D01*
Y565567D01*
X239842Y565627D01*
G02X241650I904J1072D01*
G37*
G36*
G01X258382D02*
X258311Y565567D01*
Y565274D01*
X258580D01*
Y558172D01*
X256376D01*
Y565274D01*
X256645D01*
Y565567D01*
X256574Y565627D01*
G02X258382I904J1072D01*
G37*
G36*
G01X265075D02*
X265004Y565567D01*
Y565274D01*
X265272D01*
Y558172D01*
X263070D01*
Y565274D01*
X263338D01*
Y565567D01*
X263267Y565627D01*
G02X265075I904J1072D01*
G37*
G36*
G01X271768D02*
X271697Y565567D01*
Y565274D01*
X271966D01*
Y558172D01*
X269762D01*
Y565274D01*
X270031D01*
Y565567D01*
X269960Y565627D01*
G02X271768I904J1072D01*
G37*
G36*
G01X278461D02*
X278390Y565567D01*
Y565274D01*
X278658D01*
Y558172D01*
X276456D01*
Y565274D01*
X276724D01*
Y565567D01*
X276653Y565627D01*
G02X278461I904J1072D01*
G37*
G36*
G01X295193D02*
X295122Y565567D01*
Y565274D01*
X295390D01*
Y558172D01*
X293188D01*
Y565274D01*
X293456D01*
Y565567D01*
X293385Y565627D01*
G02X295193I904J1072D01*
G37*
G36*
G01X301886D02*
X301815Y565567D01*
Y565274D01*
X302084D01*
Y558172D01*
X299882D01*
Y565274D01*
X300149D01*
Y565567D01*
X300078Y565627D01*
G02X301886I904J1072D01*
G37*
G36*
G01X452477D02*
X452406Y565567D01*
Y565274D01*
X452674D01*
Y558172D01*
X450470D01*
Y565274D01*
X450740D01*
Y565567D01*
X450669Y565627D01*
G02X452477I904J1072D01*
G37*
G36*
G01X459170D02*
X459099Y565567D01*
Y565274D01*
X459366D01*
Y558172D01*
X457164D01*
Y565274D01*
X457433D01*
Y565567D01*
X457362Y565627D01*
G02X459170I904J1072D01*
G37*
G36*
G01X475902D02*
X475831Y565567D01*
Y565274D01*
X476100D01*
Y558172D01*
X473896D01*
Y565274D01*
X474165D01*
Y565567D01*
X474094Y565627D01*
G02X475902I904J1072D01*
G37*
G36*
G01X482595D02*
X482524Y565567D01*
Y565274D01*
X482792D01*
Y558172D01*
X480590D01*
Y565274D01*
X480858D01*
Y565567D01*
X480787Y565627D01*
G02X482595I904J1072D01*
G37*
G36*
G01X489288D02*
X489217Y565567D01*
Y565274D01*
X489484D01*
Y558172D01*
X487282D01*
Y565274D01*
X487551D01*
Y565567D01*
X487480Y565627D01*
G02X489288I904J1072D01*
G37*
G36*
G01X495981D02*
X495910Y565567D01*
Y565274D01*
X496178D01*
Y558172D01*
X493974D01*
Y565274D01*
X494244D01*
Y565567D01*
X494173Y565627D01*
G02X495981I904J1072D01*
G37*
G36*
G01X512713D02*
X512642Y565567D01*
Y565274D01*
X512910D01*
Y558172D01*
X510708D01*
Y565274D01*
X510976D01*
Y565567D01*
X510905Y565627D01*
G02X512713I904J1072D01*
G37*
G36*
G01X519406D02*
X519335Y565567D01*
Y565274D01*
X519604D01*
Y558172D01*
X517400D01*
Y565274D01*
X517669D01*
Y565567D01*
X517598Y565627D01*
G02X519406I904J1072D01*
G37*
G36*
G01X526099D02*
X526028Y565567D01*
Y565274D01*
X526296D01*
Y558172D01*
X524092D01*
Y565274D01*
X524362D01*
Y565567D01*
X524291Y565627D01*
G02X526099I904J1072D01*
G37*
G36*
G01X532792D02*
X532721Y565567D01*
Y565274D01*
X532988D01*
Y558172D01*
X530786D01*
Y565274D01*
X531055D01*
Y565567D01*
X530984Y565627D01*
G02X532792I904J1072D01*
G37*
G36*
G01X549524D02*
X549453Y565567D01*
Y565274D01*
X549722D01*
Y558172D01*
X547518D01*
Y565274D01*
X547787D01*
Y565567D01*
X547716Y565627D01*
G02X549524I904J1072D01*
G37*
G36*
G01X556217D02*
X556146Y565567D01*
Y565274D01*
X556414D01*
Y558172D01*
X554212D01*
Y565274D01*
X554480D01*
Y565567D01*
X554409Y565627D01*
G02X556217I904J1072D01*
G37*
G36*
G01X562910D02*
X562839Y565567D01*
Y565274D01*
X563106D01*
Y558172D01*
X560904D01*
Y565274D01*
X561173D01*
Y565567D01*
X561102Y565627D01*
G02X562910I904J1072D01*
G37*
G36*
G01X569603D02*
X569532Y565567D01*
Y565274D01*
X569800D01*
Y558172D01*
X567596D01*
Y565274D01*
X567866D01*
Y565567D01*
X567795Y565627D01*
G02X569603I904J1072D01*
G37*
G36*
G01X586335D02*
X586264Y565567D01*
Y565274D01*
X586532D01*
Y558172D01*
X584330D01*
Y565274D01*
X584598D01*
Y565567D01*
X584527Y565627D01*
G02X586335I904J1072D01*
G37*
G36*
G01X593028D02*
X592957Y565567D01*
Y565274D01*
X593226D01*
Y558172D01*
X591022D01*
Y565274D01*
X591291D01*
Y565567D01*
X591220Y565627D01*
G02X593028I904J1072D01*
G37*
G36*
G01X774132D02*
X774061Y565567D01*
Y565274D01*
X774330D01*
Y558172D01*
X772126D01*
Y565274D01*
X772395D01*
Y565567D01*
X772324Y565627D01*
G02X774132I904J1072D01*
G37*
G36*
G01X780825D02*
X780754Y565567D01*
Y565274D01*
X781022D01*
Y558172D01*
X778820D01*
Y565274D01*
X779088D01*
Y565567D01*
X779017Y565627D01*
G02X780825I904J1072D01*
G37*
G36*
G01X797557D02*
X797486Y565567D01*
Y565274D01*
X797754D01*
Y558172D01*
X795552D01*
Y565274D01*
X795820D01*
Y565567D01*
X795749Y565627D01*
G02X797557I904J1072D01*
G37*
G36*
G01X804250D02*
X804179Y565567D01*
Y565274D01*
X804448D01*
Y558172D01*
X802244D01*
Y565274D01*
X802513D01*
Y565567D01*
X802442Y565627D01*
G02X804250I904J1072D01*
G37*
G36*
G01X810943D02*
X810872Y565567D01*
Y565274D01*
X811140D01*
Y558172D01*
X808938D01*
Y565274D01*
X809206D01*
Y565567D01*
X809135Y565627D01*
G02X810943I904J1072D01*
G37*
G36*
G01X817636D02*
X817565Y565567D01*
Y565274D01*
X817834D01*
Y558172D01*
X815630D01*
Y565274D01*
X815899D01*
Y565567D01*
X815828Y565627D01*
G02X817636I904J1072D01*
G37*
G36*
G01X834368D02*
X834297Y565567D01*
Y565274D01*
X834566D01*
Y558172D01*
X832362D01*
Y565274D01*
X832631D01*
Y565567D01*
X832560Y565627D01*
G02X834368I904J1072D01*
G37*
G36*
G01X841061D02*
X840990Y565567D01*
Y565274D01*
X841258D01*
Y558172D01*
X839056D01*
Y565274D01*
X839324D01*
Y565567D01*
X839253Y565627D01*
G02X841061I904J1072D01*
G37*
G36*
G01X847754D02*
X847683Y565567D01*
Y565274D01*
X847952D01*
Y558172D01*
X845748D01*
Y565274D01*
X846017D01*
Y565567D01*
X845946Y565627D01*
G02X847754I904J1072D01*
G37*
G36*
G01X854447D02*
X854376Y565567D01*
Y565274D01*
X854644D01*
Y558172D01*
X852442D01*
Y565274D01*
X852710D01*
Y565567D01*
X852639Y565627D01*
G02X854447I904J1072D01*
G37*
G36*
G01X871179D02*
X871108Y565567D01*
Y565274D01*
X871376D01*
Y558172D01*
X869174D01*
Y565274D01*
X869442D01*
Y565567D01*
X869371Y565627D01*
G02X871179I904J1072D01*
G37*
G36*
G01X877872D02*
X877801Y565567D01*
Y565274D01*
X878070D01*
Y558172D01*
X875866D01*
Y565274D01*
X876135D01*
Y565567D01*
X876064Y565627D01*
G02X877872I904J1072D01*
G37*
G36*
G01X884565D02*
X884494Y565567D01*
Y565274D01*
X884762D01*
Y558172D01*
X882560D01*
Y565274D01*
X882828D01*
Y565567D01*
X882757Y565627D01*
G02X884565I904J1072D01*
G37*
G36*
G01X891258D02*
X891187Y565567D01*
Y565274D01*
X891456D01*
Y558172D01*
X889252D01*
Y565274D01*
X889521D01*
Y565567D01*
X889450Y565627D01*
G02X891258I904J1072D01*
G37*
G36*
G01X907990D02*
X907919Y565567D01*
Y565274D01*
X908188D01*
Y558172D01*
X905984D01*
Y565274D01*
X906253D01*
Y565567D01*
X906182Y565627D01*
G02X907990I904J1072D01*
G37*
G36*
G01X914683D02*
X914612Y565567D01*
Y565274D01*
X914880D01*
Y558172D01*
X912678D01*
Y565274D01*
X912946D01*
Y565567D01*
X912875Y565627D01*
G02X914683I904J1072D01*
G37*
G36*
G01X921376D02*
X921305Y565567D01*
Y565274D01*
X921574D01*
Y558172D01*
X919370D01*
Y565274D01*
X919639D01*
Y565567D01*
X919568Y565627D01*
G02X921376I904J1072D01*
G37*
G36*
G01X928069D02*
X927998Y565567D01*
Y565274D01*
X928266D01*
Y558172D01*
X926064D01*
Y565274D01*
X926332D01*
Y565567D01*
X926261Y565627D01*
G02X928069I904J1072D01*
G37*
G36*
G01X944801D02*
X944730Y565567D01*
Y565274D01*
X944998D01*
Y558172D01*
X942796D01*
Y565274D01*
X943064D01*
Y565567D01*
X942993Y565627D01*
G02X944801I904J1072D01*
G37*
G36*
G01X951494D02*
X951423Y565567D01*
Y565274D01*
X951692D01*
Y558172D01*
X949490D01*
Y565274D01*
X949757D01*
Y565567D01*
X949686Y565627D01*
G02X951494I904J1072D01*
G37*
G36*
G01X1102085D02*
X1102014Y565567D01*
Y565274D01*
X1102282D01*
Y558172D01*
X1100078D01*
Y565274D01*
X1100348D01*
Y565567D01*
X1100277Y565627D01*
G02X1102085I904J1072D01*
G37*
G36*
G01X1108778D02*
X1108707Y565567D01*
Y565274D01*
X1108974D01*
Y558172D01*
X1106772D01*
Y565274D01*
X1107041D01*
Y565567D01*
X1106970Y565627D01*
G02X1108778I904J1072D01*
G37*
G36*
G01X1125510D02*
X1125439Y565567D01*
Y565274D01*
X1125708D01*
Y558172D01*
X1123504D01*
Y565274D01*
X1123773D01*
Y565567D01*
X1123702Y565627D01*
G02X1125510I904J1072D01*
G37*
G36*
G01X1132203D02*
X1132132Y565567D01*
Y565274D01*
X1132400D01*
Y558172D01*
X1130198D01*
Y565274D01*
X1130466D01*
Y565567D01*
X1130395Y565627D01*
G02X1132203I904J1072D01*
G37*
G36*
G01X1138896D02*
X1138825Y565567D01*
Y565274D01*
X1139092D01*
Y558172D01*
X1136890D01*
Y565274D01*
X1137159D01*
Y565567D01*
X1137088Y565627D01*
G02X1138896I904J1072D01*
G37*
G36*
G01X1145589D02*
X1145518Y565567D01*
Y565274D01*
X1145786D01*
Y558172D01*
X1143582D01*
Y565274D01*
X1143852D01*
Y565567D01*
X1143781Y565627D01*
G02X1145589I904J1072D01*
G37*
G36*
G01X1162321D02*
X1162250Y565567D01*
Y565274D01*
X1162518D01*
Y558172D01*
X1160316D01*
Y565274D01*
X1160584D01*
Y565567D01*
X1160513Y565627D01*
G02X1162321I904J1072D01*
G37*
G36*
G01X1169014D02*
X1168943Y565567D01*
Y565274D01*
X1169212D01*
Y558172D01*
X1167008D01*
Y565274D01*
X1167277D01*
Y565567D01*
X1167206Y565627D01*
G02X1169014I904J1072D01*
G37*
G36*
G01X1175707D02*
X1175636Y565567D01*
Y565274D01*
X1175904D01*
Y558172D01*
X1173700D01*
Y565274D01*
X1173970D01*
Y565567D01*
X1173899Y565627D01*
G02X1175707I904J1072D01*
G37*
G36*
G01X1182400D02*
X1182329Y565567D01*
Y565274D01*
X1182596D01*
Y558172D01*
X1180394D01*
Y565274D01*
X1180663D01*
Y565567D01*
X1180592Y565627D01*
G02X1182400I904J1072D01*
G37*
G36*
G01X1199132D02*
X1199061Y565567D01*
Y565274D01*
X1199330D01*
Y558172D01*
X1197126D01*
Y565274D01*
X1197395D01*
Y565567D01*
X1197324Y565627D01*
G02X1199132I904J1072D01*
G37*
G36*
G01X1205825D02*
X1205754Y565567D01*
Y565274D01*
X1206022D01*
Y558172D01*
X1203820D01*
Y565274D01*
X1204088D01*
Y565567D01*
X1204017Y565627D01*
G02X1205825I904J1072D01*
G37*
G36*
G01X1212518D02*
X1212447Y565567D01*
Y565274D01*
X1212714D01*
Y558172D01*
X1210512D01*
Y565274D01*
X1210781D01*
Y565567D01*
X1210710Y565627D01*
G02X1212518I904J1072D01*
G37*
G36*
G01X1219211D02*
X1219140Y565567D01*
Y565274D01*
X1219408D01*
Y558172D01*
X1217204D01*
Y565274D01*
X1217474D01*
Y565567D01*
X1217403Y565627D01*
G02X1219211I904J1072D01*
G37*
G36*
G01X1235943D02*
X1235872Y565567D01*
Y565274D01*
X1236140D01*
Y558172D01*
X1233938D01*
Y565274D01*
X1234206D01*
Y565567D01*
X1234135Y565627D01*
G02X1235943I904J1072D01*
G37*
G36*
G01X1242636D02*
X1242565Y565567D01*
Y565274D01*
X1242834D01*
Y558172D01*
X1240630D01*
Y565274D01*
X1240899D01*
Y565567D01*
X1240828Y565627D01*
G02X1242636I904J1072D01*
G37*
G36*
G01X1536158Y560624D02*
G02X1533730Y558862I-1261J-817D01*
G03X1533118Y558873I-311J-252D01*
G02X1530920Y558802I-1132J987D01*
G03X1530352I-284J-282D01*
G02X1528220I-1066J1058D01*
G03X1527652I-284J-282D01*
G02X1525145Y560284I-1066J1058D01*
G03X1524714Y560794I-384J113D01*
G02X1525585Y563363I-176J1492D01*
G03X1526163Y563384I279J287D01*
G02X1528351Y563444I1122J-998D01*
G03X1528919I284J282D01*
G02X1531051I1066J-1058D01*
G03X1531619I284J282D01*
G02X1533751I1066J-1058D01*
G03X1534319I284J282D01*
G02X1536210Y563641I1066J-1058D01*
G03X1536830Y563962I220J334D01*
G02X1539013Y565251I1501J-49D01*
G03X1539591Y565660I182J356D01*
G02X1542265Y566782I1489J199D01*
G03X1542895I315J246D01*
G02X1543157Y567044I1185J-923D01*
G03Y567674I-246J315D01*
G02X1545193Y569867I922J1185D01*
G03X1545741Y569824I297J268D01*
G02X1547617Y569834I944J-1168D01*
G03X1548164Y569881I249J313D01*
G02X1550407Y567883I1121J-1000D01*
G03X1550437Y567321I299J-266D01*
G02X1550483Y565145I-1012J-1110D01*
G03X1550477Y564583I282J-284D01*
G02X1548463Y562363I-1081J-1042D01*
G03X1547916Y562316I-249J-313D01*
G02X1545725Y562262I-1121J1000D01*
G03X1545130Y562235I-285J-280D01*
G02X1542901Y562127I-1163J950D01*
G03X1542333I-284J-282D01*
G02X1539806Y562838I-1066J1058D01*
G03X1539461Y562923I-194J-47D01*
G02X1539307Y562772I-1126J994D01*
G03X1539319Y562154I260J-304D01*
G02X1536915Y561289I-934J-1176D01*
G03X1536563Y561454I-196J41D01*
G02X1536261Y561166I-1178J932D01*
G03X1536158Y560624I233J-325D01*
G37*
G36*
G01X1377031Y560781D02*
G02X1375025Y560694I-961J-1021D01*
G03X1375000Y561252I-299J266D01*
G02X1377314Y562642I961J1021D01*
G03X1377988Y562470I386J105D01*
G02X1377599Y561559I1012J-971D01*
G03X1377220Y561656I-200J9D01*
G02X1377006Y561339I-1258J619D01*
G03X1377031Y560781I299J-266D01*
G37*
G36*
G01X1286743Y560598D02*
G02X1286157Y562180I-1343J402D01*
G03X1286757Y562402I217J336D01*
G02X1288885Y563162I1343J-402D01*
G03X1289506Y563450I224J332D01*
G02X1290115Y562138I1394J-150D01*
G03X1289494Y561850I-224J-332D01*
G02X1287343Y560820I-1394J150D01*
G03X1286743Y560598I-217J-336D01*
G37*
G36*
G01X64667Y560723D02*
G02Y562277I-1167J777D01*
G03X65333I333J222D01*
G02X67667I1167J-777D01*
G03X68333I333J222D01*
G02X70667I1167J-777D01*
G03X71333I333J222D01*
G02X73667I1167J-777D01*
G03X74333I333J222D01*
G02X76667I1167J-777D01*
G03X77333I333J222D01*
G02X79667I1167J-777D01*
G03X80333I333J222D01*
G02Y560723I1167J-777D01*
G03X79667I-333J-222D01*
G02X77333I-1167J777D01*
G03X76667I-333J-222D01*
G02X74333I-1167J777D01*
G03X73667I-333J-222D01*
G02X71333I-1167J777D01*
G03X70667I-333J-222D01*
G02X68333I-1167J777D01*
G03X67667I-333J-222D01*
G02X65333I-1167J777D01*
G03X64667I-333J-222D01*
G37*
G36*
G01X1744116Y562666D02*
G02X1742395Y562912I-1016J-966D01*
G03X1742484Y563534I-201J346D01*
G02X1742513Y565496I1016J966D01*
G03X1742447Y566118I-281J285D01*
G02X1742199Y568282I753J1183D01*
G03X1742155Y568881I-285J280D01*
G02X1744001Y569018I845J1119D01*
G03X1744045Y568419I285J-280D01*
G02X1744187Y566304I-845J-1119D01*
G03X1744253Y565682I281J-285D01*
G02X1744205Y563288I-753J-1182D01*
G03X1744116Y562666I201J-346D01*
G37*
G36*
G01X1934521Y563300D02*
G02X1933278Y562368I79J-1400D01*
G03X1932879Y562900I-377J133D01*
G02X1934122Y563832I-79J1400D01*
G03X1934521Y563300I377J-133D01*
G37*
G36*
G01X1417391Y563595D02*
G02X1417219Y561871I1011J-971D01*
G03X1416593Y561933I-337J-215D01*
G02X1416765Y563657I-1011J971D01*
G03X1417391Y563595I337J215D01*
G37*
G36*
G01X1324551Y564312D02*
G02X1322613Y562358I-778J-1167D01*
G03X1321998Y562415I-331J-224D01*
G02X1319833Y562623I-998J985D01*
G03X1319167I-333J-222D01*
G02X1316833I-1167J777D01*
G03X1316167I-333J-222D01*
G02X1313833I-1167J777D01*
G03X1313167I-333J-222D01*
G02X1310833I-1167J777D01*
G03X1310167I-333J-222D01*
G02X1307833I-1167J777D01*
G03X1307167I-333J-222D01*
G02X1304833I-1167J777D01*
G03X1304167I-333J-222D01*
G02X1301990Y564373I-1167J778D01*
G03Y564927I-288J277D01*
G02X1302223Y567067I1010J973D01*
G03Y567733I-222J333D01*
G02X1301990Y569873I777J1167D01*
G03Y570427I-288J277D01*
G02X1304167Y572177I1010J972D01*
G03X1304833I333J222D01*
G02X1307167I1167J-777D01*
G03X1307833I333J222D01*
G02X1310167I1167J-777D01*
G03X1310833I333J222D01*
G02X1313167I1167J-777D01*
G03X1313833I333J222D01*
G02X1316167I1167J-777D01*
G03X1316833I333J222D01*
G02X1319167I1167J-777D01*
G03X1319833I333J222D01*
G02X1322167I1167J-777D01*
G03X1322833I333J222D01*
G02X1325010Y570427I1167J-778D01*
G03Y569873I288J-277D01*
G02X1324809Y567755I-1010J-973D01*
G03X1324758Y567143I230J-327D01*
G02X1324551Y564978I-984J-998D01*
G03Y564312I222J-333D01*
G37*
G36*
G01X645967Y562523D02*
G02Y564077I-1167J777D01*
G03X646633I333J222D01*
G02X648967I1167J-777D01*
G03X649633I333J222D01*
G02X651967I1167J-777D01*
G03X652633I333J222D01*
G02Y562523I1167J-777D01*
G03X651967I-333J-222D01*
G02X649633I-1167J777D01*
G03X648967I-333J-222D01*
G02X646633I-1167J777D01*
G03X645967I-333J-222D01*
G37*
G36*
G01X1781547Y566291D02*
G02X1780064Y566043I-546J-1291D01*
G03X1779953Y566709I-267J298D01*
G02X1779579Y569057I547J1291D01*
G03Y569661I-262J302D01*
G02X1781421I921J1057D01*
G03Y569057I262J-302D01*
G02X1781436Y566957I-921J-1057D01*
G03X1781547Y566291I267J-298D01*
G37*
G36*
G01X1291833Y574879D02*
G02X1290274Y576083I-4430J-4124D01*
G03X1290847Y576550I190J352D01*
G02X1290798Y577116I1343J401D01*
G03X1290376Y577563I-397J48D01*
G02X1291684Y578798I-84J1399D01*
G03X1292106Y578351I397J-48D01*
G02X1292140Y575551I84J-1399D01*
G03X1291833Y574879I-14J-400D01*
G37*
G36*
G01X1936343Y569287D02*
G02X1935512Y567803I557J-1287D01*
G03X1934957Y568113I-396J-57D01*
G02X1935788Y569597I-557J1287D01*
G03X1936343Y569287I396J57D01*
G37*
G36*
G01X1726471Y569981D02*
G02X1724917I-777J-1167D01*
G03Y570647I-222J333D01*
G02X1726471I777J1167D01*
G03Y569981I222J-333D01*
G37*
G36*
G01X1467630Y570975D02*
G02X1467374Y569429I1019J-963D01*
G03X1466719Y569537I-364J-166D01*
G02X1466975Y571083I-1019J963D01*
G03X1467630Y570975I364J166D01*
G37*
G36*
G01X1808834Y571292D02*
G02X1807280I-777J-1167D01*
G03Y571958I-222J333D01*
G02X1808834I777J1167D01*
G03Y571292I222J-333D01*
G37*
G36*
G01X1418208Y569756D02*
G02X1416196Y569715I-1026J955D01*
G03X1415654Y569735I-282J-284D01*
G02X1413758Y571797I-910J1066D01*
G03X1413757Y572366I-282J284D01*
G02X1415676Y574409I986J996D01*
G03X1416233Y574433I266J299D01*
G02X1416588Y574705I1019J-963D01*
G03X1416596Y575405I-190J352D01*
G02X1416340Y575591I691J1220D01*
G03X1415799I-270J-295D01*
G02Y577657I-948J1033D01*
G03X1416340I271J295D01*
G02X1418229Y577663I948J-1033D01*
G03X1418789Y577685I269J296D01*
G02X1420825Y577689I1020J-962D01*
G03X1421424Y577711I290J276D01*
G02X1423286Y575656I1085J-888D01*
G03Y574990I222J-333D01*
G02Y572656I-777J-1167D01*
G03Y571990I222J-333D01*
G02X1421493Y569857I-777J-1167D01*
G03X1420894Y569835I-290J-276D01*
G02X1418791Y569759I-1085J888D01*
G03X1418208Y569756I-290J-276D01*
G37*
G36*
G01X121374Y576282D02*
X121252D01*
G03X120951Y575619I1J-400D01*
G02X119182Y575909I-1059J-919D01*
G01X119281Y575967D01*
Y576282D01*
X119172D01*
Y583384D01*
X121374D01*
Y576282D01*
G37*
G36*
G01X770982D02*
X770860D01*
G03X770559Y575619I1J-400D01*
G02X768790Y575909I-1059J-919D01*
G01X768889Y575967D01*
Y576282D01*
X768780D01*
Y583384D01*
X770982D01*
Y576282D01*
G37*
G36*
G01X1764596Y575913D02*
G02X1763899Y574647I704J-1213D01*
G03X1763299Y574978I-400J-15D01*
G02X1763996Y576244I-704J1213D01*
G03X1764596Y575913I400J15D01*
G37*
G36*
G01X1386444Y573872D02*
G02X1384021Y574167I-1128J833D01*
G03X1383396Y574322I-370J-153D01*
G02X1383795Y575938I-896J1078D01*
G03X1384420Y575783I370J153D01*
G02X1386266Y575736I896J-1078D01*
G03X1386858Y575793I270J295D01*
G02X1387036Y573929I1128J-833D01*
G03X1386444Y573872I-270J-295D01*
G37*
G36*
G01X72667Y574223D02*
G02X70723Y576167I-1167J777D01*
G03Y576833I-222J333D01*
G02X72667Y578777I777J1167D01*
G03X73333I333J222D01*
G02X75277Y576833I1167J-777D01*
G03Y576167I222J-333D01*
G02X73333Y574223I-777J-1167D01*
G03X72667I-333J-222D01*
G37*
G36*
G01X79667D02*
G02X77723Y576167I-1167J777D01*
G03Y576833I-222J333D01*
G02X79667Y578777I777J1167D01*
G03X80333I333J222D01*
G02X82277Y576833I1167J-777D01*
G03Y576167I222J-333D01*
G02X80333Y574223I-777J-1167D01*
G03X79667I-333J-222D01*
G37*
G36*
G01X1304167Y575223D02*
G02X1302223Y577167I-1167J777D01*
G03Y577833I-222J333D01*
G02X1304167Y579777I777J1167D01*
G03X1304833I333J222D01*
G02X1306777Y577833I1167J-777D01*
G03Y577167I222J-333D01*
G02X1304833Y575223I-777J-1167D01*
G03X1304167I-333J-222D01*
G37*
G36*
G01X1935503Y577183D02*
G02X1935270Y578606I-1303J517D01*
G03X1935947Y578717I305J259D01*
G02X1936180Y577294I1303J-517D01*
G03X1935503Y577183I-305J-259D01*
G37*
G36*
G01X1383529Y580052D02*
G02X1381918Y580375I-1029J-952D01*
G03X1382045Y581011I-166J364D01*
G02X1383656Y580688I1029J952D01*
G03X1383529Y580052I166J-364D01*
G37*
G36*
G01X1780237Y580693D02*
G02X1778686Y580641I-736J-1193D01*
G03X1778663Y581307I-233J325D01*
G02X1778490Y583566I737J1193D01*
G03X1778401Y584232I-260J304D01*
G02X1778223Y586667I599J1268D01*
G03Y587333I-222J333D01*
G02X1779777I777J1167D01*
G03Y586667I222J-333D01*
G02X1779910Y584434I-777J-1167D01*
G03X1779999Y583768I260J-304D01*
G02X1780214Y581359I-599J-1268D01*
G03X1780237Y580693I233J-325D01*
G37*
G36*
G01X1431862Y580346D02*
G02X1429326Y580244I-1292J544D01*
G03X1428644Y580290I-355J-185D01*
G02X1428744Y581746I-1144J810D01*
G03X1429426Y581700I355J185D01*
G02X1431246Y582118I1144J-810D01*
G03X1431808Y582314I193J350D01*
G02X1432046Y582695I1293J-543D01*
G03X1431933Y583312I-301J264D01*
G02X1433644Y583625I658J1238D01*
G03X1433757Y583008I301J-264D01*
G02X1432424Y580542I-657J-1238D01*
G03X1431862Y580346I-193J-350D01*
G37*
G36*
G01X723628Y580068D02*
G02Y581732I-1128J832D01*
G03X724272I322J238D01*
G02Y580068I1128J-832D01*
G03X723628I-322J-238D01*
G37*
G36*
G01X1283571Y582011D02*
G02X1281629I-971J-1011D01*
G03Y582589I-277J289D01*
G02X1282579Y585002I971J1011D01*
G03X1282872Y585667I-6J400D01*
G02X1284548Y584343I4531J4012D01*
G03X1283969Y583904I-188J-353D01*
G02X1283571Y582589I-1369J-303D01*
G03Y582011I277J-289D01*
G37*
G36*
G01X72667Y581223D02*
G02Y582777I-1167J777D01*
G03X73333I333J222D01*
G02Y581223I1167J-777D01*
G03X72667I-333J-222D01*
G37*
G36*
G01X79667D02*
G02Y582777I-1167J777D01*
G03X80333I333J222D01*
G02Y581223I1167J-777D01*
G03X79667I-333J-222D01*
G37*
G36*
G01X1793330Y584687D02*
G02X1792007Y585292I-1160J-787D01*
G03X1792292Y585914I-46J398D01*
G02X1793615Y585309I1160J787D01*
G03X1793330Y584687I46J-398D01*
G37*
G36*
G01X1857775Y587634D02*
G02X1856700Y586776I225J-1384D01*
G03X1856265Y587320I-371J149D01*
G02X1857340Y588178I-225J1384D01*
G03X1857775Y587634I371J-149D01*
G37*
G36*
G01X1739937Y587832D02*
G02X1738234Y587102I-437J-1332D01*
G03X1737997Y587654I-361J172D01*
G02X1737778Y587747I437J1332D01*
G03X1737239Y587582I-186J-354D01*
G02X1736659Y589483I-1236J662D01*
G03X1737198Y589648I186J354D01*
G02X1738077Y590342I1236J-662D01*
G03X1738243Y591026I-101J387D01*
G02X1738719Y593394I936J1044D01*
G03X1738961Y593916I-131J378D01*
G02X1738950Y594891I1309J502D01*
G03X1738715Y595400I-377J135D01*
G02X1740531Y596239I496J1311D01*
G03X1740766Y595730I377J-135D01*
G02X1740730Y593095I-496J-1311D01*
G03X1740488Y592573I131J-378D01*
G02X1739536Y590714I-1309J-503D01*
G03X1739370Y590030I101J-387D01*
G02X1739700Y588384I-936J-1044D01*
G03X1739937Y587832I361J-172D01*
G37*
G36*
G01X1399147Y586309D02*
G02X1397189Y588243I-1167J777D01*
G03X1397195Y588899I-226J330D01*
G02X1396711Y589513I815J1141D01*
G03X1396056Y589644I-371J-151D01*
G02X1396359Y591157I-996J986D01*
G03X1397014Y591026I371J151D01*
G02X1399282Y590629I996J-986D01*
G03X1399942Y590528I363J168D01*
G02X1401990Y588613I1038J-942D01*
G03Y588059I288J-277D01*
G02X1399813Y586309I-1010J-972D01*
G03X1399147I-333J-222D01*
G37*
G36*
G01X1821030Y593534D02*
G02X1820316Y595039I-1376J269D01*
G03X1820897Y595315I189J353D01*
G02X1821611Y593810I1376J-269D01*
G03X1821030Y593534I-189J-353D01*
G37*
G36*
G01X1938781Y595545D02*
G02X1937060Y595624I-911J-1065D01*
G03X1937089Y596255I-231J327D01*
G02X1938810Y596176I911J1065D01*
G03X1938781Y595545I231J-327D01*
G37*
G36*
G01X1444034Y596099D02*
G02X1442396Y595368I-380J-1350D01*
G03X1442145Y595929I-359J176D01*
G02X1442075Y598607I380J1350D01*
G03X1442286Y599198I-128J379D01*
G02X1443923Y598616I1187J746D01*
G03X1443712Y598025I128J-379D01*
G02X1443783Y596660I-1187J-746D01*
G03X1444034Y596099I359J-176D01*
G37*
G36*
G01X64667Y595223D02*
G02X62723Y597167I-1167J777D01*
G03Y597833I-222J333D01*
G02Y600167I777J1167D01*
G03Y600833I-222J333D01*
G02X64667Y602777I777J1167D01*
G03X65333I333J222D01*
G02X67667I1167J-777D01*
G03X68333I333J222D01*
G02X70667I1167J-777D01*
G03X71333I333J222D01*
G02X73667I1167J-777D01*
G03X74333I333J222D01*
G02X76667I1167J-777D01*
G03X77333I333J222D01*
G02X79667I1167J-777D01*
G03X80333I333J222D01*
G02X82277Y600833I1167J-777D01*
G03Y600167I222J-333D01*
G02Y597833I-777J-1167D01*
G03Y597167I222J-333D01*
G02X80333Y595223I-777J-1167D01*
G03X79667I-333J-222D01*
G02X77333I-1167J777D01*
G03X76667I-333J-222D01*
G02X74333I-1167J777D01*
G03X73667I-333J-222D01*
G02X71333I-1167J777D01*
G03X70667I-333J-222D01*
G02X68333I-1167J777D01*
G03X67667I-333J-222D01*
G02X65333I-1167J777D01*
G03X64667I-333J-222D01*
G37*
G36*
G01X124524Y603427D02*
X124453Y603367D01*
Y603074D01*
X124722D01*
Y595972D01*
X122518D01*
Y603074D01*
X122787D01*
Y603367D01*
X122716Y603427D01*
G02X124524I904J1072D01*
G37*
G36*
G01X131217D02*
X131146Y603367D01*
Y603074D01*
X131414D01*
Y595972D01*
X129212D01*
Y603074D01*
X129480D01*
Y603367D01*
X129409Y603427D01*
G02X131217I904J1072D01*
G37*
G36*
G01X147949D02*
X147878Y603367D01*
Y603074D01*
X148146D01*
Y595972D01*
X145944D01*
Y603074D01*
X146212D01*
Y603367D01*
X146141Y603427D01*
G02X147949I904J1072D01*
G37*
G36*
G01X154642D02*
X154571Y603367D01*
Y603074D01*
X154840D01*
Y595972D01*
X152636D01*
Y603074D01*
X152905D01*
Y603367D01*
X152834Y603427D01*
G02X154642I904J1072D01*
G37*
G36*
G01X161335D02*
X161264Y603367D01*
Y603074D01*
X161532D01*
Y595972D01*
X159330D01*
Y603074D01*
X159598D01*
Y603367D01*
X159527Y603427D01*
G02X161335I904J1072D01*
G37*
G36*
G01X168028D02*
X167957Y603367D01*
Y603074D01*
X168226D01*
Y595972D01*
X166022D01*
Y603074D01*
X166291D01*
Y603367D01*
X166220Y603427D01*
G02X168028I904J1072D01*
G37*
G36*
G01X184760D02*
X184689Y603367D01*
Y603074D01*
X184958D01*
Y595972D01*
X182754D01*
Y603074D01*
X183023D01*
Y603367D01*
X182952Y603427D01*
G02X184760I904J1072D01*
G37*
G36*
G01X191453D02*
X191382Y603367D01*
Y603074D01*
X191650D01*
Y595972D01*
X189448D01*
Y603074D01*
X189716D01*
Y603367D01*
X189645Y603427D01*
G02X191453I904J1072D01*
G37*
G36*
G01X198146D02*
X198075Y603367D01*
Y603074D01*
X198344D01*
Y595972D01*
X196140D01*
Y603074D01*
X196409D01*
Y603367D01*
X196338Y603427D01*
G02X198146I904J1072D01*
G37*
G36*
G01X204839D02*
X204768Y603367D01*
Y603074D01*
X205036D01*
Y595972D01*
X202834D01*
Y603074D01*
X203102D01*
Y603367D01*
X203031Y603427D01*
G02X204839I904J1072D01*
G37*
G36*
G01X221571D02*
X221500Y603367D01*
Y603074D01*
X221768D01*
Y595972D01*
X219566D01*
Y603074D01*
X219834D01*
Y603367D01*
X219763Y603427D01*
G02X221571I904J1072D01*
G37*
G36*
G01X228264D02*
X228193Y603367D01*
Y603074D01*
X228462D01*
Y595972D01*
X226258D01*
Y603074D01*
X226527D01*
Y603367D01*
X226456Y603427D01*
G02X228264I904J1072D01*
G37*
G36*
G01X234957D02*
X234886Y603367D01*
Y603074D01*
X235154D01*
Y595972D01*
X232952D01*
Y603074D01*
X233220D01*
Y603367D01*
X233149Y603427D01*
G02X234957I904J1072D01*
G37*
G36*
G01X241650D02*
X241579Y603367D01*
Y603074D01*
X241848D01*
Y595972D01*
X239644D01*
Y603074D01*
X239913D01*
Y603367D01*
X239842Y603427D01*
G02X241650I904J1072D01*
G37*
G36*
G01X258382D02*
X258311Y603367D01*
Y603074D01*
X258580D01*
Y595972D01*
X256376D01*
Y603074D01*
X256645D01*
Y603367D01*
X256574Y603427D01*
G02X258382I904J1072D01*
G37*
G36*
G01X265075D02*
X265004Y603367D01*
Y603074D01*
X265272D01*
Y595972D01*
X263070D01*
Y603074D01*
X263338D01*
Y603367D01*
X263267Y603427D01*
G02X265075I904J1072D01*
G37*
G36*
G01X271768D02*
X271697Y603367D01*
Y603074D01*
X271966D01*
Y595972D01*
X269762D01*
Y603074D01*
X270031D01*
Y603367D01*
X269960Y603427D01*
G02X271768I904J1072D01*
G37*
G36*
G01X278461D02*
X278390Y603367D01*
Y603074D01*
X278658D01*
Y595972D01*
X276456D01*
Y603074D01*
X276724D01*
Y603367D01*
X276653Y603427D01*
G02X278461I904J1072D01*
G37*
G36*
G01X295193D02*
X295122Y603367D01*
Y603074D01*
X295390D01*
Y595972D01*
X293188D01*
Y603074D01*
X293456D01*
Y603367D01*
X293385Y603427D01*
G02X295193I904J1072D01*
G37*
G36*
G01X301886D02*
X301815Y603367D01*
Y603074D01*
X302084D01*
Y595972D01*
X299882D01*
Y603074D01*
X300149D01*
Y603367D01*
X300078Y603427D01*
G02X301886I904J1072D01*
G37*
G36*
G01X452477D02*
X452406Y603367D01*
Y603074D01*
X452674D01*
Y595972D01*
X450470D01*
Y603074D01*
X450740D01*
Y603367D01*
X450669Y603427D01*
G02X452477I904J1072D01*
G37*
G36*
G01X459170D02*
X459099Y603367D01*
Y603074D01*
X459366D01*
Y595972D01*
X457164D01*
Y603074D01*
X457433D01*
Y603367D01*
X457362Y603427D01*
G02X459170I904J1072D01*
G37*
G36*
G01X475902D02*
X475831Y603367D01*
Y603074D01*
X476100D01*
Y595972D01*
X473896D01*
Y603074D01*
X474165D01*
Y603367D01*
X474094Y603427D01*
G02X475902I904J1072D01*
G37*
G36*
G01X482595D02*
X482524Y603367D01*
Y603074D01*
X482792D01*
Y595972D01*
X480590D01*
Y603074D01*
X480858D01*
Y603367D01*
X480787Y603427D01*
G02X482595I904J1072D01*
G37*
G36*
G01X489288D02*
X489217Y603367D01*
Y603074D01*
X489484D01*
Y595972D01*
X487282D01*
Y603074D01*
X487551D01*
Y603367D01*
X487480Y603427D01*
G02X489288I904J1072D01*
G37*
G36*
G01X495981D02*
X495910Y603367D01*
Y603074D01*
X496178D01*
Y595972D01*
X493974D01*
Y603074D01*
X494244D01*
Y603367D01*
X494173Y603427D01*
G02X495981I904J1072D01*
G37*
G36*
G01X512713D02*
X512642Y603367D01*
Y603074D01*
X512910D01*
Y595972D01*
X510708D01*
Y603074D01*
X510976D01*
Y603367D01*
X510905Y603427D01*
G02X512713I904J1072D01*
G37*
G36*
G01X519406D02*
X519335Y603367D01*
Y603074D01*
X519604D01*
Y595972D01*
X517400D01*
Y603074D01*
X517669D01*
Y603367D01*
X517598Y603427D01*
G02X519406I904J1072D01*
G37*
G36*
G01X526099D02*
X526028Y603367D01*
Y603074D01*
X526296D01*
Y595972D01*
X524092D01*
Y603074D01*
X524362D01*
Y603367D01*
X524291Y603427D01*
G02X526099I904J1072D01*
G37*
G36*
G01X532792D02*
X532721Y603367D01*
Y603074D01*
X532988D01*
Y595972D01*
X530786D01*
Y603074D01*
X531055D01*
Y603367D01*
X530984Y603427D01*
G02X532792I904J1072D01*
G37*
G36*
G01X549524D02*
X549453Y603367D01*
Y603074D01*
X549722D01*
Y595972D01*
X547518D01*
Y603074D01*
X547787D01*
Y603367D01*
X547716Y603427D01*
G02X549524I904J1072D01*
G37*
G36*
G01X556217D02*
X556146Y603367D01*
Y603074D01*
X556414D01*
Y595972D01*
X554212D01*
Y603074D01*
X554480D01*
Y603367D01*
X554409Y603427D01*
G02X556217I904J1072D01*
G37*
G36*
G01X562910D02*
X562839Y603367D01*
Y603074D01*
X563106D01*
Y595972D01*
X560904D01*
Y603074D01*
X561173D01*
Y603367D01*
X561102Y603427D01*
G02X562910I904J1072D01*
G37*
G36*
G01X569603D02*
X569532Y603367D01*
Y603074D01*
X569800D01*
Y595972D01*
X567596D01*
Y603074D01*
X567866D01*
Y603367D01*
X567795Y603427D01*
G02X569603I904J1072D01*
G37*
G36*
G01X586335D02*
X586264Y603367D01*
Y603074D01*
X586532D01*
Y595972D01*
X584330D01*
Y603074D01*
X584598D01*
Y603367D01*
X584527Y603427D01*
G02X586335I904J1072D01*
G37*
G36*
G01X593028D02*
X592957Y603367D01*
Y603074D01*
X593226D01*
Y595972D01*
X591022D01*
Y603074D01*
X591291D01*
Y603367D01*
X591220Y603427D01*
G02X593028I904J1072D01*
G37*
G36*
G01X774132D02*
X774061Y603367D01*
Y603074D01*
X774330D01*
Y595972D01*
X772126D01*
Y603074D01*
X772395D01*
Y603367D01*
X772324Y603427D01*
G02X774132I904J1072D01*
G37*
G36*
G01X780825D02*
X780754Y603367D01*
Y603074D01*
X781022D01*
Y595972D01*
X778820D01*
Y603074D01*
X779088D01*
Y603367D01*
X779017Y603427D01*
G02X780825I904J1072D01*
G37*
G36*
G01X797557D02*
X797486Y603367D01*
Y603074D01*
X797754D01*
Y595972D01*
X795552D01*
Y603074D01*
X795820D01*
Y603367D01*
X795749Y603427D01*
G02X797557I904J1072D01*
G37*
G36*
G01X804250D02*
X804179Y603367D01*
Y603074D01*
X804448D01*
Y595972D01*
X802244D01*
Y603074D01*
X802513D01*
Y603367D01*
X802442Y603427D01*
G02X804250I904J1072D01*
G37*
G36*
G01X810943D02*
X810872Y603367D01*
Y603074D01*
X811140D01*
Y595972D01*
X808938D01*
Y603074D01*
X809206D01*
Y603367D01*
X809135Y603427D01*
G02X810943I904J1072D01*
G37*
G36*
G01X817636D02*
X817565Y603367D01*
Y603074D01*
X817834D01*
Y595972D01*
X815630D01*
Y603074D01*
X815899D01*
Y603367D01*
X815828Y603427D01*
G02X817636I904J1072D01*
G37*
G36*
G01X834368D02*
X834297Y603367D01*
Y603074D01*
X834566D01*
Y595972D01*
X832362D01*
Y603074D01*
X832631D01*
Y603367D01*
X832560Y603427D01*
G02X834368I904J1072D01*
G37*
G36*
G01X841061D02*
X840990Y603367D01*
Y603074D01*
X841258D01*
Y595972D01*
X839056D01*
Y603074D01*
X839324D01*
Y603367D01*
X839253Y603427D01*
G02X841061I904J1072D01*
G37*
G36*
G01X847754D02*
X847683Y603367D01*
Y603074D01*
X847952D01*
Y595972D01*
X845748D01*
Y603074D01*
X846017D01*
Y603367D01*
X845946Y603427D01*
G02X847754I904J1072D01*
G37*
G36*
G01X854447D02*
X854376Y603367D01*
Y603074D01*
X854644D01*
Y595972D01*
X852442D01*
Y603074D01*
X852710D01*
Y603367D01*
X852639Y603427D01*
G02X854447I904J1072D01*
G37*
G36*
G01X871179D02*
X871108Y603367D01*
Y603074D01*
X871376D01*
Y595972D01*
X869174D01*
Y603074D01*
X869442D01*
Y603367D01*
X869371Y603427D01*
G02X871179I904J1072D01*
G37*
G36*
G01X877872D02*
X877801Y603367D01*
Y603074D01*
X878070D01*
Y595972D01*
X875866D01*
Y603074D01*
X876135D01*
Y603367D01*
X876064Y603427D01*
G02X877872I904J1072D01*
G37*
G36*
G01X884565D02*
X884494Y603367D01*
Y603074D01*
X884762D01*
Y595972D01*
X882560D01*
Y603074D01*
X882828D01*
Y603367D01*
X882757Y603427D01*
G02X884565I904J1072D01*
G37*
G36*
G01X891258D02*
X891187Y603367D01*
Y603074D01*
X891456D01*
Y595972D01*
X889252D01*
Y603074D01*
X889521D01*
Y603367D01*
X889450Y603427D01*
G02X891258I904J1072D01*
G37*
G36*
G01X907990D02*
X907919Y603367D01*
Y603074D01*
X908188D01*
Y595972D01*
X905984D01*
Y603074D01*
X906253D01*
Y603367D01*
X906182Y603427D01*
G02X907990I904J1072D01*
G37*
G36*
G01X914683D02*
X914612Y603367D01*
Y603074D01*
X914880D01*
Y595972D01*
X912678D01*
Y603074D01*
X912946D01*
Y603367D01*
X912875Y603427D01*
G02X914683I904J1072D01*
G37*
G36*
G01X921376D02*
X921305Y603367D01*
Y603074D01*
X921574D01*
Y595972D01*
X919370D01*
Y603074D01*
X919639D01*
Y603367D01*
X919568Y603427D01*
G02X921376I904J1072D01*
G37*
G36*
G01X928069D02*
X927998Y603367D01*
Y603074D01*
X928266D01*
Y595972D01*
X926064D01*
Y603074D01*
X926332D01*
Y603367D01*
X926261Y603427D01*
G02X928069I904J1072D01*
G37*
G36*
G01X944801D02*
X944730Y603367D01*
Y603074D01*
X944998D01*
Y595972D01*
X942796D01*
Y603074D01*
X943064D01*
Y603367D01*
X942993Y603427D01*
G02X944801I904J1072D01*
G37*
G36*
G01X951494D02*
X951423Y603367D01*
Y603074D01*
X951692D01*
Y595972D01*
X949490D01*
Y603074D01*
X949757D01*
Y603367D01*
X949686Y603427D01*
G02X951494I904J1072D01*
G37*
G36*
G01X1102085D02*
X1102014Y603367D01*
Y603074D01*
X1102282D01*
Y595972D01*
X1100078D01*
Y603074D01*
X1100348D01*
Y603367D01*
X1100277Y603427D01*
G02X1102085I904J1072D01*
G37*
G36*
G01X1108778D02*
X1108707Y603367D01*
Y603074D01*
X1108974D01*
Y595972D01*
X1106772D01*
Y603074D01*
X1107041D01*
Y603367D01*
X1106970Y603427D01*
G02X1108778I904J1072D01*
G37*
G36*
G01X1125510D02*
X1125439Y603367D01*
Y603074D01*
X1125708D01*
Y595972D01*
X1123504D01*
Y603074D01*
X1123773D01*
Y603367D01*
X1123702Y603427D01*
G02X1125510I904J1072D01*
G37*
G36*
G01X1132203D02*
X1132132Y603367D01*
Y603074D01*
X1132400D01*
Y595972D01*
X1130198D01*
Y603074D01*
X1130466D01*
Y603367D01*
X1130395Y603427D01*
G02X1132203I904J1072D01*
G37*
G36*
G01X1138896D02*
X1138825Y603367D01*
Y603074D01*
X1139092D01*
Y595972D01*
X1136890D01*
Y603074D01*
X1137159D01*
Y603367D01*
X1137088Y603427D01*
G02X1138896I904J1072D01*
G37*
G36*
G01X1145589D02*
X1145518Y603367D01*
Y603074D01*
X1145786D01*
Y595972D01*
X1143582D01*
Y603074D01*
X1143852D01*
Y603367D01*
X1143781Y603427D01*
G02X1145589I904J1072D01*
G37*
G36*
G01X1162321D02*
X1162250Y603367D01*
Y603074D01*
X1162518D01*
Y595972D01*
X1160316D01*
Y603074D01*
X1160584D01*
Y603367D01*
X1160513Y603427D01*
G02X1162321I904J1072D01*
G37*
G36*
G01X1169014D02*
X1168943Y603367D01*
Y603074D01*
X1169212D01*
Y595972D01*
X1167008D01*
Y603074D01*
X1167277D01*
Y603367D01*
X1167206Y603427D01*
G02X1169014I904J1072D01*
G37*
G36*
G01X1175707D02*
X1175636Y603367D01*
Y603074D01*
X1175904D01*
Y595972D01*
X1173700D01*
Y603074D01*
X1173970D01*
Y603367D01*
X1173899Y603427D01*
G02X1175707I904J1072D01*
G37*
G36*
G01X1182400D02*
X1182329Y603367D01*
Y603074D01*
X1182596D01*
Y595972D01*
X1180394D01*
Y603074D01*
X1180663D01*
Y603367D01*
X1180592Y603427D01*
G02X1182400I904J1072D01*
G37*
G36*
G01X1199132D02*
X1199061Y603367D01*
Y603074D01*
X1199330D01*
Y595972D01*
X1197126D01*
Y603074D01*
X1197395D01*
Y603367D01*
X1197324Y603427D01*
G02X1199132I904J1072D01*
G37*
G36*
G01X1205825D02*
X1205754Y603367D01*
Y603074D01*
X1206022D01*
Y595972D01*
X1203820D01*
Y603074D01*
X1204088D01*
Y603367D01*
X1204017Y603427D01*
G02X1205825I904J1072D01*
G37*
G36*
G01X1212518D02*
X1212447Y603367D01*
Y603074D01*
X1212714D01*
Y595972D01*
X1210512D01*
Y603074D01*
X1210781D01*
Y603367D01*
X1210710Y603427D01*
G02X1212518I904J1072D01*
G37*
G36*
G01X1219211D02*
X1219140Y603367D01*
Y603074D01*
X1219408D01*
Y595972D01*
X1217204D01*
Y603074D01*
X1217474D01*
Y603367D01*
X1217403Y603427D01*
G02X1219211I904J1072D01*
G37*
G36*
G01X1235943D02*
X1235872Y603367D01*
Y603074D01*
X1236140D01*
Y595972D01*
X1233938D01*
Y603074D01*
X1234206D01*
Y603367D01*
X1234135Y603427D01*
G02X1235943I904J1072D01*
G37*
G36*
G01X1242636D02*
X1242565Y603367D01*
Y603074D01*
X1242834D01*
Y595972D01*
X1240630D01*
Y603074D01*
X1240899D01*
Y603367D01*
X1240828Y603427D01*
G02X1242636I904J1072D01*
G37*
G36*
G01X1310267Y597723D02*
G02X1308090Y599473I-1167J778D01*
G03Y600027I-288J277D01*
G02X1310267Y601777I1010J972D01*
G03X1310933I333J222D01*
G02X1313267I1167J-777D01*
G03X1313933I333J222D01*
G02X1316267I1167J-777D01*
G03X1316933I333J222D01*
G02X1319267I1167J-777D01*
G03X1319933I333J222D01*
G02X1322110Y600027I1167J-778D01*
G03Y599473I288J-277D01*
G02X1319933Y597723I-1010J-972D01*
G03X1319267I-333J-222D01*
G02X1316933I-1167J777D01*
G03X1316267I-333J-222D01*
G02X1313933I-1167J777D01*
G03X1313267I-333J-222D01*
G02X1310933I-1167J777D01*
G03X1310267I-333J-222D01*
G37*
G36*
G01X1385675Y603929D02*
G02X1384126Y603796I-675J-1229D01*
G03X1384069Y604460I-249J313D01*
G02X1383529Y604989I675J1229D01*
G03X1382964Y605125I-347J-199D01*
G02X1383415Y607000I-764J1175D01*
G03X1383980Y606864I347J199D01*
G02X1385618Y604593I764J-1175D01*
G03X1385675Y603929I249J-313D01*
G37*
G36*
G01X1454689Y602452D02*
G02X1452656Y604378I-1061J916D01*
G03X1452616Y604988I-278J288D01*
G02X1452404Y605181I833J1128D01*
G03X1451798Y605171I-299J-266D01*
G02X1449720Y605084I-1078J896D01*
G03X1449132Y605065I-285J-280D01*
G02X1447003Y605073I-1061J916D01*
G03X1446354Y605016I-304J-259D01*
G02X1446213Y606635I-1209J710D01*
G03X1446862Y606692I304J259D01*
G02X1449071Y606964I1209J-711D01*
G03X1449659Y606983I285J280D01*
G02X1451767Y607000I1061J-916D01*
G03X1452373Y607010I299J266D01*
G02X1454451Y607097I1078J-896D01*
G03X1455039Y607116I285J280D01*
G02X1457072Y605190I1061J-916D01*
G03X1457112Y604580I278J-288D01*
G02X1455277Y602471I-835J-1126D01*
G03X1454689Y602452I-285J-280D01*
G37*
G36*
G01X713077Y605061D02*
G02X711135I-971J-1011D01*
G03Y605639I-277J289D01*
G02X711703Y607993I971J1011D01*
G03X711931Y608582I-115J383D01*
G02X714356Y609989I1201J724D01*
G03X715016Y609932I349J195D01*
G02X714882Y608367I1090J-882D01*
G03X714222Y608424I-349J-195D01*
G02X713535Y607963I-1090J882D01*
G03X713307Y607374I115J-383D01*
G02X713077Y605639I-1201J-724D01*
G03Y605061I277J-289D01*
G37*
G36*
G01X1758833Y605723D02*
G02X1757309Y605002I-283J-1373D01*
G03X1757036Y605580I-354J186D01*
G02X1758560Y606301I283J1373D01*
G03X1758833Y605723I354J-186D01*
G37*
G36*
G01X1921759Y605264D02*
G02X1921707Y603713I1141J-815D01*
G03X1921041Y603736I-341J-210D01*
G02X1921093Y605287I-1141J815D01*
G03X1921759Y605264I341J210D01*
G37*
G36*
G01X1470066Y608965D02*
G02X1468457Y608910I-765J-1175D01*
G03X1468435Y609564I-241J319D01*
G02X1470044Y609619I765J1175D01*
G03X1470066Y608965I241J-319D01*
G37*
G36*
G01X1498208Y611341D02*
G02X1496845Y611026I-408J-1341D01*
G03X1496689Y611702I-272J293D01*
G02X1495870Y612364I407J1342D01*
G03X1495205Y612417I-350J-193D01*
G02X1493487Y612019I-1105J863D01*
G03X1492913Y611675I-174J-360D01*
G02X1492125Y612993I-1401J57D01*
G03X1492699Y613337I174J360D01*
G02X1492859Y613932I1401J-58D01*
G03X1492559Y614514I-354J186D01*
G02X1493991Y615251I191J1389D01*
G03X1494291Y614669I354J-186D01*
G02X1495327Y613959I-191J-1389D01*
G03X1495992Y613906I350J193D01*
G02X1498052Y612017I1105J-862D01*
G03X1498208Y611341I272J-293D01*
G37*
G36*
G01X730778Y610078D02*
G02X728540Y609964I-1162J785D01*
G03X727928Y609966I-307J-256D01*
G02X727933Y611770I-1071J905D01*
G03X728545Y611768I307J256D01*
G02X730698Y611754I1071J-905D01*
G03X731338Y611785I308J255D01*
G02X731418Y610109I1162J-784D01*
G03X730778Y610078I-308J-255D01*
G37*
G36*
G01X1701138Y618388D02*
G02X1700272Y616314I4633J-3152D01*
G03X1699708Y616752I-392J77D01*
G02X1700430Y618481I-602J1266D01*
G03X1701138Y618388I377J132D01*
G37*
G36*
G01X79667Y611223D02*
G02Y612777I-1167J777D01*
G03X80333I333J222D01*
G02Y611223I1167J-777D01*
G03X79667I-333J-222D01*
G37*
G36*
G01X121003Y613438D02*
G02X119172Y613786I-1111J-855D01*
G01Y621184D01*
X121374D01*
Y614082D01*
X121320D01*
G03X121003Y613438I0J-400D01*
G37*
G36*
G01X770611D02*
G02X768780Y613786I-1111J-855D01*
G01Y621184D01*
X770982D01*
Y614082D01*
X770928D01*
G03X770611Y613438I0J-400D01*
G37*
G36*
G01X70667Y614723D02*
G02Y616277I-1167J777D01*
G03X71333I333J222D01*
G02X73667I1167J-777D01*
G03X74333I333J222D01*
G02X76667I1167J-777D01*
G03X77333I333J222D01*
G02X79667I1167J-777D01*
G03X80333I333J222D01*
G02Y614723I1167J-777D01*
G03X79667I-333J-222D01*
G02X77333I-1167J777D01*
G03X76667I-333J-222D01*
G02X74333I-1167J777D01*
G03X73667I-333J-222D01*
G02X71333I-1167J777D01*
G03X70667I-333J-222D01*
G37*
G36*
G01X1471710Y617638D02*
G02X1469044Y617506I-1354J362D01*
G03X1468485Y617720I-374J-141D01*
G02X1469151Y619458I-646J1244D01*
G03X1469710Y619244I374J141D01*
G02X1471006Y619242I646J-1244D01*
G03X1471578Y619493I185J355D01*
G02X1474057Y619968I1354J-362D01*
G03X1474712Y619987I321J239D01*
G02X1476871Y620212I1171J-770D01*
G03X1477451Y620231I281J284D01*
G02X1479164Y620535I1049J-931D01*
G03X1479714Y620712I190J352D01*
G02X1482272Y620633I1261J-612D01*
G03X1482783Y620411I370J152D01*
G02X1481982Y618567I496J-1311D01*
G03X1481471Y618789I-370J-152D01*
G02X1480311Y618865I-497J1311D01*
G03X1479761Y618688I-190J-352D01*
G02X1477512Y618305I-1261J612D01*
G03X1476932Y618286I-281J-284D01*
G02X1474758Y618380I-1049J931D01*
G03X1474103Y618361I-321J-239D01*
G02X1472282Y617889I-1171J770D01*
G03X1471710Y617638I-185J-355D01*
G37*
G36*
G01X92682Y618956D02*
G02X92719Y617218I1118J-846D01*
G03X92131Y617249I-308J-255D01*
G02X89762Y618451I-981J1001D01*
G03X89365Y618908I-396J57D01*
G02X88156Y619592I-5J1402D01*
G03X87461Y619579I-344J-205D01*
G02X87434Y620968I-1231J671D01*
G03X88129Y620981I344J205D01*
G02X90158Y621463I1231J-671D01*
G03X90734Y621594I228J328D01*
G02X92499Y619609I1218J-694D01*
G03X92321Y619021I156J-368D01*
G02X92351Y618974I-1167J-778D01*
G03X92682Y618956I172J103D01*
G37*
G36*
G01X1778267Y620296D02*
G02X1777054Y619294I133J-1396D01*
G03X1776633Y619804I-384J112D01*
G02X1777846Y620806I-133J1396D01*
G03X1778267Y620296I384J-112D01*
G37*
G36*
G01X1517373Y618790D02*
G02X1515315Y618912I-973J1010D01*
G03X1514716Y618934I-309J-254D01*
G02X1512666Y618953I-1016J966D01*
G03X1512112Y618988I-295J-270D01*
G02X1510259Y619021I-908J1068D01*
G03X1509670Y618966I-269J-296D01*
G02X1507346Y619092I-1120J844D01*
G03X1506708Y619159I-344J-204D01*
G02X1506883Y620829I-1029J952D01*
G03X1507521Y620762I344J204D01*
G02X1509495Y620845I1029J-952D01*
G03X1510084Y620900I269J296D01*
G02X1512238Y621003I1120J-844D01*
G03X1512792Y620968I295J270D01*
G02X1514785Y620788I908J-1068D01*
G03X1515384Y620766I309J254D01*
G02X1517373Y620810I1016J-966D01*
G03X1517927I277J288D01*
G02Y618790I973J-1010D01*
G03X1517373I-277J-288D01*
G37*
G36*
G01X1322260Y281218D02*
X1318751D01*
G02Y284242I0J1512D01*
G01X1322261D01*
G02X1323772Y282740I-1J-1512D01*
G01Y282645D01*
X1323762Y282561D01*
G02X1323058Y281447I-1502J170D01*
G03X1323004Y281396I108J-168D01*
G02X1322837Y281316I-160J120D01*
G03X1322763Y281305I-8J-200D01*
G02X1322260Y281218I-505J1425D01*
G37*
G36*
G01X1323733Y281174D02*
X1327244D01*
G02X1328422Y280609I0J-1511D01*
G03X1329023Y280584I311J251D01*
G02X1328993Y278685I1016J-966D01*
G03X1328390Y278679I-299J-266D01*
G02X1327243Y278152I-1147J984D01*
G01X1323734D01*
G02X1322936Y280946I0J1511D01*
G03X1322990Y280997I-108J168D01*
G02X1323157Y281077I160J-120D01*
G03X1323231Y281088I8J200D01*
G02X1323733Y281174I503J-1425D01*
G37*
G36*
G01X45416Y305233D02*
X49498Y309315D01*
Y334789D01*
X51703Y336994D01*
X51673Y337106D01*
G02X52942Y338875I1352J370D01*
G03X53248Y339502I-23J399D01*
G02X55802Y340299I1152J798D01*
G03X56224Y339900I400J0D01*
G02X56848Y339790I75J-1400D01*
G01X56886Y339774D01*
X58444D01*
G02X60460I1008J-974D01*
G01X61731D01*
G02X64069I1169J-774D01*
G01X64704D01*
G02X66896I1096J-874D01*
G01X67992D01*
G02X70008I1008J-974D01*
G01X70992D01*
G02X73008I1008J-974D01*
G01X73746D01*
G02X75854I1054J-924D01*
G01X81179D01*
G03X81472Y340446I0J400D01*
G02X83528I1028J954D01*
G03X83821Y339774I293J-272D01*
G01X93342D01*
X98502Y334615D01*
Y273848D01*
X93096Y268442D01*
X78260D01*
G03X77977Y267760I0J-400D01*
G01X79085Y266652D01*
Y222979D01*
X75275Y219169D01*
X51334D01*
X51318Y219185D01*
X44891D01*
X44734Y219028D01*
Y197413D01*
X39300Y191980D01*
X11160D01*
X7096Y196043D01*
Y230657D01*
X2126Y235627D01*
Y264825D01*
X8820Y271518D01*
Y338949D01*
X14153Y344282D01*
X40824D01*
X44734Y340373D01*
Y305515D01*
G03X45416Y305233I400J1D01*
G37*
G36*
G01X1498944Y114388D02*
G02X1501966Y114398I1511J0D01*
G01Y110848D01*
X1501957Y110764D01*
G02X1500456Y109422I-1502J169D01*
G03X1500091Y108859I1J-400D01*
G02X1498755Y109691I-1281J-569D01*
G03X1499098Y110267I-16J400D01*
G02X1498944Y110930I1357J665D01*
G01Y114388D01*
G37*
G36*
G01X1464743Y358094D02*
G02X1462744Y358356I-1126J-835D01*
G03X1462816Y358907I-249J313D01*
G02X1462742Y359017I1125J837D01*
G03X1462092Y359067I-343J-206D01*
G02X1461366Y361323I-1076J898D01*
G03X1461851Y361819I100J387D01*
G02X1464431Y361528I1349J381D01*
G03X1464595Y360983I351J-192D01*
G02X1464815Y358645I-653J-1241D01*
G03X1464743Y358094I249J-313D01*
G37*
G36*
G01X1559790Y361274D02*
G02X1558147Y361257I-810J-1144D01*
G03X1558140Y361906I-238J322D01*
G02X1559783Y361923I810J1144D01*
G03X1559790Y361274I238J-322D01*
G37*
G36*
G01X110785Y128096D02*
G02X110826Y129597I-1163J783D01*
G03X111501Y129578I344J205D01*
G02X111460Y128077I1163J-783D01*
G03X110785Y128096I-344J-205D01*
G37*
G36*
G01X118581Y133842D02*
G03X119128Y133859I264J300D01*
G02X121151Y131918I989J-994D01*
G03X121155Y131373I295J-270D01*
G02X119191Y129374I-1017J-965D01*
G03X118646Y129369I-270J-295D01*
G02X116626Y131310I-964J1018D01*
G03X116620Y131843I-301J263D01*
G02X118581Y133842I1032J949D01*
G37*
G36*
G01X357780Y589938D02*
G03Y589367I280J-286D01*
G02X355816I-982J-1001D01*
G03Y589938I-280J285D01*
G02X357780I982J1001D01*
G37*
G36*
G01X363196Y584806D02*
G03X362587I-305J-258D01*
G02Y586622I-1069J908D01*
G03X363196I305J258D01*
G02Y584806I1069J-908D01*
G37*
G36*
G01X358734Y571001D02*
G03Y570446I288J-278D01*
G02X356714I-1010J-972D01*
G03Y571001I-288J277D01*
G02X358734I1010J972D01*
G37*
G36*
G01X358510Y552100D02*
G03Y551522I277J-289D01*
G02X356568I-971J-1011D01*
G03Y552100I-277J289D01*
G02X358510I971J1011D01*
G37*
G36*
G01X363196Y547006D02*
G03X362587I-305J-258D01*
G02Y548822I-1069J908D01*
G03X363196I305J258D01*
G02Y547006I1069J-908D01*
G37*
G36*
G01X375837Y544726D02*
G03X375845Y545304I-272J293D01*
G02X377784Y545277I984J999D01*
G03X377776Y544699I272J-293D01*
G02X375837Y544726I-984J-999D01*
G37*
G36*
G01X358688Y533045D02*
G03Y532501I293J-272D01*
G02X356634I-1027J-955D01*
G03Y533045I-293J272D01*
G02X358688I1027J955D01*
G37*
G36*
G01X376202Y517883D02*
G03Y517329I288J-277D01*
G02X374182I-1010J-973D01*
G03Y517883I-288J277D01*
G02X376202I1010J973D01*
G37*
G36*
G01X362680Y516142D02*
G03X363262Y516132I296J269D01*
G02X363227Y514210I1003J-980D01*
G03X362645Y514220I-296J-269D01*
G02X362680Y516142I-1003J980D01*
G37*
G36*
G01X363196Y509206D02*
G03X362587I-305J-258D01*
G02Y511022I-1069J908D01*
G03X363196I305J258D01*
G02Y509206I1069J-908D01*
G37*
G36*
G01X402210Y614082D02*
Y613789D01*
X402281Y613729D01*
G02X400471I-905J-1071D01*
G01X400542Y613789D01*
Y614082D01*
X400274D01*
Y621184D01*
X402478D01*
Y614082D01*
X402210D01*
G37*
G36*
G01X435673D02*
Y613789D01*
X435744Y613729D01*
G02X433936I-904J-1072D01*
G01X434007Y613789D01*
Y614082D01*
X433738D01*
Y621184D01*
X435942D01*
Y614082D01*
X435673D01*
G37*
G36*
G01X428980D02*
Y613789D01*
X429051Y613729D01*
G02X427243I-904J-1072D01*
G01X427314Y613789D01*
Y614082D01*
X427046D01*
Y621184D01*
X429248D01*
Y614082D01*
X428980D01*
G37*
G36*
G01X415594D02*
Y613789D01*
X415665Y613729D01*
G02X413857I-904J-1072D01*
G01X413928Y613789D01*
Y614082D01*
X413660D01*
Y621184D01*
X415864D01*
Y614082D01*
X415594D01*
G37*
G36*
G01X395515D02*
Y613789D01*
X395586Y613729D01*
G02X393778I-904J-1072D01*
G01X393849Y613789D01*
Y614082D01*
X393582D01*
Y621184D01*
X395784D01*
Y614082D01*
X395515D01*
G37*
G36*
G01X334980D02*
Y613760D01*
X335088Y613704D01*
G02X333806I-641J-1247D01*
G01X333914Y613760D01*
Y614082D01*
X333346D01*
Y621184D01*
X335548D01*
Y614082D01*
X334980D01*
G37*
G36*
G01X328287D02*
Y613760D01*
X328395Y613704D01*
G02X327113I-641J-1247D01*
G01X327221Y613760D01*
Y614082D01*
X326652D01*
Y621184D01*
X328856D01*
Y614082D01*
X328287D01*
G37*
G36*
G01X355476Y613388D02*
G02X353574I-951J-1030D01*
G03X353424Y614063I-272J294D01*
G01Y621184D01*
X355626D01*
Y614063D01*
G03X355476Y613388I122J-381D01*
G37*
G36*
G01X348784D02*
G02X346882I-951J-1031D01*
G03X346732Y614063I-271J294D01*
G01Y621184D01*
X348934D01*
Y614063D01*
G03X348784Y613388I121J-381D01*
G37*
G36*
G01X373176Y612291D02*
G02X372642Y611067I863J-1105D01*
G03X371997Y611348I-398J-34D01*
G02X372531Y612572I-863J1105D01*
G03X373176Y612291I398J34D01*
G37*
G36*
G01X445982Y595972D02*
X443778D01*
Y603074D01*
X444201D01*
Y603382D01*
X444111Y603442D01*
G02X445649I769J1172D01*
G01X445559Y603382D01*
Y603074D01*
X445982D01*
Y595972D01*
G37*
G36*
G01X439288D02*
X437086D01*
Y603074D01*
X437508D01*
Y603382D01*
X437418Y603442D01*
G02X438956I769J1172D01*
G01X438866Y603382D01*
Y603074D01*
X439288D01*
Y595972D01*
G37*
G36*
G01X432596D02*
X430392D01*
Y603074D01*
X430661D01*
Y603367D01*
X430590Y603427D01*
G02X432398I904J1072D01*
G01X432327Y603367D01*
Y603074D01*
X432596D01*
Y595972D01*
G37*
G36*
G01X425902D02*
X423700D01*
Y603074D01*
X424122D01*
Y603382D01*
X424032Y603442D01*
G02X425570I769J1172D01*
G01X425480Y603382D01*
Y603074D01*
X425902D01*
Y595972D01*
G37*
G36*
G01X405824D02*
X403620D01*
Y603074D01*
X403889D01*
Y603367D01*
X403818Y603427D01*
G02X405626I904J1072D01*
G01X405555Y603367D01*
Y603074D01*
X405824D01*
Y595972D01*
G37*
G36*
G01X399130D02*
X396928D01*
Y603074D01*
X397196D01*
Y603367D01*
X397125Y603427D01*
G02X398933I904J1072D01*
G01X398862Y603367D01*
Y603074D01*
X399130D01*
Y595972D01*
G37*
G36*
G01X365666D02*
X363464D01*
Y603074D01*
X363886D01*
Y603382D01*
X363796Y603442D01*
G02X365334I769J1172D01*
G01X365244Y603382D01*
Y603074D01*
X365666D01*
Y595972D01*
G37*
G36*
G01X362320D02*
X360116D01*
Y603074D01*
X360539D01*
Y603382D01*
X360449Y603442D01*
G02X361987I769J1172D01*
G01X361897Y603382D01*
Y603074D01*
X362320D01*
Y595972D01*
G37*
G36*
G01X352280D02*
X350078D01*
Y603074D01*
X350346D01*
Y603367D01*
X350275Y603427D01*
G02X352083I904J1072D01*
G01X352012Y603367D01*
Y603074D01*
X352280D01*
Y595972D01*
G37*
G36*
G01X345588D02*
X343384D01*
Y603074D01*
X343807D01*
Y603382D01*
X343717Y603442D01*
G02X345255I769J1172D01*
G01X345165Y603382D01*
Y603074D01*
X345588D01*
Y595972D01*
G37*
G36*
G01X332202D02*
X329998D01*
Y603074D01*
X330421D01*
Y603382D01*
X330331Y603442D01*
G02X331869I769J1172D01*
G01X331779Y603382D01*
Y603074D01*
X332202D01*
Y595972D01*
G37*
G36*
G01X325508D02*
X323306D01*
Y603074D01*
X323574D01*
Y603367D01*
X323503Y603427D01*
G02X325311I904J1072D01*
G01X325240Y603367D01*
Y603074D01*
X325508D01*
Y595972D01*
G37*
G36*
G01X375160Y594586D02*
G02X375066Y592831I1044J-936D01*
G03X374444Y592864I-324J-234D01*
G02X372370Y592849I-1044J936D01*
G03X371761Y592825I-294J-271D01*
G02X371689Y594642I-1102J866D01*
G03X372298Y594666I294J271D01*
G02X374538Y594619I1102J-866D01*
G03X375160Y594586I324J234D01*
G37*
G36*
G01X445583Y576282D02*
Y575976D01*
X445671Y575916D01*
G02X444093I-789J-1159D01*
G01X444181Y575976D01*
Y576282D01*
X443778D01*
Y583384D01*
X445982D01*
Y576282D01*
X445583D01*
G37*
G36*
G01X438890D02*
Y575976D01*
X438978Y575916D01*
G02X437400I-789J-1159D01*
G01X437488Y575976D01*
Y576282D01*
X437086D01*
Y583384D01*
X439288D01*
Y576282D01*
X438890D01*
G37*
G36*
G01X435543D02*
Y575976D01*
X435631Y575916D01*
G02X434053I-789J-1159D01*
G01X434141Y575976D01*
Y576282D01*
X433738D01*
Y583384D01*
X435942D01*
Y576282D01*
X435543D01*
G37*
G36*
G01X428850D02*
Y575976D01*
X428938Y575916D01*
G02X427360I-789J-1159D01*
G01X427448Y575976D01*
Y576282D01*
X427046D01*
Y583384D01*
X429248D01*
Y576282D01*
X428850D01*
G37*
G36*
G01X415464D02*
Y575976D01*
X415552Y575916D01*
G02X413974I-789J-1159D01*
G01X414062Y575976D01*
Y576282D01*
X413660D01*
Y583384D01*
X415864D01*
Y576282D01*
X415464D01*
G37*
G36*
G01X405424D02*
Y575976D01*
X405512Y575916D01*
G02X403934I-789J-1159D01*
G01X404022Y575976D01*
Y576282D01*
X403620D01*
Y583384D01*
X405824D01*
Y576282D01*
X405424D01*
G37*
G36*
G01X402078D02*
Y575976D01*
X402166Y575916D01*
G02X400588I-789J-1159D01*
G01X400676Y575976D01*
Y576282D01*
X400274D01*
Y583384D01*
X402478D01*
Y576282D01*
X402078D01*
G37*
G36*
G01X395385D02*
Y575976D01*
X395473Y575916D01*
G02X393895I-789J-1159D01*
G01X393983Y575976D01*
Y576282D01*
X393582D01*
Y583384D01*
X395784D01*
Y576282D01*
X395385D01*
G37*
G36*
G01X355227D02*
Y575976D01*
X355315Y575916D01*
G02X353737I-789J-1159D01*
G01X353825Y575976D01*
Y576282D01*
X353424D01*
Y583384D01*
X355626D01*
Y576282D01*
X355227D01*
G37*
G36*
G01X348534D02*
Y575976D01*
X348622Y575916D01*
G02X347044I-789J-1159D01*
G01X347132Y575976D01*
Y576282D01*
X346732D01*
Y583384D01*
X348934D01*
Y576282D01*
X348534D01*
G37*
G36*
G01X345187D02*
Y575976D01*
X345275Y575916D01*
G02X343697I-789J-1159D01*
G01X343785Y575976D01*
Y576282D01*
X343384D01*
Y583384D01*
X345588D01*
Y576282D01*
X345187D01*
G37*
G36*
G01X338494D02*
Y575976D01*
X338582Y575916D01*
G02X337004I-789J-1159D01*
G01X337092Y575976D01*
Y576282D01*
X336692D01*
Y583384D01*
X338894D01*
Y576282D01*
X338494D01*
G37*
G36*
G01X335148D02*
Y575976D01*
X335236Y575916D01*
G02X333658I-789J-1159D01*
G01X333746Y575976D01*
Y576282D01*
X333346D01*
Y583384D01*
X335548D01*
Y576282D01*
X335148D01*
G37*
G36*
G01X328455D02*
Y575976D01*
X328543Y575916D01*
G02X326965I-789J-1159D01*
G01X327053Y575976D01*
Y576282D01*
X326652D01*
Y583384D01*
X328856D01*
Y576282D01*
X328455D01*
G37*
G36*
G01X325108D02*
Y575976D01*
X325196Y575916D01*
G02X323618I-789J-1159D01*
G01X323706Y575976D01*
Y576282D01*
X323306D01*
Y583384D01*
X325508D01*
Y576282D01*
X325108D01*
G37*
G36*
G01X311722D02*
Y575976D01*
X311810Y575916D01*
G02X310232I-789J-1159D01*
G01X310320Y575976D01*
Y576282D01*
X309920D01*
Y583384D01*
X312122D01*
Y576282D01*
X311722D01*
G37*
G36*
G01X365244D02*
Y575974D01*
X365334Y575914D01*
G02X363796I-769J-1172D01*
G01X363886Y575974D01*
Y576282D01*
X363464D01*
Y583384D01*
X365666D01*
Y576282D01*
X365244D01*
G37*
G36*
G01X361897D02*
Y575974D01*
X361987Y575914D01*
G02X360449I-769J-1172D01*
G01X360539Y575974D01*
Y576282D01*
X360116D01*
Y583384D01*
X362320D01*
Y576282D01*
X361897D01*
G37*
G36*
G01X445982Y558172D02*
X443778D01*
Y565274D01*
X444214D01*
Y565584D01*
X444122Y565643D01*
G02X445638I758J1179D01*
G01X445546Y565584D01*
Y565274D01*
X445982D01*
Y558172D01*
G37*
G36*
G01X439288D02*
X437086D01*
Y565274D01*
X437523D01*
Y565584D01*
X437431Y565643D01*
G02X438947I758J1179D01*
G01X438855Y565584D01*
Y565274D01*
X439288D01*
Y558172D01*
G37*
G36*
G01X432596D02*
X430392D01*
Y565274D01*
X430805D01*
Y565581D01*
X430716Y565641D01*
G02X432272I778J1166D01*
G01X432183Y565581D01*
Y565274D01*
X432596D01*
Y558172D01*
G37*
G36*
G01X425902D02*
X423700D01*
Y565274D01*
X424112D01*
Y565581D01*
X424023Y565641D01*
G02X425579I778J1166D01*
G01X425490Y565581D01*
Y565274D01*
X425902D01*
Y558172D01*
G37*
G36*
G01X422556D02*
X420354D01*
Y565274D01*
X420790D01*
Y565584D01*
X420698Y565643D01*
G02X422214I758J1179D01*
G01X422122Y565584D01*
Y565274D01*
X422556D01*
Y558172D01*
G37*
G36*
G01X415864D02*
X413660D01*
Y565274D01*
X414097D01*
Y565584D01*
X414005Y565643D01*
G02X415521I758J1179D01*
G01X415429Y565584D01*
Y565274D01*
X415864D01*
Y558172D01*
G37*
G36*
G01X409170D02*
X406968D01*
Y565274D01*
X407380D01*
Y565581D01*
X407291Y565641D01*
G02X408847I778J1166D01*
G01X408758Y565581D01*
Y565274D01*
X409170D01*
Y558172D01*
G37*
G36*
G01X405824D02*
X403620D01*
Y565274D01*
X404057D01*
Y565584D01*
X403965Y565643D01*
G02X405481I758J1179D01*
G01X405389Y565584D01*
Y565274D01*
X405824D01*
Y558172D01*
G37*
G36*
G01X399130D02*
X396928D01*
Y565274D01*
X397340D01*
Y565581D01*
X397251Y565641D01*
G02X398807I778J1166D01*
G01X398718Y565581D01*
Y565274D01*
X399130D01*
Y558172D01*
G37*
G36*
G01X365666D02*
X363464D01*
Y565274D01*
X363886D01*
Y565582D01*
X363796Y565642D01*
G02X365334I769J1172D01*
G01X365244Y565582D01*
Y565274D01*
X365666D01*
Y558172D01*
G37*
G36*
G01X362320D02*
X360116D01*
Y565274D01*
X360539D01*
Y565582D01*
X360449Y565642D01*
G02X361987I769J1172D01*
G01X361897Y565582D01*
Y565274D01*
X362320D01*
Y558172D01*
G37*
G36*
G01X355626D02*
X353424D01*
Y565274D01*
X353859D01*
Y565584D01*
X353767Y565643D01*
G02X355283I758J1179D01*
G01X355191Y565584D01*
Y565274D01*
X355626D01*
Y558172D01*
G37*
G36*
G01X352280D02*
X350078D01*
Y565274D01*
X350513D01*
Y565584D01*
X350421Y565643D01*
G02X351937I758J1179D01*
G01X351845Y565584D01*
Y565274D01*
X352280D01*
Y558172D01*
G37*
G36*
G01X345588D02*
X343384D01*
Y565274D01*
X343820D01*
Y565584D01*
X343728Y565643D01*
G02X345244I758J1179D01*
G01X345152Y565584D01*
Y565274D01*
X345588D01*
Y558172D01*
G37*
G36*
G01X342242D02*
X340038D01*
Y565274D01*
X340474D01*
Y565584D01*
X340382Y565643D01*
G02X341898I758J1179D01*
G01X341806Y565584D01*
Y565274D01*
X342242D01*
Y558172D01*
G37*
G36*
G01X335548D02*
X333346D01*
Y565274D01*
X333767D01*
Y565582D01*
X333677Y565642D01*
G02X335215I769J1172D01*
G01X335125Y565582D01*
Y565274D01*
X335548D01*
Y558172D01*
G37*
G36*
G01X332202D02*
X329998D01*
Y565274D01*
X330421D01*
Y565582D01*
X330331Y565642D01*
G02X331869I769J1172D01*
G01X331779Y565582D01*
Y565274D01*
X332202D01*
Y558172D01*
G37*
G36*
G01X325508D02*
X323306D01*
Y565274D01*
X323728D01*
Y565582D01*
X323638Y565642D01*
G02X325176I769J1172D01*
G01X325086Y565582D01*
Y565274D01*
X325508D01*
Y558172D01*
G37*
G36*
G01X322162D02*
X319960D01*
Y565274D01*
X320382D01*
Y565582D01*
X320292Y565642D01*
G02X321830I769J1172D01*
G01X321740Y565582D01*
Y565274D01*
X322162D01*
Y558172D01*
G37*
G36*
G01X315470D02*
X313266D01*
Y565274D01*
X313689D01*
Y565582D01*
X313599Y565642D01*
G02X315137I769J1172D01*
G01X315047Y565582D01*
Y565274D01*
X315470D01*
Y558172D01*
G37*
G36*
G01X395429Y538482D02*
Y538189D01*
X395500Y538129D01*
G02X393690I-905J-1071D01*
G01X393761Y538189D01*
Y538482D01*
X393582D01*
Y545584D01*
X395784D01*
Y538482D01*
X395429D01*
G37*
G36*
G01X445583D02*
Y538176D01*
X445671Y538116D01*
G02X444093I-789J-1159D01*
G01X444181Y538176D01*
Y538482D01*
X443778D01*
Y545584D01*
X445982D01*
Y538482D01*
X445583D01*
G37*
G36*
G01X438890D02*
Y538176D01*
X438978Y538116D01*
G02X437400I-789J-1159D01*
G01X437488Y538176D01*
Y538482D01*
X437086D01*
Y545584D01*
X439288D01*
Y538482D01*
X438890D01*
G37*
G36*
G01X435543D02*
Y538176D01*
X435631Y538116D01*
G02X434053I-789J-1159D01*
G01X434141Y538176D01*
Y538482D01*
X433738D01*
Y545584D01*
X435942D01*
Y538482D01*
X435543D01*
G37*
G36*
G01X428850D02*
Y538176D01*
X428938Y538116D01*
G02X427360I-789J-1159D01*
G01X427448Y538176D01*
Y538482D01*
X427046D01*
Y545584D01*
X429248D01*
Y538482D01*
X428850D01*
G37*
G36*
G01X415464D02*
Y538176D01*
X415552Y538116D01*
G02X413974I-789J-1159D01*
G01X414062Y538176D01*
Y538482D01*
X413660D01*
Y545584D01*
X415864D01*
Y538482D01*
X415464D01*
G37*
G36*
G01X405424D02*
Y538176D01*
X405512Y538116D01*
G02X403934I-789J-1159D01*
G01X404022Y538176D01*
Y538482D01*
X403620D01*
Y545584D01*
X405824D01*
Y538482D01*
X405424D01*
G37*
G36*
G01X402078D02*
Y538176D01*
X402166Y538116D01*
G02X400588I-789J-1159D01*
G01X400676Y538176D01*
Y538482D01*
X400274D01*
Y545584D01*
X402478D01*
Y538482D01*
X402078D01*
G37*
G36*
G01X355227D02*
Y538176D01*
X355315Y538116D01*
G02X353737I-789J-1159D01*
G01X353825Y538176D01*
Y538482D01*
X353424D01*
Y545584D01*
X355626D01*
Y538482D01*
X355227D01*
G37*
G36*
G01X348534D02*
Y538176D01*
X348622Y538116D01*
G02X347044I-789J-1159D01*
G01X347132Y538176D01*
Y538482D01*
X346732D01*
Y545584D01*
X348934D01*
Y538482D01*
X348534D01*
G37*
G36*
G01X345187D02*
Y538176D01*
X345275Y538116D01*
G02X343697I-789J-1159D01*
G01X343785Y538176D01*
Y538482D01*
X343384D01*
Y545584D01*
X345588D01*
Y538482D01*
X345187D01*
G37*
G36*
G01X338494D02*
Y538176D01*
X338582Y538116D01*
G02X337004I-789J-1159D01*
G01X337092Y538176D01*
Y538482D01*
X336692D01*
Y545584D01*
X338894D01*
Y538482D01*
X338494D01*
G37*
G36*
G01X335148D02*
Y538176D01*
X335236Y538116D01*
G02X333658I-789J-1159D01*
G01X333746Y538176D01*
Y538482D01*
X333346D01*
Y545584D01*
X335548D01*
Y538482D01*
X335148D01*
G37*
G36*
G01X328455D02*
Y538176D01*
X328543Y538116D01*
G02X326965I-789J-1159D01*
G01X327053Y538176D01*
Y538482D01*
X326652D01*
Y545584D01*
X328856D01*
Y538482D01*
X328455D01*
G37*
G36*
G01X325108D02*
Y538176D01*
X325196Y538116D01*
G02X323618I-789J-1159D01*
G01X323706Y538176D01*
Y538482D01*
X323306D01*
Y545584D01*
X325508D01*
Y538482D01*
X325108D01*
G37*
G36*
G01X311722D02*
Y538176D01*
X311810Y538116D01*
G02X310232I-789J-1159D01*
G01X310320Y538176D01*
Y538482D01*
X309920D01*
Y545584D01*
X312122D01*
Y538482D01*
X311722D01*
G37*
G36*
G01X422556Y520372D02*
X420354D01*
Y527474D01*
X420790D01*
Y527784D01*
X420698Y527843D01*
G02X422214I758J1179D01*
G01X422122Y527784D01*
Y527474D01*
X422556D01*
Y520372D01*
G37*
G36*
G01X409170D02*
X406968D01*
Y527474D01*
X407380D01*
Y527781D01*
X407291Y527841D01*
G02X408847I778J1166D01*
G01X408758Y527781D01*
Y527474D01*
X409170D01*
Y520372D01*
G37*
G36*
G01X405824D02*
X403620D01*
Y527474D01*
X404057D01*
Y527784D01*
X403965Y527843D01*
G02X405481I758J1179D01*
G01X405389Y527784D01*
Y527474D01*
X405824D01*
Y520372D01*
G37*
G36*
G01X399130D02*
X396928D01*
Y527474D01*
X397340D01*
Y527781D01*
X397251Y527841D01*
G02X398807I778J1166D01*
G01X398718Y527781D01*
Y527474D01*
X399130D01*
Y520372D01*
G37*
G36*
G01X355626D02*
X353424D01*
Y527474D01*
X353859D01*
Y527784D01*
X353767Y527843D01*
G02X355283I758J1179D01*
G01X355191Y527784D01*
Y527474D01*
X355626D01*
Y520372D01*
G37*
G36*
G01X352280D02*
X350078D01*
Y527474D01*
X350513D01*
Y527784D01*
X350421Y527843D01*
G02X351937I758J1179D01*
G01X351845Y527784D01*
Y527474D01*
X352280D01*
Y520372D01*
G37*
G36*
G01X345588D02*
X343384D01*
Y527474D01*
X343820D01*
Y527784D01*
X343728Y527843D01*
G02X345244I758J1179D01*
G01X345152Y527784D01*
Y527474D01*
X345588D01*
Y520372D01*
G37*
G36*
G01X342242D02*
X340038D01*
Y527474D01*
X340474D01*
Y527784D01*
X340382Y527843D01*
G02X341898I758J1179D01*
G01X341806Y527784D01*
Y527474D01*
X342242D01*
Y520372D01*
G37*
G36*
G01X335548D02*
X333346D01*
Y527474D01*
X333767D01*
Y527782D01*
X333677Y527842D01*
G02X335215I769J1172D01*
G01X335125Y527782D01*
Y527474D01*
X335548D01*
Y520372D01*
G37*
G36*
G01X332202D02*
X329998D01*
Y527474D01*
X330421D01*
Y527782D01*
X330331Y527842D01*
G02X331869I769J1172D01*
G01X331779Y527782D01*
Y527474D01*
X332202D01*
Y520372D01*
G37*
G36*
G01X325508D02*
X323306D01*
Y527474D01*
X323728D01*
Y527782D01*
X323638Y527842D01*
G02X325176I769J1172D01*
G01X325086Y527782D01*
Y527474D01*
X325508D01*
Y520372D01*
G37*
G36*
G01X322162D02*
X319960D01*
Y527474D01*
X320382D01*
Y527782D01*
X320292Y527842D01*
G02X321830I769J1172D01*
G01X321740Y527782D01*
Y527474D01*
X322162D01*
Y520372D01*
G37*
G36*
G01X975284Y104251D02*
G03X975861Y104144I338J214D01*
G02X975516Y102270I839J-1123D01*
G03X974939Y102377I-338J-214D01*
G02X975284Y104251I-839J1123D01*
G37*
G36*
G01X1013753Y86617D02*
G03X1013132I-311J-252D01*
G02Y88383I-1089J883D01*
G03X1013753I310J252D01*
G02Y86617I1089J-883D01*
G37*
G36*
G01X1025955Y85404D02*
G03Y84850I288J-277D01*
G02X1023935I-1010J-973D01*
G03Y85404I-288J277D01*
G02X1025955I1010J973D01*
G37*
G36*
G01X1008351Y69924D02*
G03Y69346I277J-289D01*
G02X1006409I-971J-1011D01*
G03Y69924I-277J289D01*
G02X1008351I971J1011D01*
G37*
G36*
G01X958546Y69365D02*
G03X958532Y68789I270J-295D01*
G02X956590Y68837I-996J-987D01*
G03X956604Y69413I-270J295D01*
G02X958546Y69365I996J987D01*
G37*
G36*
G01X1008310Y51293D02*
G03Y50699I268J-297D01*
G02X1006430I-940J-1040D01*
G03Y51293I-268J297D01*
G02X1008310I940J1040D01*
G37*
G36*
G01X1012804Y46006D02*
G03X1012195I-305J-258D01*
G02Y47822I-1069J908D01*
G03X1012804I304J258D01*
G02Y46006I1069J-908D01*
G37*
G36*
G01X1009185Y32318D02*
G03X1009179Y31740I273J-292D01*
G02X1007242Y31760I-979J-1004D01*
G03X1007248Y32338I-273J292D01*
G02X1009185Y32318I979J1004D01*
G37*
G36*
G01X1013899Y16081D02*
G03X1013311Y16074I-291J-275D01*
G02X1013290Y17975I-1041J939D01*
G03X1013878Y17982I291J275D01*
G02X1013899Y16081I1041J-939D01*
G37*
G36*
G01X1047394Y15661D02*
G03X1046925Y15287I-70J-394D01*
G02X1045768Y16738I-1400J70D01*
G03X1046237Y17112I70J394D01*
G02X1047394Y15661I1400J-70D01*
G37*
G36*
G01X1008071Y13303D02*
G03Y12725I277J-289D01*
G02X1006129I-971J-1011D01*
G03Y13303I-277J289D01*
G02X1008071I971J1011D01*
G37*
G36*
G01X1026779Y7498D02*
G03X1027385Y7467I316J245D01*
G02X1027291Y5642I1015J-967D01*
G03X1026685Y5673I-316J-245D01*
G02X1026779Y7498I-1015J967D01*
G37*
G36*
G01X1013495Y91625D02*
G02Y93375I-1095J875D01*
G03X1014120I312J250D01*
G02Y91625I1095J-875D01*
G03X1013495I-313J-250D01*
G37*
G36*
G01X1024615Y75306D02*
G02X1023185I-715J-1206D01*
G03Y75994I-204J344D01*
G02X1024615I715J1206D01*
G03Y75306I204J-344D01*
G37*
G36*
G01X1088498Y75282D02*
Y74976D01*
X1088586Y74916D01*
G02X1087008I-789J-1159D01*
G01X1087096Y74976D01*
Y75282D01*
X1086694D01*
Y82384D01*
X1088896D01*
Y75282D01*
X1088498D01*
G37*
G36*
G01X1085151D02*
Y74976D01*
X1085239Y74916D01*
G02X1083661I-789J-1159D01*
G01X1083749Y74976D01*
Y75282D01*
X1083346D01*
Y82384D01*
X1085550D01*
Y75282D01*
X1085151D01*
G37*
G36*
G01X1078458D02*
Y74976D01*
X1078546Y74916D01*
G02X1076968I-789J-1159D01*
G01X1077056Y74976D01*
Y75282D01*
X1076654D01*
Y82384D01*
X1078856D01*
Y75282D01*
X1078458D01*
G37*
G36*
G01X1065072D02*
Y74976D01*
X1065160Y74916D01*
G02X1063582I-789J-1159D01*
G01X1063670Y74976D01*
Y75282D01*
X1063268D01*
Y82384D01*
X1065472D01*
Y75282D01*
X1065072D01*
G37*
G36*
G01X1055032D02*
Y74976D01*
X1055120Y74916D01*
G02X1053542I-789J-1159D01*
G01X1053630Y74976D01*
Y75282D01*
X1053228D01*
Y82384D01*
X1055432D01*
Y75282D01*
X1055032D01*
G37*
G36*
G01X1051686D02*
Y74976D01*
X1051774Y74916D01*
G02X1050196I-789J-1159D01*
G01X1050284Y74976D01*
Y75282D01*
X1049882D01*
Y82384D01*
X1052086D01*
Y75282D01*
X1051686D01*
G37*
G36*
G01X1004835D02*
Y74976D01*
X1004923Y74916D01*
G02X1003345I-789J-1159D01*
G01X1003433Y74976D01*
Y75282D01*
X1003032D01*
Y82384D01*
X1005234D01*
Y75282D01*
X1004835D01*
G37*
G36*
G01X998142D02*
Y74976D01*
X998230Y74916D01*
G02X996652I-789J-1159D01*
G01X996740Y74976D01*
Y75282D01*
X996340D01*
Y82384D01*
X998542D01*
Y75282D01*
X998142D01*
G37*
G36*
G01X994795D02*
Y74976D01*
X994883Y74916D01*
G02X993305I-789J-1159D01*
G01X993393Y74976D01*
Y75282D01*
X992992D01*
Y82384D01*
X995196D01*
Y75282D01*
X994795D01*
G37*
G36*
G01X988102D02*
Y74976D01*
X988190Y74916D01*
G02X986612I-789J-1159D01*
G01X986700Y74976D01*
Y75282D01*
X986300D01*
Y82384D01*
X988502D01*
Y75282D01*
X988102D01*
G37*
G36*
G01X984756D02*
Y74976D01*
X984844Y74916D01*
G02X983266I-789J-1159D01*
G01X983354Y74976D01*
Y75282D01*
X982954D01*
Y82384D01*
X985156D01*
Y75282D01*
X984756D01*
G37*
G36*
G01X978063D02*
Y74976D01*
X978151Y74916D01*
G02X976573I-789J-1159D01*
G01X976661Y74976D01*
Y75282D01*
X976260D01*
Y82384D01*
X978464D01*
Y75282D01*
X978063D01*
G37*
G36*
G01X974716D02*
Y74976D01*
X974804Y74916D01*
G02X973226I-789J-1159D01*
G01X973314Y74976D01*
Y75282D01*
X972914D01*
Y82384D01*
X975116D01*
Y75282D01*
X974716D01*
G37*
G36*
G01X1095590Y57172D02*
X1093386D01*
Y64274D01*
X1093822D01*
Y64584D01*
X1093730Y64643D01*
G02X1095246I758J1179D01*
G01X1095154Y64584D01*
Y64274D01*
X1095590D01*
Y57172D01*
G37*
G36*
G01X1088896D02*
X1086694D01*
Y64274D01*
X1087131D01*
Y64584D01*
X1087039Y64643D01*
G02X1088555I758J1179D01*
G01X1088463Y64584D01*
Y64274D01*
X1088896D01*
Y57172D01*
G37*
G36*
G01X1082204D02*
X1080000D01*
Y64274D01*
X1080413D01*
Y64581D01*
X1080324Y64641D01*
G02X1081880I778J1166D01*
G01X1081791Y64581D01*
Y64274D01*
X1082204D01*
Y57172D01*
G37*
G36*
G01X1075510D02*
X1073308D01*
Y64274D01*
X1073720D01*
Y64581D01*
X1073631Y64641D01*
G02X1075187I778J1166D01*
G01X1075098Y64581D01*
Y64274D01*
X1075510D01*
Y57172D01*
G37*
G36*
G01X1072164D02*
X1069962D01*
Y64274D01*
X1070398D01*
Y64584D01*
X1070306Y64643D01*
G02X1071822I758J1179D01*
G01X1071730Y64584D01*
Y64274D01*
X1072164D01*
Y57172D01*
G37*
G36*
G01X1065472D02*
X1063268D01*
Y64274D01*
X1063705D01*
Y64584D01*
X1063613Y64643D01*
G02X1065129I758J1179D01*
G01X1065037Y64584D01*
Y64274D01*
X1065472D01*
Y57172D01*
G37*
G36*
G01X1058778D02*
X1056576D01*
Y64274D01*
X1056988D01*
Y64581D01*
X1056899Y64641D01*
G02X1058455I778J1166D01*
G01X1058366Y64581D01*
Y64274D01*
X1058778D01*
Y57172D01*
G37*
G36*
G01X1055432D02*
X1053228D01*
Y64274D01*
X1053665D01*
Y64584D01*
X1053573Y64643D01*
G02X1055089I758J1179D01*
G01X1054997Y64584D01*
Y64274D01*
X1055432D01*
Y57172D01*
G37*
G36*
G01X1048738D02*
X1046536D01*
Y64274D01*
X1046948D01*
Y64581D01*
X1046859Y64641D01*
G02X1048415I778J1166D01*
G01X1048326Y64581D01*
Y64274D01*
X1048738D01*
Y57172D01*
G37*
G36*
G01X1005234D02*
X1003032D01*
Y64274D01*
X1003467D01*
Y64584D01*
X1003375Y64643D01*
G02X1004891I758J1179D01*
G01X1004799Y64584D01*
Y64274D01*
X1005234D01*
Y57172D01*
G37*
G36*
G01X1001888D02*
X999686D01*
Y64274D01*
X1000121D01*
Y64584D01*
X1000029Y64643D01*
G02X1001545I758J1179D01*
G01X1001453Y64584D01*
Y64274D01*
X1001888D01*
Y57172D01*
G37*
G36*
G01X995196D02*
X992992D01*
Y64274D01*
X993428D01*
Y64584D01*
X993336Y64643D01*
G02X994852I758J1179D01*
G01X994760Y64584D01*
Y64274D01*
X995196D01*
Y57172D01*
G37*
G36*
G01X991850D02*
X989646D01*
Y64274D01*
X990082D01*
Y64584D01*
X989990Y64643D01*
G02X991506I758J1179D01*
G01X991414Y64584D01*
Y64274D01*
X991850D01*
Y57172D01*
G37*
G36*
G01X985156D02*
X982954D01*
Y64274D01*
X983375D01*
Y64582D01*
X983285Y64642D01*
G02X984823I769J1172D01*
G01X984733Y64582D01*
Y64274D01*
X985156D01*
Y57172D01*
G37*
G36*
G01X981810D02*
X979606D01*
Y64274D01*
X980029D01*
Y64582D01*
X979939Y64642D01*
G02X981477I769J1172D01*
G01X981387Y64582D01*
Y64274D01*
X981810D01*
Y57172D01*
G37*
G36*
G01X975116D02*
X972914D01*
Y64274D01*
X973336D01*
Y64582D01*
X973246Y64642D01*
G02X974784I769J1172D01*
G01X974694Y64582D01*
Y64274D01*
X975116D01*
Y57172D01*
G37*
G36*
G01X971770D02*
X969568D01*
Y64274D01*
X969990D01*
Y64582D01*
X969900Y64642D01*
G02X971438I769J1172D01*
G01X971348Y64582D01*
Y64274D01*
X971770D01*
Y57172D01*
G37*
G36*
G01X965078D02*
X962874D01*
Y64274D01*
X963297D01*
Y64582D01*
X963207Y64642D01*
G02X964745I769J1172D01*
G01X964655Y64582D01*
Y64274D01*
X965078D01*
Y57172D01*
G37*
G36*
G01X1095191Y37482D02*
Y37176D01*
X1095279Y37116D01*
G02X1093701I-789J-1159D01*
G01X1093789Y37176D01*
Y37482D01*
X1093386D01*
Y44584D01*
X1095590D01*
Y37482D01*
X1095191D01*
G37*
G36*
G01X1088498D02*
Y37176D01*
X1088586Y37116D01*
G02X1087008I-789J-1159D01*
G01X1087096Y37176D01*
Y37482D01*
X1086694D01*
Y44584D01*
X1088896D01*
Y37482D01*
X1088498D01*
G37*
G36*
G01X1085151D02*
Y37176D01*
X1085239Y37116D01*
G02X1083661I-789J-1159D01*
G01X1083749Y37176D01*
Y37482D01*
X1083346D01*
Y44584D01*
X1085550D01*
Y37482D01*
X1085151D01*
G37*
G36*
G01X1078458D02*
Y37176D01*
X1078546Y37116D01*
G02X1076968I-789J-1159D01*
G01X1077056Y37176D01*
Y37482D01*
X1076654D01*
Y44584D01*
X1078856D01*
Y37482D01*
X1078458D01*
G37*
G36*
G01X1065072D02*
Y37176D01*
X1065160Y37116D01*
G02X1063582I-789J-1159D01*
G01X1063670Y37176D01*
Y37482D01*
X1063268D01*
Y44584D01*
X1065472D01*
Y37482D01*
X1065072D01*
G37*
G36*
G01X1055032D02*
Y37176D01*
X1055120Y37116D01*
G02X1053542I-789J-1159D01*
G01X1053630Y37176D01*
Y37482D01*
X1053228D01*
Y44584D01*
X1055432D01*
Y37482D01*
X1055032D01*
G37*
G36*
G01X1051686D02*
Y37176D01*
X1051774Y37116D01*
G02X1050196I-789J-1159D01*
G01X1050284Y37176D01*
Y37482D01*
X1049882D01*
Y44584D01*
X1052086D01*
Y37482D01*
X1051686D01*
G37*
G36*
G01X1044993D02*
Y37176D01*
X1045081Y37116D01*
G02X1043503I-789J-1159D01*
G01X1043591Y37176D01*
Y37482D01*
X1043190D01*
Y44584D01*
X1045392D01*
Y37482D01*
X1044993D01*
G37*
G36*
G01X1004835D02*
Y37176D01*
X1004923Y37116D01*
G02X1003345I-789J-1159D01*
G01X1003433Y37176D01*
Y37482D01*
X1003032D01*
Y44584D01*
X1005234D01*
Y37482D01*
X1004835D01*
G37*
G36*
G01X998142D02*
Y37176D01*
X998230Y37116D01*
G02X996652I-789J-1159D01*
G01X996740Y37176D01*
Y37482D01*
X996340D01*
Y44584D01*
X998542D01*
Y37482D01*
X998142D01*
G37*
G36*
G01X994795D02*
Y37176D01*
X994883Y37116D01*
G02X993305I-789J-1159D01*
G01X993393Y37176D01*
Y37482D01*
X992992D01*
Y44584D01*
X995196D01*
Y37482D01*
X994795D01*
G37*
G36*
G01X988102D02*
Y37176D01*
X988190Y37116D01*
G02X986612I-789J-1159D01*
G01X986700Y37176D01*
Y37482D01*
X986300D01*
Y44584D01*
X988502D01*
Y37482D01*
X988102D01*
G37*
G36*
G01X984756D02*
Y37176D01*
X984844Y37116D01*
G02X983266I-789J-1159D01*
G01X983354Y37176D01*
Y37482D01*
X982954D01*
Y44584D01*
X985156D01*
Y37482D01*
X984756D01*
G37*
G36*
G01X978063D02*
Y37176D01*
X978151Y37116D01*
G02X976573I-789J-1159D01*
G01X976661Y37176D01*
Y37482D01*
X976260D01*
Y44584D01*
X978464D01*
Y37482D01*
X978063D01*
G37*
G36*
G01X974716D02*
Y37176D01*
X974804Y37116D01*
G02X973226I-789J-1159D01*
G01X973314Y37176D01*
Y37482D01*
X972914D01*
Y44584D01*
X975116D01*
Y37482D01*
X974716D01*
G37*
G36*
G01X961330D02*
Y37176D01*
X961418Y37116D01*
G02X959840I-789J-1159D01*
G01X959928Y37176D01*
Y37482D01*
X959528D01*
Y44584D01*
X961730D01*
Y37482D01*
X961330D01*
G37*
G36*
G01X1014852D02*
Y37174D01*
X1014942Y37114D01*
G02X1013404I-769J-1172D01*
G01X1013494Y37174D01*
Y37482D01*
X1013072D01*
Y44584D01*
X1015274D01*
Y37482D01*
X1014852D01*
G37*
G36*
G01X1011505D02*
Y37174D01*
X1011595Y37114D01*
G02X1010057I-769J-1172D01*
G01X1010147Y37174D01*
Y37482D01*
X1009724D01*
Y44584D01*
X1011928D01*
Y37482D01*
X1011505D01*
G37*
G36*
G01X1031207Y24330D02*
G02X1029654Y24304I-757J-1180D01*
G03X1029643Y24970I-227J329D01*
G02X1031196Y24996I757J1180D01*
G03X1031207Y24330I227J-329D01*
G37*
G36*
G01X1095590Y19372D02*
X1093386D01*
Y26474D01*
X1093822D01*
Y26784D01*
X1093730Y26843D01*
G02X1095246I758J1179D01*
G01X1095154Y26784D01*
Y26474D01*
X1095590D01*
Y19372D01*
G37*
G36*
G01X1088896D02*
X1086694D01*
Y26474D01*
X1087131D01*
Y26784D01*
X1087039Y26843D01*
G02X1088555I758J1179D01*
G01X1088463Y26784D01*
Y26474D01*
X1088896D01*
Y19372D01*
G37*
G36*
G01X1082204D02*
X1080000D01*
Y26474D01*
X1080413D01*
Y26781D01*
X1080324Y26841D01*
G02X1081880I778J1166D01*
G01X1081791Y26781D01*
Y26474D01*
X1082204D01*
Y19372D01*
G37*
G36*
G01X1075510D02*
X1073308D01*
Y26474D01*
X1073720D01*
Y26781D01*
X1073631Y26841D01*
G02X1075187I778J1166D01*
G01X1075098Y26781D01*
Y26474D01*
X1075510D01*
Y19372D01*
G37*
G36*
G01X1072164D02*
X1069962D01*
Y26474D01*
X1070398D01*
Y26784D01*
X1070306Y26843D01*
G02X1071822I758J1179D01*
G01X1071730Y26784D01*
Y26474D01*
X1072164D01*
Y19372D01*
G37*
G36*
G01X1065472D02*
X1063268D01*
Y26474D01*
X1063705D01*
Y26784D01*
X1063613Y26843D01*
G02X1065129I758J1179D01*
G01X1065037Y26784D01*
Y26474D01*
X1065472D01*
Y19372D01*
G37*
G36*
G01X1058778D02*
X1056576D01*
Y26474D01*
X1056988D01*
Y26781D01*
X1056899Y26841D01*
G02X1058455I778J1166D01*
G01X1058366Y26781D01*
Y26474D01*
X1058778D01*
Y19372D01*
G37*
G36*
G01X1055432D02*
X1053228D01*
Y26474D01*
X1053665D01*
Y26784D01*
X1053573Y26843D01*
G02X1055089I758J1179D01*
G01X1054997Y26784D01*
Y26474D01*
X1055432D01*
Y19372D01*
G37*
G36*
G01X1048738D02*
X1046536D01*
Y26474D01*
X1046948D01*
Y26781D01*
X1046859Y26841D01*
G02X1048415I778J1166D01*
G01X1048326Y26781D01*
Y26474D01*
X1048738D01*
Y19372D01*
G37*
G36*
G01X1015274D02*
X1013072D01*
Y26474D01*
X1013494D01*
Y26782D01*
X1013404Y26842D01*
G02X1014942I769J1172D01*
G01X1014852Y26782D01*
Y26474D01*
X1015274D01*
Y19372D01*
G37*
G36*
G01X1011928D02*
X1009724D01*
Y26474D01*
X1010147D01*
Y26782D01*
X1010057Y26842D01*
G02X1011595I769J1172D01*
G01X1011505Y26782D01*
Y26474D01*
X1011928D01*
Y19372D01*
G37*
G36*
G01X1005234D02*
X1003032D01*
Y26474D01*
X1003467D01*
Y26784D01*
X1003375Y26843D01*
G02X1004891I758J1179D01*
G01X1004799Y26784D01*
Y26474D01*
X1005234D01*
Y19372D01*
G37*
G36*
G01X1001888D02*
X999686D01*
Y26474D01*
X1000121D01*
Y26784D01*
X1000029Y26843D01*
G02X1001545I758J1179D01*
G01X1001453Y26784D01*
Y26474D01*
X1001888D01*
Y19372D01*
G37*
G36*
G01X995196D02*
X992992D01*
Y26474D01*
X993428D01*
Y26784D01*
X993336Y26843D01*
G02X994852I758J1179D01*
G01X994760Y26784D01*
Y26474D01*
X995196D01*
Y19372D01*
G37*
G36*
G01X991850D02*
X989646D01*
Y26474D01*
X990082D01*
Y26784D01*
X989990Y26843D01*
G02X991506I758J1179D01*
G01X991414Y26784D01*
Y26474D01*
X991850D01*
Y19372D01*
G37*
G36*
G01X985156D02*
X982954D01*
Y26474D01*
X983375D01*
Y26782D01*
X983285Y26842D01*
G02X984823I769J1172D01*
G01X984733Y26782D01*
Y26474D01*
X985156D01*
Y19372D01*
G37*
G36*
G01X981810D02*
X979606D01*
Y26474D01*
X980029D01*
Y26782D01*
X979939Y26842D01*
G02X981477I769J1172D01*
G01X981387Y26782D01*
Y26474D01*
X981810D01*
Y19372D01*
G37*
G36*
G01X975116D02*
X972914D01*
Y26474D01*
X973336D01*
Y26782D01*
X973246Y26842D01*
G02X974784I769J1172D01*
G01X974694Y26782D01*
Y26474D01*
X975116D01*
Y19372D01*
G37*
G36*
G01X971770D02*
X969568D01*
Y26474D01*
X969990D01*
Y26782D01*
X969900Y26842D01*
G02X971438I769J1172D01*
G01X971348Y26782D01*
Y26474D01*
X971770D01*
Y19372D01*
G37*
G36*
G01X965078D02*
X962874D01*
Y26474D01*
X963297D01*
Y26782D01*
X963207Y26842D01*
G02X964745I769J1172D01*
G01X964655Y26782D01*
Y26474D01*
X965078D01*
Y19372D01*
G37*
G36*
G01X958384D02*
X956182D01*
Y26474D01*
X956604D01*
Y26782D01*
X956514Y26842D01*
G02X958052I769J1172D01*
G01X957962Y26782D01*
Y26474D01*
X958384D01*
Y19372D01*
G37*
G36*
G01X1025003Y18760D02*
G02X1023684Y19551I-1263J-610D01*
G03X1024028Y20124I-16J399D01*
G02X1025347Y19333I1263J610D01*
G03X1025003Y18760I16J-399D01*
G37*
G36*
G01X1004967Y-318D02*
Y-611D01*
X1005038Y-671D01*
G02X1003228I-905J-1071D01*
G01X1003299Y-611D01*
Y-318D01*
X1003032D01*
Y6784D01*
X1005234D01*
Y-318D01*
X1004967D01*
G37*
G36*
G01X1085281D02*
Y-611D01*
X1085352Y-671D01*
G02X1083544I-904J-1072D01*
G01X1083615Y-611D01*
Y-318D01*
X1083346D01*
Y6784D01*
X1085550D01*
Y-318D01*
X1085281D01*
G37*
G36*
G01X1078588D02*
Y-611D01*
X1078659Y-671D01*
G02X1076851I-904J-1072D01*
G01X1076922Y-611D01*
Y-318D01*
X1076654D01*
Y6784D01*
X1078856D01*
Y-318D01*
X1078588D01*
G37*
G36*
G01X1065202D02*
Y-611D01*
X1065273Y-671D01*
G02X1063465I-904J-1072D01*
G01X1063536Y-611D01*
Y-318D01*
X1063268D01*
Y6784D01*
X1065472D01*
Y-318D01*
X1065202D01*
G37*
G36*
G01X1051816D02*
Y-611D01*
X1051887Y-671D01*
G02X1050079I-904J-1072D01*
G01X1050150Y-611D01*
Y-318D01*
X1049882D01*
Y6784D01*
X1052086D01*
Y-318D01*
X1051816D01*
G37*
G36*
G01X998274D02*
Y-611D01*
X998345Y-671D01*
G02X996537I-904J-1072D01*
G01X996608Y-611D01*
Y-318D01*
X996340D01*
Y6784D01*
X998542D01*
Y-318D01*
X998274D01*
G37*
G36*
G01X984888D02*
Y-611D01*
X984959Y-671D01*
G02X983151I-904J-1072D01*
G01X983222Y-611D01*
Y-318D01*
X982954D01*
Y6784D01*
X985156D01*
Y-318D01*
X984888D01*
G37*
G36*
G01X978195D02*
Y-611D01*
X978266Y-671D01*
G02X976458I-904J-1072D01*
G01X976529Y-611D01*
Y-318D01*
X976260D01*
Y6784D01*
X978464D01*
Y-318D01*
X978195D01*
G37*
G36*
G01X1014852D02*
Y-626D01*
X1014942Y-686D01*
G02X1013404I-769J-1172D01*
G01X1013494Y-626D01*
Y-318D01*
X1013072D01*
Y6784D01*
X1015274D01*
Y-318D01*
X1014852D01*
G37*
G36*
G01X1011505D02*
Y-626D01*
X1011595Y-686D01*
G02X1010057I-769J-1172D01*
G01X1010147Y-626D01*
Y-318D01*
X1009724D01*
Y6784D01*
X1011928D01*
Y-318D01*
X1011505D01*
G37*
G36*
G01X1030373Y-7536D02*
G02X1029065Y-8532I34J-1402D01*
G03X1028673Y-8017I-383J115D01*
G02X1029981Y-7021I-34J1402D01*
G03X1030373Y-7536I383J-115D01*
G37*
G36*
G01X1082204Y-18428D02*
X1080000D01*
Y-11326D01*
X1080269D01*
Y-11033D01*
X1080198Y-10973D01*
G02X1082006I904J1072D01*
G01X1081935Y-11033D01*
Y-11326D01*
X1082204D01*
Y-18428D01*
G37*
G36*
G01X1048738D02*
X1046536D01*
Y-11326D01*
X1046804D01*
Y-11033D01*
X1046733Y-10973D01*
G02X1048541I904J1072D01*
G01X1048470Y-11033D01*
Y-11326D01*
X1048738D01*
Y-18428D01*
G37*
G36*
G01X1015274D02*
X1013072D01*
Y-11326D01*
X1013494D01*
Y-11018D01*
X1013404Y-10958D01*
G02X1014942I769J1172D01*
G01X1014852Y-11018D01*
Y-11326D01*
X1015274D01*
Y-18428D01*
G37*
G36*
G01X1011928D02*
X1009724D01*
Y-11326D01*
X1010147D01*
Y-11018D01*
X1010057Y-10958D01*
G02X1011595I769J1172D01*
G01X1011505Y-11018D01*
Y-11326D01*
X1011928D01*
Y-18428D01*
G37*
G36*
G01X1001888D02*
X999686D01*
Y-11326D01*
X999954D01*
Y-11033D01*
X999883Y-10973D01*
G02X1001691I904J1072D01*
G01X1001620Y-11033D01*
Y-11326D01*
X1001888D01*
Y-18428D01*
G37*
G36*
G01X995196D02*
X992992D01*
Y-11326D01*
X993415D01*
Y-11018D01*
X993325Y-10958D01*
G02X994863I769J1172D01*
G01X994773Y-11018D01*
Y-11326D01*
X995196D01*
Y-18428D01*
G37*
G36*
G01X981810D02*
X979606D01*
Y-11326D01*
X980029D01*
Y-11018D01*
X979939Y-10958D01*
G02X981477I769J1172D01*
G01X981387Y-11018D01*
Y-11326D01*
X981810D01*
Y-18428D01*
G37*
G36*
G01X975116D02*
X972914D01*
Y-11326D01*
X973182D01*
Y-11033D01*
X973111Y-10973D01*
G02X974919I904J1072D01*
G01X974848Y-11033D01*
Y-11326D01*
X975116D01*
Y-18428D01*
G37*
G36*
G01X1024477Y592640D02*
G03X1023923I-277J-288D01*
G02X1021901Y592720I-973J1010D01*
G03X1021313Y592731I-299J-266D01*
G02X1021349Y594630I-1013J969D01*
G03X1021937Y594619I299J266D01*
G02X1023923Y594660I1013J-969D01*
G03X1024477I277J288D01*
G02Y592640I973J-1010D01*
G37*
G36*
G01X1007377Y589955D02*
G03Y589377I277J-289D01*
G02X1005435I-971J-1011D01*
G03Y589955I-277J289D01*
G02X1007377I971J1011D01*
G37*
G36*
G01X1012804Y584806D02*
G03X1012195I-305J-258D01*
G02Y586622I-1069J908D01*
G03X1012804I304J258D01*
G02X1014884Y586685I1068J-908D01*
G03X1015462I289J277D01*
G02Y584743I1011J-971D01*
G03X1014884I-289J-277D01*
G02X1012804Y584806I-1012J971D01*
G37*
G36*
G01X1008303Y570999D02*
G03Y570421I277J-289D01*
G02X1006361I-971J-1011D01*
G03Y570999I-277J289D01*
G02X1008303I971J1011D01*
G37*
G36*
G01X1008118Y552100D02*
G03Y551522I277J-289D01*
G02X1006176I-971J-1011D01*
G03Y552100I-277J289D01*
G02X1008118I971J1011D01*
G37*
G36*
G01X1012804Y547006D02*
G03X1012195I-305J-258D01*
G02Y548822I-1069J908D01*
G03X1012804I304J258D01*
G02Y547006I1069J-908D01*
G37*
G36*
G01X1025534Y542016D02*
G03X1025512Y542615I-276J290D01*
G02Y544785I888J1085D01*
G03X1025534Y545384I-254J309D01*
G02X1027388Y545315I966J1016D01*
G03X1027366Y544716I254J-309D01*
G02Y542684I-966J-1016D01*
G03X1027388Y542085I276J-290D01*
G02X1027510Y540027I-888J-1085D01*
G03Y539473I288J-277D01*
G02X1025490I-1010J-973D01*
G03Y540027I-288J277D01*
G02X1025534Y542016I1010J973D01*
G37*
G36*
G01X1008178Y533126D02*
G03Y532548I277J-289D01*
G02X1006236I-971J-1011D01*
G03Y533126I-277J289D01*
G02X1008178I971J1011D01*
G37*
G36*
G01X1025810Y517883D02*
G03Y517329I288J-277D01*
G02X1023790I-1010J-973D01*
G03Y517883I-288J277D01*
G02X1025810I1010J973D01*
G37*
G36*
G01X1012288Y516142D02*
G03X1012870Y516132I296J269D01*
G02X1012835Y514210I1003J-980D01*
G03X1012253Y514220I-296J-269D01*
G02X1012288Y516142I-1003J980D01*
G37*
G36*
G01X1012804Y509206D02*
G03X1012195I-305J-258D01*
G02Y511022I-1069J908D01*
G03X1012804I304J258D01*
G02Y509206I1069J-908D01*
G37*
G36*
G01X1045125Y614082D02*
Y613789D01*
X1045196Y613729D01*
G02X1043386I-905J-1071D01*
G01X1043457Y613789D01*
Y614082D01*
X1043190D01*
Y621184D01*
X1045392D01*
Y614082D01*
X1045125D01*
G37*
G36*
G01X1085281D02*
Y613789D01*
X1085352Y613729D01*
G02X1083544I-904J-1072D01*
G01X1083615Y613789D01*
Y614082D01*
X1083346D01*
Y621184D01*
X1085550D01*
Y614082D01*
X1085281D01*
G37*
G36*
G01X984588D02*
Y613760D01*
X984696Y613704D01*
G02X983414I-641J-1247D01*
G01X983522Y613760D01*
Y614082D01*
X982954D01*
Y621184D01*
X985156D01*
Y614082D01*
X984588D01*
G37*
G36*
G01X977895D02*
Y613760D01*
X978003Y613704D01*
G02X976721I-641J-1247D01*
G01X976829Y613760D01*
Y614082D01*
X976260D01*
Y621184D01*
X978464D01*
Y614082D01*
X977895D01*
G37*
G36*
G01X1005084Y613388D02*
G02X1003182I-951J-1030D01*
G03X1003032Y614063I-272J294D01*
G01Y621184D01*
X1005234D01*
Y614063D01*
G03X1005084Y613388I122J-381D01*
G37*
G36*
G01X998392D02*
G02X996490I-951J-1031D01*
G03X996340Y614063I-271J294D01*
G01Y621184D01*
X998542D01*
Y614063D01*
G03X998392Y613388I121J-381D01*
G37*
G36*
G01X1022726Y612019D02*
G02X1021807Y610859I474J-1319D01*
G03X1021274Y611281I-397J46D01*
G02X1022193Y612441I-474J1319D01*
G03X1022726Y612019I397J-46D01*
G37*
G36*
G01X1095590Y595972D02*
X1093386D01*
Y603074D01*
X1093809D01*
Y603382D01*
X1093719Y603442D01*
G02X1095257I769J1172D01*
G01X1095167Y603382D01*
Y603074D01*
X1095590D01*
Y595972D01*
G37*
G36*
G01X1088896D02*
X1086694D01*
Y603074D01*
X1087116D01*
Y603382D01*
X1087026Y603442D01*
G02X1088564I769J1172D01*
G01X1088474Y603382D01*
Y603074D01*
X1088896D01*
Y595972D01*
G37*
G36*
G01X1082204D02*
X1080000D01*
Y603074D01*
X1080269D01*
Y603367D01*
X1080198Y603427D01*
G02X1082006I904J1072D01*
G01X1081935Y603367D01*
Y603074D01*
X1082204D01*
Y595972D01*
G37*
G36*
G01X1075510D02*
X1073308D01*
Y603074D01*
X1073730D01*
Y603382D01*
X1073640Y603442D01*
G02X1075178I769J1172D01*
G01X1075088Y603382D01*
Y603074D01*
X1075510D01*
Y595972D01*
G37*
G36*
G01X1055432D02*
X1053228D01*
Y603074D01*
X1053497D01*
Y603367D01*
X1053426Y603427D01*
G02X1055234I904J1072D01*
G01X1055163Y603367D01*
Y603074D01*
X1055432D01*
Y595972D01*
G37*
G36*
G01X1048738D02*
X1046536D01*
Y603074D01*
X1046804D01*
Y603367D01*
X1046733Y603427D01*
G02X1048541I904J1072D01*
G01X1048470Y603367D01*
Y603074D01*
X1048738D01*
Y595972D01*
G37*
G36*
G01X1015274D02*
X1013072D01*
Y603074D01*
X1013494D01*
Y603382D01*
X1013404Y603442D01*
G02X1014942I769J1172D01*
G01X1014852Y603382D01*
Y603074D01*
X1015274D01*
Y595972D01*
G37*
G36*
G01X1011928D02*
X1009724D01*
Y603074D01*
X1010147D01*
Y603382D01*
X1010057Y603442D01*
G02X1011595I769J1172D01*
G01X1011505Y603382D01*
Y603074D01*
X1011928D01*
Y595972D01*
G37*
G36*
G01X1001888D02*
X999686D01*
Y603074D01*
X999954D01*
Y603367D01*
X999883Y603427D01*
G02X1001691I904J1072D01*
G01X1001620Y603367D01*
Y603074D01*
X1001888D01*
Y595972D01*
G37*
G36*
G01X995196D02*
X992992D01*
Y603074D01*
X993415D01*
Y603382D01*
X993325Y603442D01*
G02X994863I769J1172D01*
G01X994773Y603382D01*
Y603074D01*
X995196D01*
Y595972D01*
G37*
G36*
G01X981810D02*
X979606D01*
Y603074D01*
X980029D01*
Y603382D01*
X979939Y603442D01*
G02X981477I769J1172D01*
G01X981387Y603382D01*
Y603074D01*
X981810D01*
Y595972D01*
G37*
G36*
G01X975116D02*
X972914D01*
Y603074D01*
X973182D01*
Y603367D01*
X973111Y603427D01*
G02X974919I904J1072D01*
G01X974848Y603367D01*
Y603074D01*
X975116D01*
Y595972D01*
G37*
G36*
G01X1088498Y576282D02*
Y575976D01*
X1088586Y575916D01*
G02X1087008I-789J-1159D01*
G01X1087096Y575976D01*
Y576282D01*
X1086694D01*
Y583384D01*
X1088896D01*
Y576282D01*
X1088498D01*
G37*
G36*
G01X1085151D02*
Y575976D01*
X1085239Y575916D01*
G02X1083661I-789J-1159D01*
G01X1083749Y575976D01*
Y576282D01*
X1083346D01*
Y583384D01*
X1085550D01*
Y576282D01*
X1085151D01*
G37*
G36*
G01X1078458D02*
Y575976D01*
X1078546Y575916D01*
G02X1076968I-789J-1159D01*
G01X1077056Y575976D01*
Y576282D01*
X1076654D01*
Y583384D01*
X1078856D01*
Y576282D01*
X1078458D01*
G37*
G36*
G01X1065072D02*
Y575976D01*
X1065160Y575916D01*
G02X1063582I-789J-1159D01*
G01X1063670Y575976D01*
Y576282D01*
X1063268D01*
Y583384D01*
X1065472D01*
Y576282D01*
X1065072D01*
G37*
G36*
G01X1055032D02*
Y575976D01*
X1055120Y575916D01*
G02X1053542I-789J-1159D01*
G01X1053630Y575976D01*
Y576282D01*
X1053228D01*
Y583384D01*
X1055432D01*
Y576282D01*
X1055032D01*
G37*
G36*
G01X1051686D02*
Y575976D01*
X1051774Y575916D01*
G02X1050196I-789J-1159D01*
G01X1050284Y575976D01*
Y576282D01*
X1049882D01*
Y583384D01*
X1052086D01*
Y576282D01*
X1051686D01*
G37*
G36*
G01X1044993D02*
Y575976D01*
X1045081Y575916D01*
G02X1043503I-789J-1159D01*
G01X1043591Y575976D01*
Y576282D01*
X1043190D01*
Y583384D01*
X1045392D01*
Y576282D01*
X1044993D01*
G37*
G36*
G01X1004835D02*
Y575976D01*
X1004923Y575916D01*
G02X1003345I-789J-1159D01*
G01X1003433Y575976D01*
Y576282D01*
X1003032D01*
Y583384D01*
X1005234D01*
Y576282D01*
X1004835D01*
G37*
G36*
G01X998142D02*
Y575976D01*
X998230Y575916D01*
G02X996652I-789J-1159D01*
G01X996740Y575976D01*
Y576282D01*
X996340D01*
Y583384D01*
X998542D01*
Y576282D01*
X998142D01*
G37*
G36*
G01X994795D02*
Y575976D01*
X994883Y575916D01*
G02X993305I-789J-1159D01*
G01X993393Y575976D01*
Y576282D01*
X992992D01*
Y583384D01*
X995196D01*
Y576282D01*
X994795D01*
G37*
G36*
G01X988102D02*
Y575976D01*
X988190Y575916D01*
G02X986612I-789J-1159D01*
G01X986700Y575976D01*
Y576282D01*
X986300D01*
Y583384D01*
X988502D01*
Y576282D01*
X988102D01*
G37*
G36*
G01X984756D02*
Y575976D01*
X984844Y575916D01*
G02X983266I-789J-1159D01*
G01X983354Y575976D01*
Y576282D01*
X982954D01*
Y583384D01*
X985156D01*
Y576282D01*
X984756D01*
G37*
G36*
G01X978063D02*
Y575976D01*
X978151Y575916D01*
G02X976573I-789J-1159D01*
G01X976661Y575976D01*
Y576282D01*
X976260D01*
Y583384D01*
X978464D01*
Y576282D01*
X978063D01*
G37*
G36*
G01X974716D02*
Y575976D01*
X974804Y575916D01*
G02X973226I-789J-1159D01*
G01X973314Y575976D01*
Y576282D01*
X972914D01*
Y583384D01*
X975116D01*
Y576282D01*
X974716D01*
G37*
G36*
G01X961330D02*
Y575976D01*
X961418Y575916D01*
G02X959840I-789J-1159D01*
G01X959928Y575976D01*
Y576282D01*
X959528D01*
Y583384D01*
X961730D01*
Y576282D01*
X961330D01*
G37*
G36*
G01X1014852D02*
Y575974D01*
X1014942Y575914D01*
G02X1013404I-769J-1172D01*
G01X1013494Y575974D01*
Y576282D01*
X1013072D01*
Y583384D01*
X1015274D01*
Y576282D01*
X1014852D01*
G37*
G36*
G01X1011505D02*
Y575974D01*
X1011595Y575914D01*
G02X1010057I-769J-1172D01*
G01X1010147Y575974D01*
Y576282D01*
X1009724D01*
Y583384D01*
X1011928D01*
Y576282D01*
X1011505D01*
G37*
G36*
G01X1095590Y558172D02*
X1093386D01*
Y565274D01*
X1093822D01*
Y565584D01*
X1093730Y565643D01*
G02X1095246I758J1179D01*
G01X1095154Y565584D01*
Y565274D01*
X1095590D01*
Y558172D01*
G37*
G36*
G01X1088896D02*
X1086694D01*
Y565274D01*
X1087131D01*
Y565584D01*
X1087039Y565643D01*
G02X1088555I758J1179D01*
G01X1088463Y565584D01*
Y565274D01*
X1088896D01*
Y558172D01*
G37*
G36*
G01X1082204D02*
X1080000D01*
Y565274D01*
X1080413D01*
Y565581D01*
X1080324Y565641D01*
G02X1081880I778J1166D01*
G01X1081791Y565581D01*
Y565274D01*
X1082204D01*
Y558172D01*
G37*
G36*
G01X1075510D02*
X1073308D01*
Y565274D01*
X1073720D01*
Y565581D01*
X1073631Y565641D01*
G02X1075187I778J1166D01*
G01X1075098Y565581D01*
Y565274D01*
X1075510D01*
Y558172D01*
G37*
G36*
G01X1072164D02*
X1069962D01*
Y565274D01*
X1070398D01*
Y565584D01*
X1070306Y565643D01*
G02X1071822I758J1179D01*
G01X1071730Y565584D01*
Y565274D01*
X1072164D01*
Y558172D01*
G37*
G36*
G01X1065472D02*
X1063268D01*
Y565274D01*
X1063705D01*
Y565584D01*
X1063613Y565643D01*
G02X1065129I758J1179D01*
G01X1065037Y565584D01*
Y565274D01*
X1065472D01*
Y558172D01*
G37*
G36*
G01X1058778D02*
X1056576D01*
Y565274D01*
X1056988D01*
Y565581D01*
X1056899Y565641D01*
G02X1058455I778J1166D01*
G01X1058366Y565581D01*
Y565274D01*
X1058778D01*
Y558172D01*
G37*
G36*
G01X1055432D02*
X1053228D01*
Y565274D01*
X1053665D01*
Y565584D01*
X1053573Y565643D01*
G02X1055089I758J1179D01*
G01X1054997Y565584D01*
Y565274D01*
X1055432D01*
Y558172D01*
G37*
G36*
G01X1048738D02*
X1046536D01*
Y565274D01*
X1046948D01*
Y565581D01*
X1046859Y565641D01*
G02X1048415I778J1166D01*
G01X1048326Y565581D01*
Y565274D01*
X1048738D01*
Y558172D01*
G37*
G36*
G01X1015274D02*
X1013072D01*
Y565274D01*
X1013494D01*
Y565582D01*
X1013404Y565642D01*
G02X1014942I769J1172D01*
G01X1014852Y565582D01*
Y565274D01*
X1015274D01*
Y558172D01*
G37*
G36*
G01X1011928D02*
X1009724D01*
Y565274D01*
X1010147D01*
Y565582D01*
X1010057Y565642D01*
G02X1011595I769J1172D01*
G01X1011505Y565582D01*
Y565274D01*
X1011928D01*
Y558172D01*
G37*
G36*
G01X1005234D02*
X1003032D01*
Y565274D01*
X1003467D01*
Y565584D01*
X1003375Y565643D01*
G02X1004891I758J1179D01*
G01X1004799Y565584D01*
Y565274D01*
X1005234D01*
Y558172D01*
G37*
G36*
G01X1001888D02*
X999686D01*
Y565274D01*
X1000121D01*
Y565584D01*
X1000029Y565643D01*
G02X1001545I758J1179D01*
G01X1001453Y565584D01*
Y565274D01*
X1001888D01*
Y558172D01*
G37*
G36*
G01X995196D02*
X992992D01*
Y565274D01*
X993428D01*
Y565584D01*
X993336Y565643D01*
G02X994852I758J1179D01*
G01X994760Y565584D01*
Y565274D01*
X995196D01*
Y558172D01*
G37*
G36*
G01X991850D02*
X989646D01*
Y565274D01*
X990082D01*
Y565584D01*
X989990Y565643D01*
G02X991506I758J1179D01*
G01X991414Y565584D01*
Y565274D01*
X991850D01*
Y558172D01*
G37*
G36*
G01X985156D02*
X982954D01*
Y565274D01*
X983375D01*
Y565582D01*
X983285Y565642D01*
G02X984823I769J1172D01*
G01X984733Y565582D01*
Y565274D01*
X985156D01*
Y558172D01*
G37*
G36*
G01X981810D02*
X979606D01*
Y565274D01*
X980029D01*
Y565582D01*
X979939Y565642D01*
G02X981477I769J1172D01*
G01X981387Y565582D01*
Y565274D01*
X981810D01*
Y558172D01*
G37*
G36*
G01X975116D02*
X972914D01*
Y565274D01*
X973336D01*
Y565582D01*
X973246Y565642D01*
G02X974784I769J1172D01*
G01X974694Y565582D01*
Y565274D01*
X975116D01*
Y558172D01*
G37*
G36*
G01X971770D02*
X969568D01*
Y565274D01*
X969990D01*
Y565582D01*
X969900Y565642D01*
G02X971438I769J1172D01*
G01X971348Y565582D01*
Y565274D01*
X971770D01*
Y558172D01*
G37*
G36*
G01X965078D02*
X962874D01*
Y565274D01*
X963297D01*
Y565582D01*
X963207Y565642D01*
G02X964745I769J1172D01*
G01X964655Y565582D01*
Y565274D01*
X965078D01*
Y558172D01*
G37*
G36*
G01X1045037Y538482D02*
Y538189D01*
X1045108Y538129D01*
G02X1043298I-905J-1071D01*
G01X1043369Y538189D01*
Y538482D01*
X1043190D01*
Y545584D01*
X1045392D01*
Y538482D01*
X1045037D01*
G37*
G36*
G01X1088498D02*
Y538176D01*
X1088586Y538116D01*
G02X1087008I-789J-1159D01*
G01X1087096Y538176D01*
Y538482D01*
X1086694D01*
Y545584D01*
X1088896D01*
Y538482D01*
X1088498D01*
G37*
G36*
G01X1085151D02*
Y538176D01*
X1085239Y538116D01*
G02X1083661I-789J-1159D01*
G01X1083749Y538176D01*
Y538482D01*
X1083346D01*
Y545584D01*
X1085550D01*
Y538482D01*
X1085151D01*
G37*
G36*
G01X1078458D02*
Y538176D01*
X1078546Y538116D01*
G02X1076968I-789J-1159D01*
G01X1077056Y538176D01*
Y538482D01*
X1076654D01*
Y545584D01*
X1078856D01*
Y538482D01*
X1078458D01*
G37*
G36*
G01X1065072D02*
Y538176D01*
X1065160Y538116D01*
G02X1063582I-789J-1159D01*
G01X1063670Y538176D01*
Y538482D01*
X1063268D01*
Y545584D01*
X1065472D01*
Y538482D01*
X1065072D01*
G37*
G36*
G01X1055032D02*
Y538176D01*
X1055120Y538116D01*
G02X1053542I-789J-1159D01*
G01X1053630Y538176D01*
Y538482D01*
X1053228D01*
Y545584D01*
X1055432D01*
Y538482D01*
X1055032D01*
G37*
G36*
G01X1051686D02*
Y538176D01*
X1051774Y538116D01*
G02X1050196I-789J-1159D01*
G01X1050284Y538176D01*
Y538482D01*
X1049882D01*
Y545584D01*
X1052086D01*
Y538482D01*
X1051686D01*
G37*
G36*
G01X1004835D02*
Y538176D01*
X1004923Y538116D01*
G02X1003345I-789J-1159D01*
G01X1003433Y538176D01*
Y538482D01*
X1003032D01*
Y545584D01*
X1005234D01*
Y538482D01*
X1004835D01*
G37*
G36*
G01X998142D02*
Y538176D01*
X998230Y538116D01*
G02X996652I-789J-1159D01*
G01X996740Y538176D01*
Y538482D01*
X996340D01*
Y545584D01*
X998542D01*
Y538482D01*
X998142D01*
G37*
G36*
G01X994795D02*
Y538176D01*
X994883Y538116D01*
G02X993305I-789J-1159D01*
G01X993393Y538176D01*
Y538482D01*
X992992D01*
Y545584D01*
X995196D01*
Y538482D01*
X994795D01*
G37*
G36*
G01X988102D02*
Y538176D01*
X988190Y538116D01*
G02X986612I-789J-1159D01*
G01X986700Y538176D01*
Y538482D01*
X986300D01*
Y545584D01*
X988502D01*
Y538482D01*
X988102D01*
G37*
G36*
G01X984756D02*
Y538176D01*
X984844Y538116D01*
G02X983266I-789J-1159D01*
G01X983354Y538176D01*
Y538482D01*
X982954D01*
Y545584D01*
X985156D01*
Y538482D01*
X984756D01*
G37*
G36*
G01X978063D02*
Y538176D01*
X978151Y538116D01*
G02X976573I-789J-1159D01*
G01X976661Y538176D01*
Y538482D01*
X976260D01*
Y545584D01*
X978464D01*
Y538482D01*
X978063D01*
G37*
G36*
G01X974716D02*
Y538176D01*
X974804Y538116D01*
G02X973226I-789J-1159D01*
G01X973314Y538176D01*
Y538482D01*
X972914D01*
Y545584D01*
X975116D01*
Y538482D01*
X974716D01*
G37*
G36*
G01X961330D02*
Y538176D01*
X961418Y538116D01*
G02X959840I-789J-1159D01*
G01X959928Y538176D01*
Y538482D01*
X959528D01*
Y545584D01*
X961730D01*
Y538482D01*
X961330D01*
G37*
G36*
G01X1072164Y520372D02*
X1069962D01*
Y527474D01*
X1070398D01*
Y527784D01*
X1070306Y527843D01*
G02X1071822I758J1179D01*
G01X1071730Y527784D01*
Y527474D01*
X1072164D01*
Y520372D01*
G37*
G36*
G01X1058778D02*
X1056576D01*
Y527474D01*
X1056988D01*
Y527781D01*
X1056899Y527841D01*
G02X1058455I778J1166D01*
G01X1058366Y527781D01*
Y527474D01*
X1058778D01*
Y520372D01*
G37*
G36*
G01X1055432D02*
X1053228D01*
Y527474D01*
X1053665D01*
Y527784D01*
X1053573Y527843D01*
G02X1055089I758J1179D01*
G01X1054997Y527784D01*
Y527474D01*
X1055432D01*
Y520372D01*
G37*
G36*
G01X1048738D02*
X1046536D01*
Y527474D01*
X1046948D01*
Y527781D01*
X1046859Y527841D01*
G02X1048415I778J1166D01*
G01X1048326Y527781D01*
Y527474D01*
X1048738D01*
Y520372D01*
G37*
G36*
G01X1015274D02*
X1013072D01*
Y527474D01*
X1013211D01*
Y527820D01*
X1013072Y527865D01*
G02X1014450Y528169I428J1335D01*
G03X1014721Y527474I271J-295D01*
G01X1015274D01*
Y520372D01*
G37*
G36*
G01X1005234D02*
X1003032D01*
Y527474D01*
X1003467D01*
Y527784D01*
X1003375Y527843D01*
G02X1004891I758J1179D01*
G01X1004799Y527784D01*
Y527474D01*
X1005234D01*
Y520372D01*
G37*
G36*
G01X1001888D02*
X999686D01*
Y527474D01*
X1000121D01*
Y527784D01*
X1000029Y527843D01*
G02X1001545I758J1179D01*
G01X1001453Y527784D01*
Y527474D01*
X1001888D01*
Y520372D01*
G37*
G36*
G01X995196D02*
X992992D01*
Y527474D01*
X993428D01*
Y527784D01*
X993336Y527843D01*
G02X994852I758J1179D01*
G01X994760Y527784D01*
Y527474D01*
X995196D01*
Y520372D01*
G37*
G36*
G01X991850D02*
X989646D01*
Y527474D01*
X990082D01*
Y527784D01*
X989990Y527843D01*
G02X991506I758J1179D01*
G01X991414Y527784D01*
Y527474D01*
X991850D01*
Y520372D01*
G37*
G36*
G01X985156D02*
X982954D01*
Y527474D01*
X983375D01*
Y527782D01*
X983285Y527842D01*
G02X984823I769J1172D01*
G01X984733Y527782D01*
Y527474D01*
X985156D01*
Y520372D01*
G37*
G36*
G01X981810D02*
X979606D01*
Y527474D01*
X980029D01*
Y527782D01*
X979939Y527842D01*
G02X981477I769J1172D01*
G01X981387Y527782D01*
Y527474D01*
X981810D01*
Y520372D01*
G37*
G36*
G01X975116D02*
X972914D01*
Y527474D01*
X973336D01*
Y527782D01*
X973246Y527842D01*
G02X974784I769J1172D01*
G01X974694Y527782D01*
Y527474D01*
X975116D01*
Y520372D01*
G37*
G36*
G01X971770D02*
X969568D01*
Y527474D01*
X969990D01*
Y527782D01*
X969900Y527842D01*
G02X971438I769J1172D01*
G01X971348Y527782D01*
Y527474D01*
X971770D01*
Y520372D01*
G37*
G54D109*
X1950000Y220787D03*
Y228661D03*
G54D112*
X388187Y608555D03*
Y551879D03*
Y589679D03*
Y570755D03*
Y514079D03*
Y532955D03*
X1037797Y50878D03*
Y88678D03*
Y69778D03*
Y13078D03*
Y31978D03*
Y-5822D03*
Y608555D03*
Y551879D03*
Y589679D03*
Y570755D03*
Y514079D03*
Y532955D03*
G54D72*
X44050Y504383D03*
X38389Y523748D03*
X27280Y510420D03*
X47550Y504367D03*
X98633Y78481D03*
X95041Y78451D03*
X91536Y78481D03*
X50500Y205696D03*
X108174Y164127D03*
X123624Y164600D03*
X234501Y270392D03*
X224390Y258920D03*
X230800Y265200D03*
X219500Y254500D03*
X195300Y229250D03*
X219000Y335900D03*
X229100Y325900D03*
X224000Y330900D03*
X234000Y320900D03*
X214000Y340900D03*
X378577Y309795D03*
X374994Y309910D03*
X378294Y292904D03*
X605176Y487581D03*
X628589Y463649D03*
X641107Y471989D03*
X632771Y473269D03*
X629359Y469583D03*
X695790Y351300D03*
X747000Y386000D03*
X743500D03*
X750500D03*
X754000D03*
X743500Y374000D03*
X747000D03*
X754000D03*
X750500D03*
X743500Y380000D03*
X747000D03*
X818960Y202230D03*
X814849Y205001D03*
X808165Y203529D03*
X803134Y202969D03*
X792514Y201290D03*
X844400Y280500D03*
X845050Y229400D03*
X844350Y344000D03*
X844300Y312450D03*
X889586Y274278D03*
X884586Y269278D03*
X879586Y264278D03*
X874586Y259278D03*
X869586Y254278D03*
X877008Y326100D03*
X867008Y336100D03*
X872008Y331100D03*
X862008Y341100D03*
X1028136Y309815D03*
X1017083Y309910D03*
X1431664Y190213D03*
X1463369Y561763D03*
X1567425Y144373D03*
X1570020Y295340D03*
X1608099Y197125D03*
X1608280Y249234D03*
X1681586Y141438D03*
X1693586Y142438D03*
X1689785Y161180D03*
X1688207Y168972D03*
X1758324Y232657D03*
X1758000Y250000D03*
X1828390Y165600D03*
X1832000Y165800D03*
X1852654Y164624D03*
X1847654D03*
X1882669Y454368D03*
X1954271Y80449D03*
X1908400Y101010D03*
G54D94*
X1643803Y570630D03*
X1646756Y565118D03*
Y580079D03*
Y610000D03*
X1643803Y600551D03*
Y615512D03*
X1691047Y570630D03*
X1694000Y565118D03*
Y580079D03*
Y610000D03*
X1691047Y600551D03*
Y615512D03*
G54D76*
X85609Y385234D03*
X710800Y7100D03*
X705250Y8600D03*
X1301240Y476228D03*
X1490821Y73750D03*
X1573121Y120649D03*
X1591865Y237407D03*
X1569926Y308064D03*
X1576074Y359600D03*
X1590530Y610620D03*
X1598028Y256422D03*
X1600552Y261281D03*
X1640001Y370790D03*
X1644856Y604930D03*
X1640921Y605334D03*
X1680139Y99073D03*
X1695734Y164676D03*
X1663566Y213009D03*
X1687741Y466988D03*
X1759093Y9310D03*
X1761872Y-7220D03*
X1734875Y9238D03*
X1777000Y115750D03*
X1778000Y120000D03*
X1723189Y176012D03*
X1789356Y38286D03*
X1780720Y153850D03*
X1784750Y124000D03*
X1836396Y481349D03*
X1847000Y198600D03*
X1949389Y152083D03*
X1963092Y167936D03*
X1944550Y176450D03*
X1950981Y168064D03*
X1966700Y152400D03*
X251213Y646784D03*
Y652784D03*
X261125Y646784D03*
Y652784D03*
X389473Y646508D03*
Y652508D03*
X379561Y646508D03*
Y652508D03*
X448593Y652514D03*
Y646514D03*
X438681D03*
Y652514D03*
X567029Y652238D03*
Y646238D03*
X576941D03*
Y652238D03*
X951795Y652234D03*
Y646234D03*
X941883D03*
Y652234D03*
X1196198Y652206D03*
Y646206D03*
X1206110D03*
Y652206D03*
X1265293Y652264D03*
Y646264D03*
X1255381D03*
Y652264D03*
X1509696Y652236D03*
Y646236D03*
X1519608D03*
Y652236D03*
G54D111*
X1912406Y518328D03*
X1904532D03*
G54D69*
X10512Y467244D03*
X20512D03*
X50512D03*
X1884100Y493000D03*
X1894100D03*
X1891086Y592105D03*
Y612105D03*
Y602105D03*
X1904100Y493000D03*
G54D96*
X1779504Y-15000D03*
G54D84*
X1454902Y273603D03*
X1451754Y283053D03*
X1442304Y273603D03*
X1448603Y276753D03*
X1445454Y279902D03*
X1464351D03*
X1461300Y270400D03*
X1442303Y270454D03*
Y267303D03*
X1454902Y276753D03*
X1451753Y279902D03*
X1464351Y283052D03*
X1448603Y267304D03*
Y270454D03*
X1451753Y273603D03*
X1445454D03*
X1461202D03*
Y279902D03*
X1464351Y276753D03*
X1448603Y279902D03*
X1461202Y276753D03*
X1451753Y270454D03*
X1458052Y279902D03*
X1454902Y283052D03*
X1461400Y264700D03*
X1442304Y279902D03*
X1445454Y276753D03*
X1458052D03*
Y273603D03*
X1458102Y270402D03*
X1461202Y283052D03*
X1445454Y267304D03*
X1464424Y273676D03*
X1454902Y270454D03*
X1448603Y283053D03*
X1442304Y305098D03*
X1445454Y308247D03*
X1451753Y286202D03*
X1448603D03*
Y314546D03*
X1454928Y317723D03*
X1445427Y292526D03*
X1461202Y305098D03*
X1440910Y316693D03*
X1458052Y298798D03*
X1451753Y317696D03*
X1458052Y305098D03*
X1448603Y317696D03*
X1458400Y318500D03*
X1445454Y305098D03*
X1448603D03*
X1454902Y308247D03*
X1451753Y305098D03*
X1464351Y298798D03*
X1461202D03*
Y295649D03*
X1445528Y317772D03*
X1461202Y286202D03*
X1464351D03*
X1461202Y289351D03*
X1442303Y298799D03*
X1454902Y301948D03*
X1461202D03*
Y314546D03*
X1464350Y308247D03*
X1458052Y289351D03*
X1448603D03*
X1442304Y292499D03*
X1445427Y295624D03*
X1448577D03*
X1451751Y295649D03*
X1454902Y286202D03*
Y314546D03*
Y311397D03*
X1463610Y321329D03*
X1451753Y301948D03*
X1445454D03*
X1464351Y311397D03*
X1461202D03*
X1458052Y308247D03*
X1454902Y289351D03*
X1458052Y286202D03*
X1464351Y301948D03*
X1451753Y298798D03*
X1458052Y311397D03*
X1442304Y289350D03*
X1445454Y311397D03*
X1442304D03*
X1454902Y298798D03*
X1464351Y305098D03*
X1458052Y295649D03*
X1448603Y301948D03*
X1442304Y308247D03*
X1448603Y298798D03*
X1445454D03*
X1451753Y289351D03*
X1445454D03*
X1451753Y311397D03*
X1458052Y314546D03*
X1462776Y318200D03*
X1451753Y314546D03*
X1448603Y308247D03*
X1473798Y273603D03*
X1496030Y267665D03*
X1486397Y283052D03*
X1470649Y273603D03*
X1486574Y267127D03*
X1476948Y276753D03*
X1480098D03*
X1483247Y279902D03*
X1473798D03*
X1480098Y283052D03*
X1476948Y279902D03*
X1483247Y267304D03*
X1486397Y270454D03*
X1480098Y273603D03*
X1473798Y283052D03*
X1483247D03*
X1469829Y266909D03*
X1473798Y270454D03*
X1476948D03*
X1480098Y267304D03*
X1470649Y276753D03*
X1476948Y273603D03*
X1470649Y270454D03*
Y283052D03*
Y279902D03*
X1473798Y276753D03*
X1489546Y279902D03*
X1483247Y270454D03*
Y273603D03*
X1480098Y270454D03*
X1473798Y305098D03*
X1480098Y301948D03*
Y298798D03*
X1493400Y300800D03*
X1486397Y298798D03*
X1480098Y295649D03*
X1476948Y298798D03*
X1486397Y305098D03*
X1470649Y298798D03*
Y286202D03*
X1473798Y295649D03*
X1483247Y305098D03*
X1480098Y308247D03*
X1473798Y298798D03*
Y289351D03*
Y286202D03*
Y308247D03*
X1476948Y305098D03*
X1497509Y303120D03*
X1489546Y308247D03*
X1476948Y289351D03*
X1480098Y286202D03*
X1476948Y311397D03*
X1480098Y314546D03*
X1486397Y286202D03*
X1489546D03*
Y317696D03*
X1470649Y305098D03*
X1486397Y295649D03*
Y308247D03*
X1483247Y298798D03*
X1473798Y301948D03*
X1476948Y295649D03*
X1486396Y317696D03*
X1483247Y289351D03*
X1476948Y308247D03*
X1470649Y311397D03*
X1473798Y314546D03*
X1470649Y301948D03*
X1483247Y314546D03*
X1489546Y301948D03*
Y311397D03*
X1483247Y286202D03*
X1470649Y308247D03*
X1486397Y314546D03*
X1483247Y311397D03*
X1495300Y297300D03*
X1478524Y318900D03*
X1480098Y311397D03*
X1483247Y301948D03*
X1473798Y311397D03*
X1493500Y304400D03*
X1486397Y301948D03*
X1470649Y314546D03*
X1476948Y286202D03*
X1588176Y157600D03*
X1591950Y158250D03*
X1590569Y152464D03*
X1604000Y93925D03*
X1607442Y159585D03*
X1616891Y150137D03*
X1654686Y109191D03*
X1613741Y146987D03*
X1648387Y159585D03*
X1651536D03*
X1632574Y106107D03*
X1620100Y153300D03*
X1613741Y121790D03*
X1610591D03*
X1629489Y115491D03*
X1632615Y109215D03*
X1632638Y112341D03*
Y115491D03*
X1616890Y112341D03*
X1616848Y115449D03*
X1654673Y118628D03*
X1654685Y112341D03*
X1613741Y153286D03*
X1648387Y115491D03*
X1651536D03*
X1610591Y112341D03*
X1607441Y115491D03*
X1610591Y118640D03*
X1607441Y112341D03*
X1616891Y128089D03*
X1620040Y134388D03*
Y128089D03*
X1629489Y153286D03*
X1613741Y118640D03*
X1610645Y143783D03*
X1600148Y142262D03*
X1610591Y159585D03*
X1604292Y150137D03*
X1607401Y146947D03*
X1600182Y148562D03*
X1600148Y151711D03*
X1596427Y157975D03*
X1600490Y158010D03*
X1610591Y156436D03*
X1604169Y156407D03*
X1610591Y153286D03*
X1607441Y156436D03*
X1651536Y156435D03*
X1613741Y106042D03*
Y109191D03*
X1616890Y118641D03*
X1638938Y159585D03*
X1616900Y143880D03*
X1653111Y102240D03*
X1645237Y115491D03*
X1641770Y112340D03*
X1607441Y134389D03*
X1610591Y140688D03*
Y137538D03*
Y124939D03*
Y150137D03*
X1613741Y159585D03*
Y137538D03*
X1607441Y153286D03*
X1600900Y131900D03*
X1595390Y151778D03*
X1629489Y159585D03*
X1635788D03*
X1642087D03*
X1610591Y134389D03*
X1613741Y140688D03*
X1613690Y124990D03*
X1613741Y134389D03*
X1608000Y99400D03*
X1607441Y143837D03*
X1610591Y146987D03*
X1645237Y112341D03*
X1607441Y106042D03*
X1654638Y159685D03*
X1613741Y150137D03*
Y156436D03*
X1626339Y115491D03*
X1613741Y128089D03*
X1620040Y159585D03*
X1626339Y118651D03*
Y109191D03*
X1626300Y112300D03*
X1651536Y112341D03*
X1623200Y153100D03*
X1607441Y124939D03*
X1654685Y143837D03*
X1651536Y146988D03*
X1654686Y150138D03*
X1654685Y140687D03*
X1654686Y124940D03*
Y134389D03*
X1654685Y131239D03*
X1654686Y153288D03*
X1651536Y128089D03*
X1635750Y128240D03*
X1642087Y143837D03*
X1623190Y124940D03*
Y128089D03*
Y134388D03*
Y140687D03*
Y146987D03*
X1635788Y153286D03*
X1626339Y150136D03*
X1637363Y149484D03*
X1645237Y124940D03*
X1642087D03*
X1651536Y134388D03*
Y131239D03*
Y124939D03*
Y140687D03*
Y143837D03*
X1626364Y121765D03*
X1635788Y118640D03*
X1632639D03*
X1642150Y118660D03*
X1645237Y118640D03*
X1626313Y153312D03*
X1642087Y153286D03*
X1632638D03*
X1620100Y150200D03*
X1620040Y146987D03*
Y140687D03*
X1632639Y124940D03*
X1648393Y153280D03*
X1651532Y137534D03*
X1626339Y124940D03*
X1645237Y159585D03*
X1607441Y121790D03*
X1604292Y137538D03*
X1607239Y131358D03*
X1626339Y159585D03*
X1623189D03*
X1629400Y106131D03*
X1629487Y109280D03*
X1642084Y115494D03*
X1629489Y112341D03*
X1648387D03*
Y109191D03*
X1651536D03*
X1607441Y137538D03*
X1604292Y134388D03*
X1616890Y159585D03*
X1610591Y128089D03*
X1654686Y156436D03*
X1610591Y115491D03*
X1648386Y156435D03*
X1645237Y109191D03*
X1594565Y148720D03*
X1613741Y162735D03*
X1607441D03*
X1645237Y165884D03*
X1626339Y162735D03*
X1623276Y165798D03*
X1600490Y167459D03*
X1629489Y162735D03*
X1624966Y172936D03*
X1621942Y173237D03*
X1629489Y165884D03*
X1645151Y162649D03*
X1642101Y162749D03*
X1610591Y162735D03*
X1651536Y165884D03*
X1622217Y177809D03*
X1654685Y162735D03*
X1613741Y165885D03*
X1616891D03*
X1638938Y162735D03*
X1635788Y165885D03*
X1642088D03*
X1638938Y165884D03*
X1608731Y180819D03*
X1620006Y168956D03*
X1620041Y165885D03*
X1616890Y162735D03*
X1651536D03*
X1610591Y165885D03*
X1648320Y172690D03*
X1648326Y162674D03*
X1648386Y165885D03*
X1623250Y162611D03*
X1626339Y165884D03*
X1635788Y162735D03*
X1643662Y172609D03*
X1660985Y159585D03*
X1657835Y115491D03*
Y109191D03*
X1660985D03*
X1670434Y115491D03*
X1667284D03*
X1660985D03*
X1664135Y118640D03*
X1657835Y112341D03*
X1660985D03*
X1667238Y112387D03*
X1660985Y156435D03*
X1660986Y137538D03*
X1657835Y143837D03*
X1664186Y147038D03*
X1657835Y146987D03*
X1660985Y150137D03*
X1657836Y153288D03*
X1664135Y153286D03*
X1660985Y143837D03*
X1664136Y137538D03*
X1695236Y138938D03*
Y135788D03*
X1664135Y121790D03*
X1660985Y128089D03*
Y121790D03*
X1657835D03*
X1667284Y131239D03*
X1664135Y128089D03*
X1660985Y131239D03*
Y124939D03*
X1677386Y132788D03*
Y129638D03*
X1676886Y120038D03*
Y123188D03*
X1660985Y146987D03*
X1657836Y137538D03*
Y140688D03*
X1660985D03*
X1664134Y156436D03*
X1667348Y156500D03*
X1664135Y112341D03*
Y115491D03*
X1660985Y118640D03*
X1657835D03*
Y159585D03*
Y165884D03*
Y162735D03*
X1665063Y172608D03*
X1660985Y165885D03*
Y162735D03*
X1723314Y98550D03*
X1717014Y97550D03*
X1735914Y139500D03*
X1723314Y142650D03*
X1735989Y133250D03*
X1739064Y145800D03*
X1728789Y136250D03*
X1723264Y145850D03*
X1735989Y149050D03*
X1726539Y139450D03*
X1734989Y142750D03*
X1720164Y139500D03*
X1739064Y142650D03*
X1720164Y145800D03*
X1742214D03*
X1726464D03*
X1739064Y139500D03*
X1723314D03*
X1739064Y136350D03*
Y126900D03*
X1723314Y130050D03*
Y126900D03*
X1726464Y133200D03*
Y111150D03*
X1739064Y120600D03*
X1735914Y104850D03*
X1723314D03*
X1720164Y108000D03*
X1735914D03*
X1723314D03*
X1739064Y123750D03*
X1726464Y120600D03*
X1742214D03*
X1723314Y120601D03*
X1735912Y123750D03*
X1726464D03*
X1720164Y104850D03*
X1739064Y117450D03*
X1735914D03*
X1723314Y101700D03*
X1731789Y139450D03*
X1717014Y142650D03*
X1739064Y130050D03*
X1746189Y153250D03*
X1723314Y133200D03*
X1742214Y142650D03*
X1746189Y134777D03*
X1742214Y130050D03*
X1745768Y111743D03*
X1745363Y108004D03*
X1735914Y101700D03*
X1742214Y114300D03*
Y123750D03*
X1745364D03*
X1723314D03*
X1720164D03*
Y117451D03*
X1726464Y117450D03*
X1745364Y142650D03*
X1746189Y131624D03*
X1745364Y117450D03*
X1717014Y133200D03*
Y111150D03*
Y104850D03*
X1745500Y104500D03*
G54D80*
X1392264Y23976D03*
X1513918D03*
G54D66*
X-10236Y116969D03*
X-4725D03*
X23228Y124843D03*
X17716D03*
X-10236Y132717D03*
X-4725D03*
X6299D03*
X11811D03*
X17716Y140591D03*
X23228D03*
X-10236Y373110D03*
X-4725D03*
X23228Y380984D03*
X17716D03*
X-10236Y388858D03*
X-4725D03*
X6299D03*
X11811D03*
X17716Y396732D03*
X23228D03*
G54D87*
X1527844Y80791D03*
X1724606Y235430D03*
G54D78*
X476672Y220096D03*
X480052Y210346D03*
Y225947D03*
X476672Y235696D03*
X483432Y216196D03*
X531871Y202547D03*
X525111D03*
X483432Y212296D03*
Y231797D03*
Y239596D03*
X501452Y337096D03*
X531871Y331247D03*
X525111Y323446D03*
X531871D03*
X525111Y327347D03*
X528491Y333196D03*
X521731Y329296D03*
X518352Y335147D03*
X521731Y340996D03*
X525111Y319547D03*
X528491Y321496D03*
Y325396D03*
Y329296D03*
X525111Y331247D03*
X521731Y333196D03*
Y337096D03*
X535251Y344896D03*
X542011D03*
Y340996D03*
Y337096D03*
X538631Y331247D03*
Y327347D03*
X535251Y340996D03*
X538631Y342947D03*
X542011Y333196D03*
Y329296D03*
Y325396D03*
X538631Y323446D03*
X535251Y337096D03*
X528491Y340996D03*
X531871Y339047D03*
Y342947D03*
X528491Y344896D03*
X491312Y342947D03*
X484552Y389747D03*
X494692Y399496D03*
X491312Y393647D03*
X487932Y383896D03*
X484552Y374146D03*
X511592Y362447D03*
X514972Y368296D03*
X508212Y364396D03*
X498072Y378047D03*
X494692Y379996D03*
Y387796D03*
X518352Y350747D03*
Y354647D03*
X511592Y358547D03*
X514972Y360496D03*
Y364396D03*
X511592Y366347D03*
X508212Y368296D03*
Y372197D03*
X504832Y374146D03*
X501452Y376096D03*
X498072Y381947D03*
X494692Y383896D03*
X518352Y346847D03*
X521731Y352696D03*
X511592Y354647D03*
X498072Y374146D03*
X528491Y387796D03*
X521731D03*
Y391696D03*
X518352Y393647D03*
X514972Y395597D03*
X511592Y389747D03*
X528491Y379996D03*
Y383896D03*
X525111Y385847D03*
X521731Y383896D03*
X525111Y389747D03*
X521731Y395597D03*
X514972Y391696D03*
Y387796D03*
X528491Y376096D03*
X531871Y381947D03*
X535251Y348796D03*
X538631Y346847D03*
Y354647D03*
Y358547D03*
Y362447D03*
X531871D03*
Y366347D03*
X535251Y372197D03*
Y379996D03*
X538631Y350747D03*
X542011Y356596D03*
X535251Y360496D03*
X531871Y358547D03*
X535251Y364396D03*
Y368296D03*
X538631Y374146D03*
X531871Y378047D03*
X525111Y346847D03*
X528491Y348796D03*
Y352696D03*
X487932Y356596D03*
X491312Y354647D03*
X511592Y401447D03*
X508212Y383896D03*
X514972Y376096D03*
X504832Y401446D03*
X552151Y331247D03*
Y335147D03*
Y342947D03*
X548771Y344896D03*
Y333196D03*
X552151Y339047D03*
X555531Y340996D03*
X545391Y327347D03*
Y339047D03*
X562591Y340996D03*
X558911Y339047D03*
X555531Y344896D03*
X562591Y337096D03*
X555531D03*
X552151Y346847D03*
X548771Y387796D03*
X552151Y385847D03*
X555531Y352696D03*
Y348796D03*
X552151Y354647D03*
X558911Y350747D03*
X559211Y366347D03*
X555531Y379996D03*
X552151Y381947D03*
X558911Y354647D03*
X552151Y362447D03*
X545391Y350747D03*
X548771Y348796D03*
X947887Y324160D03*
X937747Y322209D03*
X930987D03*
X941127Y324160D03*
G54D108*
X1892720Y525415D03*
X1900595D03*
X1894689Y518328D03*
X1908469Y525415D03*
X1916343D03*
X1924217D03*
G54D90*
X1627642Y-14488D03*
X1647327Y-315D03*
X1667012Y-14488D03*
X1969291Y486064D03*
Y497874D03*
G54D49*
X1630386Y413942D03*
X1634400Y412900D03*
X1630120Y418887D03*
X1621347Y415297D03*
X1603000Y422971D03*
X1611418D03*
X1673800Y201070D03*
X1681352Y196092D03*
X1469000Y345850D03*
X-19210Y162529D03*
X-17014Y455604D03*
X-17200Y510800D03*
X-17302Y506798D03*
X-13500Y486400D03*
X-14800Y526100D03*
X-18160Y522609D03*
X-19802Y476738D03*
X-19783Y481286D03*
X-16186Y519304D03*
X-12600Y578900D03*
X-14971Y540000D03*
X-17500Y574000D03*
X8660Y27274D03*
X43960Y20572D03*
X-3560Y34620D03*
X-10850Y30800D03*
X2871Y22791D03*
X19964Y18793D03*
X2934Y26933D03*
X16550Y18300D03*
X602Y30502D03*
X25827Y-16958D03*
X8988Y58267D03*
X-1750Y43320D03*
X-1920Y47290D03*
X11925Y74867D03*
X11864Y71294D03*
X11539Y39927D03*
X11500Y43400D03*
X-1470Y63910D03*
X37037Y138425D03*
X39109Y154901D03*
X5120Y276058D03*
X2269Y273532D03*
X1500Y295000D03*
X47100Y327000D03*
X49200Y340650D03*
X10365Y461602D03*
X37550Y425400D03*
X40965Y429434D03*
X2450Y460000D03*
X-9600Y526100D03*
X-6650Y487800D03*
X-5680Y524570D03*
X47800Y487600D03*
X3354Y517143D03*
X6748Y517021D03*
X-6200Y505400D03*
X-6676Y501800D03*
X10932Y523601D03*
X14700Y517000D03*
X-9900Y486400D03*
X-2430Y524340D03*
X-7360Y512000D03*
X-6712Y515731D03*
X-2083Y513704D03*
X-4350Y482100D03*
X-900Y482300D03*
X22491Y500618D03*
X2350Y469650D03*
X-8318Y542216D03*
X-8200Y578600D03*
X-3100Y533991D03*
X-2500Y569500D03*
X-10947Y544117D03*
X-4300Y558400D03*
X-4100Y554400D03*
X1439Y546583D03*
X1539Y550183D03*
Y586183D03*
X1439Y582583D03*
X-9287Y531604D03*
X-6566Y568363D03*
X-9291Y535201D03*
X-9283Y571324D03*
X-4500Y594000D03*
X93500Y-18000D03*
X82300Y-16600D03*
X53382Y-1173D03*
X52744Y-4368D03*
X74386Y-18439D03*
X71172Y-18486D03*
X87091Y-16391D03*
X106000Y17260D03*
X52389Y-14258D03*
X60035Y7508D03*
X51090Y8080D03*
X54307Y-8051D03*
X104500Y-1850D03*
X76106Y89337D03*
X86600Y94000D03*
X70980Y97166D03*
X105898Y55194D03*
X82046Y90043D03*
X98420Y112198D03*
X99250Y160370D03*
X104424Y110833D03*
X87200Y152374D03*
X91913Y121318D03*
X77790Y121030D03*
X79670Y132300D03*
X75660Y152380D03*
X78950Y152810D03*
X91306Y157194D03*
X61800Y191600D03*
X76143Y183019D03*
X61356Y181000D03*
X61256Y186000D03*
X90831Y184982D03*
X86731Y189148D03*
X107700Y211040D03*
X104820Y202100D03*
X102507Y211047D03*
X99500Y223800D03*
X97200Y265000D03*
X99758Y240300D03*
X88000Y343900D03*
X103500Y304700D03*
X104600Y316602D03*
X103500Y308500D03*
X103200Y330190D03*
X102322Y295478D03*
X60400Y355750D03*
X57395Y366795D03*
X55500Y371700D03*
X109500Y370000D03*
X61914Y368731D03*
X57800Y376100D03*
X60565Y380131D03*
X65000Y383000D03*
X74800Y379700D03*
X80200D03*
X62600Y375100D03*
X87900Y347500D03*
X93712Y380507D03*
X97472Y380934D03*
X90518Y388828D03*
X54900Y389400D03*
X110452Y407092D03*
X79100Y347000D03*
X61041Y351737D03*
X74800Y383114D03*
X66016Y468350D03*
X106392Y527413D03*
X59731Y480066D03*
X71050Y478670D03*
X86100Y505200D03*
X105392Y566000D03*
X102236Y614167D03*
X106192Y604600D03*
X132959Y33700D03*
X163391D03*
X157084Y34100D03*
X126580Y33700D03*
X150391Y34100D03*
X169770Y33700D03*
X132959Y-4100D03*
X130313Y17157D03*
X163391Y-4100D03*
X160431Y17157D03*
X163477Y12114D03*
X132959D03*
X157084Y-3700D03*
X153738Y17157D03*
X157084Y12114D03*
X126580Y-4100D03*
X123620Y17157D03*
X126666Y12114D03*
X147045Y17157D03*
X150391Y-3700D03*
Y12114D03*
X169770Y-4100D03*
X167124Y17157D03*
X169770Y12114D03*
X114680Y17320D03*
X120273Y9157D03*
X116070Y35780D03*
X114050Y21320D03*
X116692Y-1800D03*
X116300Y-9460D03*
X132959Y71500D03*
X130313Y92757D03*
X163391Y71500D03*
X160431Y92757D03*
X163477Y87714D03*
X132959D03*
X157084Y71900D03*
X153738Y92757D03*
X157084Y87714D03*
X126580Y71500D03*
X123620Y92757D03*
X126666Y87714D03*
X150391Y71900D03*
X147045Y92757D03*
X150391Y87714D03*
X169770Y71500D03*
X167124Y92757D03*
X169770Y87714D03*
X130313Y54957D03*
X160431D03*
X163477Y49914D03*
X132959D03*
X153738Y54957D03*
X157084Y49914D03*
X123620Y54957D03*
X126666Y49914D03*
X147045Y54957D03*
X150391Y49914D03*
X167124Y54957D03*
X169770Y49914D03*
X119892Y84700D03*
X120273Y46957D03*
X116200Y70387D03*
X115980Y73680D03*
X117600Y193805D03*
X122542Y214019D03*
X150000Y194850D03*
Y199850D03*
X162800Y195600D03*
X162788Y200650D03*
X124340Y197750D03*
X122203Y246675D03*
X122400Y278671D03*
X125563Y234316D03*
X125663Y230716D03*
X125563Y227116D03*
Y259116D03*
X125663Y262716D03*
X125563Y266316D03*
X122361Y342649D03*
X122493Y310633D03*
X125663Y294716D03*
X125563Y298316D03*
Y291116D03*
Y323116D03*
X125663Y326716D03*
X122473Y374716D03*
X153392Y404000D03*
X167640Y404842D03*
X118220Y360500D03*
X125563Y355116D03*
X125663Y358716D03*
Y390716D03*
X125563Y387116D03*
Y394316D03*
X151909Y413267D03*
X148409Y422239D03*
X153392Y407500D03*
X167680Y408440D03*
X157862Y416012D03*
X150650Y409860D03*
X130313Y518157D03*
X160431D03*
X163477Y513114D03*
X132959D03*
X153738Y518157D03*
X157084Y513114D03*
X123620Y518157D03*
X126666Y513114D03*
X147045Y518157D03*
X150391Y513114D03*
X167124Y518157D03*
X169770Y513114D03*
X119892Y510100D03*
X116927Y517900D03*
X132959Y534700D03*
X163391D03*
X157084Y535100D03*
X126580Y534700D03*
X150391Y535100D03*
X169770Y534700D03*
X130313Y555957D03*
X132959Y572500D03*
X160431Y555957D03*
X163391Y572500D03*
X163477Y550914D03*
X132959D03*
X153738Y555957D03*
X157084Y572900D03*
Y550914D03*
X123620Y555957D03*
X126580Y572500D03*
X126666Y550914D03*
X147045Y555957D03*
X150391Y572900D03*
Y550914D03*
X167124Y555957D03*
X169770Y572500D03*
Y550914D03*
X163477Y588714D03*
X132959D03*
X157084D03*
X126666D03*
X150391D03*
X169770D03*
X113692Y566000D03*
X119892Y547900D03*
Y585700D03*
X114150Y585850D03*
X114509Y575658D03*
X116927Y555700D03*
X115883Y548024D03*
X132959Y610300D03*
X130313Y593757D03*
X163391Y610300D03*
X160431Y593757D03*
X157084Y610700D03*
X153738Y593757D03*
X126580Y610300D03*
X123620Y593757D03*
X150391Y610700D03*
X147045Y593757D03*
X167124D03*
X169770Y610300D03*
X114792Y604600D03*
X116927Y593500D03*
X193895Y34100D03*
X187202D03*
X206581Y33700D03*
X230706Y34100D03*
X200202Y33700D03*
X224013Y34100D03*
X193895Y-3700D03*
X190549Y17157D03*
X193895Y12114D03*
X187202Y-3700D03*
X183856Y17157D03*
X187202Y12114D03*
X206581Y-4100D03*
X203935Y17157D03*
X206581Y12114D03*
X230706Y-3700D03*
X227360Y17157D03*
X230706Y12114D03*
X200202Y-4100D03*
X197242Y17157D03*
X200288Y12114D03*
X224013Y-3700D03*
X220667Y17157D03*
X224013Y12114D03*
X234053Y17157D03*
X193895Y71900D03*
X190549Y92757D03*
X193895Y87714D03*
X187202Y71900D03*
X183856Y92757D03*
X187202Y87714D03*
X206581Y71500D03*
X203935Y92757D03*
X206581Y87714D03*
X230706Y71900D03*
X227360Y92757D03*
X230706Y87714D03*
X200202Y71500D03*
X197242Y92757D03*
X200288Y87714D03*
X224013Y71900D03*
X220667Y92761D03*
X224013Y87714D03*
X234053Y92757D03*
X190549Y54957D03*
X193895Y49914D03*
X183856Y54957D03*
X187202Y49914D03*
X203935Y54957D03*
X206581Y49914D03*
X227360Y54957D03*
X230706Y49914D03*
X197242Y54957D03*
X200288Y49914D03*
X220667Y54957D03*
X224013Y49914D03*
X234053Y54957D03*
Y112327D03*
X206600Y372400D03*
X190549Y518157D03*
X193895Y513114D03*
X183856Y518157D03*
X187202Y513114D03*
X203935Y518157D03*
X206581Y513114D03*
X227360Y518157D03*
X230706Y513114D03*
X197242Y518157D03*
X200288Y513114D03*
X220667Y518161D03*
X224013Y513114D03*
X234053Y518157D03*
X233292Y498500D03*
X193895Y535100D03*
X187202D03*
X206581Y534700D03*
X230706Y535100D03*
X200202Y534700D03*
X224013Y535100D03*
X190549Y555957D03*
X193895Y572900D03*
Y550914D03*
X183856Y555957D03*
X187202Y572900D03*
Y550914D03*
X203935Y555957D03*
X206581Y572500D03*
Y550914D03*
X227360Y555957D03*
X230706Y572900D03*
Y550914D03*
X197242Y555957D03*
X200202Y572500D03*
X200288Y550914D03*
X220667Y555961D03*
X224013Y572900D03*
Y550914D03*
X234053Y555957D03*
X193895Y588714D03*
X187202D03*
X206581D03*
X230706D03*
X200288D03*
X224013D03*
X190549Y593757D03*
X193895Y610700D03*
X183856Y593757D03*
X187202Y610700D03*
X206581Y610300D03*
X203935Y593757D03*
X230706Y610700D03*
X227360Y593757D03*
X197242D03*
X200202Y610300D03*
X224013Y610700D03*
X220667Y593761D03*
X234053Y593757D03*
X243392Y33700D03*
X267517Y34100D03*
X237013Y33700D03*
X260824Y34100D03*
X280203Y33700D03*
X273824D03*
X243392Y-4100D03*
X240746Y17157D03*
X243392Y12114D03*
X267517Y-3700D03*
X264171Y17157D03*
X267517Y12114D03*
X237013Y-4100D03*
X237099Y12114D03*
X260824Y-3700D03*
X257478Y17157D03*
X260824Y12114D03*
X280203Y-4100D03*
X277557Y17157D03*
X280203Y12114D03*
X270864Y17157D03*
X273824Y-4100D03*
X273910Y12114D03*
X294289Y17157D03*
X243392Y71500D03*
X240746Y92757D03*
X243392Y87714D03*
X267517Y71900D03*
X264171Y92757D03*
X267517Y87714D03*
X237013Y71500D03*
X237099Y87714D03*
X260824Y71900D03*
X257478Y92757D03*
X260824Y87714D03*
X280203Y71500D03*
X277557Y92757D03*
X280203Y87714D03*
X270864Y92757D03*
X273824Y71500D03*
X273910Y87714D03*
X294289Y92757D03*
X240746Y54957D03*
X243392Y49914D03*
X264171Y54957D03*
X267517Y49914D03*
X237099D03*
X257478Y54957D03*
X260824Y49914D03*
X277557Y54957D03*
X280203Y49914D03*
X270864Y54957D03*
X273910Y49914D03*
X294289Y54957D03*
X240746Y112327D03*
X243392Y106934D03*
X264171Y112327D03*
X267517Y107284D03*
X237099D03*
X257478Y112327D03*
X260824Y107284D03*
X277557Y112327D03*
X280203Y106934D03*
X270864Y112327D03*
X273910Y107284D03*
X294889Y110927D03*
X274619Y205210D03*
X271239Y207159D03*
X277999Y218860D03*
X281379Y216909D03*
X284759Y218860D03*
X294899Y216909D03*
Y220809D03*
X288139D03*
X284759Y203260D03*
Y211060D03*
X294899Y205210D03*
Y209109D03*
X281379Y205210D03*
Y209109D03*
X291519Y203260D03*
Y211060D03*
X288139Y201309D03*
Y213009D03*
Y205210D03*
Y209109D03*
X267859D03*
X277999Y199360D03*
X274619Y201309D03*
X271239Y203260D03*
X294899Y197409D03*
X274619Y209109D03*
X264179Y257860D03*
X281379Y228610D03*
X288139Y224709D03*
X271239Y257860D03*
X284759Y230559D03*
X288139Y228610D03*
X277999Y222760D03*
X264092Y242260D03*
X271239D03*
X264179Y261760D03*
X271239D03*
X264179Y246160D03*
X271239D03*
Y250060D03*
X277999Y226660D03*
X271239Y253960D03*
X267859Y248109D03*
X281379Y224709D03*
X284759Y222760D03*
X267859Y255909D03*
X281379Y267609D03*
X277999Y238360D03*
X281379Y236409D03*
X284759Y250060D03*
X288139Y248109D03*
X277999Y242260D03*
X284759Y238360D03*
X288139Y263709D03*
X277999Y257860D03*
X281379Y255909D03*
X284759Y269560D03*
X288139Y267609D03*
X277999Y261760D03*
X284759Y257860D03*
X281379Y248109D03*
X288139Y244209D03*
Y259809D03*
X277999Y246160D03*
X288139Y240309D03*
X277999Y265660D03*
X284759Y261760D03*
X281379Y244209D03*
X284759Y242260D03*
X281379Y263709D03*
X294899Y232509D03*
Y236409D03*
Y252009D03*
Y255909D03*
Y240309D03*
Y259809D03*
X239778Y274478D03*
X271239Y277360D03*
Y281260D03*
X267392Y276000D03*
X267359Y279310D03*
Y283209D03*
X288139Y279310D03*
X284759Y281260D03*
X291519D03*
X277999D03*
X274619Y279310D03*
Y283209D03*
X288139D03*
X281379Y279310D03*
Y283209D03*
X294899D03*
Y279310D03*
X267859Y271509D03*
X264179Y273460D03*
X274619Y271509D03*
X294899D03*
Y267609D03*
X291519Y273460D03*
X277999D03*
X271239Y335860D03*
X264179D03*
X271239Y331960D03*
X264179D03*
X271239Y343660D03*
Y339760D03*
X267859Y345609D03*
Y337809D03*
X288139Y333909D03*
X281379Y330009D03*
Y341709D03*
X277999Y339760D03*
X288139Y330009D03*
X284759Y328060D03*
Y339760D03*
X277999Y335860D03*
Y331960D03*
X284759Y335860D03*
X281379Y333909D03*
X288139Y337809D03*
X294899Y341709D03*
Y337809D03*
X271239Y320260D03*
Y324160D03*
X270939Y316160D03*
X267359Y318309D03*
X267859Y326110D03*
X267392Y322000D03*
X270892Y304660D03*
Y311960D03*
Y300760D03*
Y308560D03*
Y292959D03*
Y289060D03*
Y285500D03*
Y296860D03*
X281379Y302709D03*
X288139D03*
X294899D03*
X291519Y304660D03*
X281379Y306609D03*
Y310509D03*
X288139Y306609D03*
Y310509D03*
X284759Y304660D03*
X294899Y310509D03*
Y306609D03*
X281379Y287109D03*
X288139Y291009D03*
X284759Y289060D03*
X291519D03*
Y296860D03*
X288139Y298809D03*
X274619Y306609D03*
Y310509D03*
X277999Y304660D03*
X274619Y302709D03*
Y298809D03*
Y294909D03*
X277999Y289060D03*
X274619Y287109D03*
Y291009D03*
X277999Y296860D03*
X288139Y287109D03*
X281379Y298809D03*
Y294909D03*
X288139D03*
X284759Y296860D03*
X281379Y291009D03*
X294899Y298809D03*
Y294909D03*
Y291009D03*
Y287109D03*
X291519Y312460D03*
X284759D03*
X277999D03*
X274619Y314409D03*
X294899D03*
X281379D03*
X288139D03*
X274619Y318309D03*
X291519Y320260D03*
X284759D03*
X288139Y322209D03*
X281379D03*
X291519Y324160D03*
X277999D03*
X294899Y326109D03*
Y330009D03*
X288139Y372909D03*
X281379Y369010D03*
Y380709D03*
X277999Y378760D03*
X288139Y369010D03*
X284759Y367060D03*
Y378760D03*
X277999Y374860D03*
X294899Y376809D03*
Y380709D03*
X264179Y351460D03*
X271239D03*
X264179Y347560D03*
X271239D03*
X284759Y374860D03*
X277999Y370959D03*
X288139Y376809D03*
X281379Y372909D03*
X284759Y359260D03*
X281379Y361209D03*
X288139Y349509D03*
X284759Y347560D03*
X277999Y355360D03*
Y359260D03*
X284759Y386560D03*
Y394359D03*
X294899Y388509D03*
Y392410D03*
X281379Y388509D03*
Y392410D03*
X291519Y386560D03*
Y394359D03*
X288139Y353409D03*
X281379Y349509D03*
X284759Y355360D03*
X288139Y388509D03*
X277999Y351460D03*
X288139Y396309D03*
Y357309D03*
Y384609D03*
X281379Y353409D03*
X288139Y392410D03*
X294899Y361209D03*
Y365109D03*
Y345609D03*
Y357309D03*
X274619Y400209D03*
X281379D03*
X271239Y394359D03*
X267859Y392410D03*
X294899Y400209D03*
X271239Y398260D03*
X277999D03*
X274619Y396309D03*
X240746Y518157D03*
X243392Y513114D03*
X264171Y518157D03*
X267517Y513114D03*
X237099D03*
X257478Y518157D03*
X260824Y513114D03*
X277557Y518157D03*
X280203Y513114D03*
X270864Y518157D03*
X273910Y513114D03*
X294289Y518157D03*
X239592Y495900D03*
X243392Y495694D03*
X264171Y498487D03*
X267584Y493919D03*
X236892Y490800D03*
X257478Y498487D03*
X260824Y493744D03*
X277557Y498644D03*
X280203Y493244D03*
X271092Y498644D03*
X273992Y493744D03*
X294392Y493100D03*
X243392Y534700D03*
X267517Y535100D03*
X237013Y534700D03*
X260824Y535100D03*
X280203Y534700D03*
X273824D03*
X240746Y555957D03*
X243392Y572500D03*
Y550914D03*
X264171Y555957D03*
X267517Y572900D03*
Y550914D03*
X237013Y572500D03*
X237099Y550914D03*
X257478Y555957D03*
X260824Y572900D03*
Y550914D03*
X277557Y555957D03*
X280203Y572500D03*
Y550914D03*
X270864Y555957D03*
X273824Y572500D03*
X273910Y550914D03*
X294289Y555957D03*
X243392Y588714D03*
X267517D03*
X237099D03*
X260824D03*
X280203D03*
X273910D03*
X240746Y593757D03*
X243392Y610300D03*
X267517Y610700D03*
X264171Y593757D03*
X237013Y610300D03*
X257478Y593757D03*
X260824Y610700D03*
X280203Y610300D03*
X277557Y593757D03*
X273824Y610300D03*
X270864Y593757D03*
X294289D03*
X297635Y34100D03*
X300982Y17157D03*
X297635Y-3700D03*
Y12114D03*
X300982Y92757D03*
X297635Y71900D03*
Y87714D03*
X300982Y54957D03*
X297635Y49914D03*
X300982Y109700D03*
X304178Y107684D03*
X297635Y105084D03*
X298279Y214960D03*
X308418Y216909D03*
Y220809D03*
X305039Y214960D03*
X301659Y213009D03*
Y216909D03*
Y220809D03*
X338838Y250060D03*
X298279Y222760D03*
X305039D03*
X328698Y236409D03*
X301659Y224709D03*
X328698Y248109D03*
Y240309D03*
Y244209D03*
X325318Y238360D03*
Y246160D03*
X335458Y240309D03*
Y244209D03*
X321938Y240309D03*
Y244209D03*
X332078Y238360D03*
Y246160D03*
X298279Y261760D03*
Y230559D03*
X301659Y244209D03*
X305039Y242260D03*
X301659Y232509D03*
X311798Y230559D03*
X318558Y234460D03*
Y222760D03*
X321938Y224709D03*
X305039Y257860D03*
X311798Y234460D03*
X315178Y236409D03*
Y224709D03*
X321938Y228610D03*
X328698Y255909D03*
Y263709D03*
X338838Y257860D03*
Y261760D03*
X325318Y257860D03*
Y261760D03*
X335458Y255909D03*
Y263709D03*
X298279Y250060D03*
X301659Y263709D03*
X305039Y261760D03*
X301659Y252009D03*
X298279Y242260D03*
X305039Y238360D03*
Y253960D03*
X311798Y226660D03*
X332078Y253960D03*
X315178Y263709D03*
X305039Y234460D03*
X321938Y232509D03*
X332078Y265660D03*
X315178Y275409D03*
X301659Y255909D03*
X298279Y238360D03*
X315178Y228610D03*
X332078Y257860D03*
X315178Y267609D03*
X301659Y236409D03*
X318558Y230559D03*
X332078Y261760D03*
X315178Y271509D03*
X298279Y257860D03*
X311798Y265660D03*
Y273460D03*
X321938Y267609D03*
Y271509D03*
X308418Y267609D03*
Y271509D03*
X318558Y265660D03*
Y273460D03*
X301659Y279310D03*
X298279Y281260D03*
X308418Y283209D03*
X305039Y281260D03*
X308418Y279310D03*
X311798Y281260D03*
X301659Y283209D03*
X348978Y267609D03*
X357057Y277360D03*
Y281260D03*
X345598D03*
X348978Y283209D03*
X345598Y277360D03*
X348978Y279310D03*
Y275409D03*
Y271509D03*
X352357Y265660D03*
X355737Y263709D03*
X332078Y222760D03*
X328698Y224709D03*
X332078Y226660D03*
X335458Y228610D03*
X328698D03*
X332078Y230560D03*
X335458Y232510D03*
X311798Y242260D03*
X315178Y244209D03*
X311798Y246160D03*
X315178Y248109D03*
X308418D03*
X352357Y250060D03*
X345598D03*
X318558D03*
X355737Y252009D03*
X348978D03*
X321938D03*
X352357Y253960D03*
X345598D03*
X355737Y255909D03*
X348978D03*
X338838Y273460D03*
X345598Y261760D03*
X338838Y269560D03*
X332078Y273460D03*
X298279D03*
X335458Y275409D03*
X328698D03*
X338838Y277360D03*
X332078D03*
X325318D03*
X335458Y279310D03*
X328698D03*
X321938D03*
X335458Y271509D03*
X342218Y252009D03*
X301659Y271509D03*
X328698D03*
X298279Y269560D03*
X348978Y259809D03*
X345598Y257860D03*
X352357D03*
X348978Y337809D03*
X305039Y339760D03*
X298279Y335860D03*
X332078D03*
Y343660D03*
X342218Y337809D03*
Y341709D03*
X328698Y337809D03*
Y341709D03*
X338838Y335860D03*
Y343660D03*
X305039Y335860D03*
X301659Y333909D03*
X335458Y337809D03*
X318558Y328060D03*
Y335860D03*
X301659Y341709D03*
X298279Y339760D03*
X335458Y333909D03*
X318558Y324160D03*
X335458Y341709D03*
X318558Y331960D03*
X305039Y343660D03*
X315178Y326110D03*
Y333909D03*
X325318Y328060D03*
Y331960D03*
X311798Y328060D03*
Y331960D03*
X321938Y326110D03*
Y333909D03*
X308418Y306609D03*
X301659Y310509D03*
Y306609D03*
X311798Y304660D03*
X305039D03*
X321938Y306609D03*
X325318Y304660D03*
Y308560D03*
X298279Y304660D03*
X308418Y302709D03*
X301659D03*
X315178D03*
X321938D03*
X318558Y304660D03*
Y308560D03*
X321938Y291009D03*
X318558Y296860D03*
X315178Y294909D03*
X321938D03*
X301659D03*
X325318Y285160D03*
Y289060D03*
Y296860D03*
X298279D03*
Y289060D03*
X308418Y298809D03*
X301659D03*
X305039Y289060D03*
X308418Y291009D03*
Y287109D03*
X311798Y289060D03*
X308418Y294909D03*
X311798Y296860D03*
X305039D03*
X315178Y287109D03*
X318558Y285160D03*
X321938Y287109D03*
X301659D03*
Y291009D03*
X315178Y298809D03*
X321938D03*
X318558Y289060D03*
X315178Y291009D03*
X332078Y308560D03*
Y304660D03*
X328698Y302709D03*
Y306609D03*
Y287109D03*
Y291009D03*
Y294909D03*
Y298809D03*
X332078Y296860D03*
Y285160D03*
Y289060D03*
X315178Y306609D03*
X308418Y310509D03*
X311798Y312460D03*
X305039D03*
X298279D03*
X308418Y314409D03*
X301659D03*
X335458Y298809D03*
X357057Y296860D03*
X348978Y287109D03*
X345598Y285160D03*
X357057D03*
Y292959D03*
X348978Y298809D03*
Y291009D03*
X345598Y289060D03*
Y292959D03*
Y296860D03*
X348978Y294909D03*
X345598Y300760D03*
X348978Y302709D03*
X357057Y300760D03*
Y308560D03*
X348978Y306609D03*
X345598Y304660D03*
Y308560D03*
X348978Y310509D03*
X357057Y304660D03*
Y289060D03*
X342218Y302709D03*
Y306609D03*
Y291009D03*
Y287109D03*
Y294909D03*
Y298809D03*
X338838Y308560D03*
X335458Y302709D03*
X338838Y304660D03*
X335458Y306609D03*
Y287109D03*
X338838Y289060D03*
Y285160D03*
X335458Y291009D03*
X338838Y296860D03*
X335458Y294909D03*
X348978Y314409D03*
X357057Y312460D03*
X345598D03*
X357987Y327609D03*
X348978Y322209D03*
X355737Y333909D03*
X345598Y316360D03*
X348978Y318309D03*
Y330009D03*
X352357Y331960D03*
X348978Y326110D03*
X357057Y320260D03*
Y324160D03*
Y316360D03*
X328698Y314409D03*
X321938D03*
X332078Y328060D03*
X328698Y322209D03*
Y318309D03*
X332078Y324160D03*
Y320260D03*
Y316360D03*
X325318Y320260D03*
X305039D03*
X321938Y318309D03*
X315178D03*
X318558Y316360D03*
X301659Y322209D03*
X325318Y316360D03*
X305039Y324160D03*
X311798Y320260D03*
X308418Y322209D03*
X301659Y326110D03*
X335458Y314409D03*
Y326110D03*
Y318309D03*
Y322209D03*
X338838Y320260D03*
Y324160D03*
Y328060D03*
X298279Y324160D03*
Y320260D03*
X355737Y345609D03*
X348978Y341709D03*
X352357Y343660D03*
X321938Y341709D03*
X352357Y339760D03*
X321938Y345609D03*
X359117Y343660D03*
X355737Y341709D03*
X298279Y374860D03*
Y382660D03*
X308418Y376809D03*
Y380709D03*
X305039Y374860D03*
Y382660D03*
X301659Y376809D03*
X328698Y353409D03*
X301659Y384609D03*
X328698Y361209D03*
X301659Y372909D03*
X328698Y349509D03*
X301659Y380709D03*
X328698Y357309D03*
X325318Y351460D03*
Y359260D03*
X335458Y353409D03*
Y357309D03*
X321938Y353409D03*
Y357309D03*
X332078Y351460D03*
Y359260D03*
X301659Y365109D03*
X298279Y367060D03*
X305039Y355360D03*
X301659Y353409D03*
X318558Y363160D03*
X311798Y367060D03*
X321938Y372909D03*
X318558Y374860D03*
X315178Y361209D03*
X311798Y363160D03*
X321938Y369010D03*
X315178Y372909D03*
X298279Y347560D03*
X301659Y345609D03*
X305039Y359260D03*
X298279Y355360D03*
X301659Y361209D03*
X318558Y367060D03*
X311798Y370959D03*
X335458Y345609D03*
X305039Y363160D03*
X321938Y365109D03*
X298279Y359260D03*
X315178Y369010D03*
Y349509D03*
Y353409D03*
X348978Y345609D03*
X311798Y355360D03*
Y347560D03*
Y351460D03*
X308418Y349509D03*
X315178Y384609D03*
Y380709D03*
X332078Y374860D03*
X328698Y372909D03*
X332078Y370959D03*
X328698Y369010D03*
X332078Y367060D03*
X300982Y518157D03*
X297635Y513114D03*
X301092Y493300D03*
X304392Y494700D03*
X297835Y494944D03*
X297635Y535100D03*
X300982Y555957D03*
X297635Y572900D03*
Y550914D03*
Y588714D03*
X300982Y593757D03*
X297635Y610700D03*
X415634Y220096D03*
Y216196D03*
X419214Y218147D03*
Y222047D03*
X415634Y239596D03*
Y243496D03*
X419214Y245447D03*
X396296Y244209D03*
X415634Y227896D03*
Y231797D03*
X419214Y225947D03*
Y229847D03*
X372637Y253960D03*
X376017Y252009D03*
X368127Y264300D03*
X364747Y266300D03*
X362497Y259809D03*
X365877Y257860D03*
X369257Y255909D03*
X391787Y254259D03*
X388407Y256500D03*
X374887Y260300D03*
X385027Y254259D03*
X359117Y261760D03*
X371507Y262300D03*
X381647Y256400D03*
X378267Y258400D03*
X395166Y256400D03*
X418084Y253546D03*
X398546Y254259D03*
X405306Y254500D03*
X401926Y256500D03*
X359117Y250060D03*
Y253960D03*
X392916Y242260D03*
X386157D03*
X389537Y244209D03*
X382777D03*
X392916Y246160D03*
X386157D03*
X379397D03*
X365877Y250060D03*
X362497Y252009D03*
X399676Y246160D03*
X388407Y345160D03*
X364747Y331509D03*
X361367Y329560D03*
X371507Y335409D03*
X362497Y337809D03*
X369257Y341709D03*
X368127Y333460D03*
X365877Y339760D03*
X372637Y343660D03*
X374887Y337360D03*
X381647Y341260D03*
X378267Y339309D03*
X385027Y343209D03*
X359117Y335860D03*
X395166Y345160D03*
X401926D03*
X407448Y338641D03*
X394648Y338341D03*
X362497Y345609D03*
X391787Y347109D03*
X398546D03*
X411431Y359351D03*
X411086Y355360D03*
X382777Y353409D03*
X411086Y382660D03*
Y378760D03*
X460912Y33700D03*
X454533D03*
X478344Y34100D03*
X460912Y-4100D03*
X458266Y17157D03*
X460912Y12114D03*
X481691Y17157D03*
X451573D03*
X454533Y-4100D03*
X454619Y12114D03*
X478344Y-3700D03*
X474998Y17157D03*
X478344Y12114D03*
X460912Y71500D03*
X458266Y92757D03*
X460912Y87714D03*
X481691Y92757D03*
X454533Y71500D03*
X451573Y92757D03*
X454619Y87714D03*
X478344Y71900D03*
X474998Y92757D03*
X478344Y87714D03*
X458266Y54957D03*
X460912Y49914D03*
X481691Y54957D03*
X451573D03*
X454619Y49564D03*
X474998Y54957D03*
X478344Y49914D03*
X436113Y220096D03*
X446253Y222047D03*
X432733D03*
X442873Y220096D03*
X456393D03*
X466533Y222047D03*
X453013D03*
X463153Y220096D03*
X473292Y222047D03*
X439493Y218147D03*
X459773D03*
X480052D03*
X439493Y222047D03*
X459773D03*
X480052D03*
X425974D03*
X422594Y220096D03*
X458400Y276400D03*
X436113Y227896D03*
X446253Y225947D03*
X432733D03*
X442873Y227896D03*
X456393D03*
X466533Y225947D03*
X453013D03*
X463153Y227896D03*
X476672D03*
X473292Y225947D03*
X439493Y229847D03*
X459773D03*
X439493Y225947D03*
X459773D03*
X480052Y229847D03*
X425974Y225947D03*
X422594Y227896D03*
X466533Y233746D03*
Y241547D03*
X476672Y239596D03*
X463153Y235696D03*
Y239596D03*
X473292Y233746D03*
Y241547D03*
X469913Y231797D03*
Y243496D03*
Y235696D03*
Y239596D03*
X425974Y233746D03*
Y241547D03*
X436113Y235696D03*
Y239596D03*
X422594Y235696D03*
Y239596D03*
X432733Y233746D03*
Y241547D03*
X446253Y233746D03*
Y241547D03*
X456393Y235696D03*
Y239596D03*
X442873Y235696D03*
Y239596D03*
X453013Y233746D03*
Y241547D03*
X456393Y247396D03*
Y255196D03*
X466533Y249347D03*
Y253247D03*
X453013Y249347D03*
Y253247D03*
X463153Y247396D03*
Y255196D03*
X476672Y247396D03*
Y255196D03*
X473292Y249347D03*
Y253247D03*
X429354Y231797D03*
X449633D03*
X459773Y245447D03*
X480052D03*
X429354Y243496D03*
X449633D03*
X459773Y257147D03*
X480052D03*
X429354Y235696D03*
X449633D03*
X459773Y249347D03*
X480052D03*
X429354Y239596D03*
X449633D03*
X459773Y253247D03*
X480052D03*
X452865Y270081D03*
X465100Y280300D03*
X434983Y255497D03*
X438363Y257446D03*
X421464Y255497D03*
X431604Y257446D03*
X448503Y263297D03*
X441743Y259397D03*
X455263Y267197D03*
X436113Y247396D03*
X446253Y249347D03*
X442873Y251296D03*
X439493Y249347D03*
X442873Y247396D03*
X439493Y245447D03*
X446253Y253247D03*
X466533Y261047D03*
X463153Y262996D03*
X477792Y276646D03*
Y280547D03*
X469913Y282496D03*
X474413Y274696D03*
X469913Y278596D03*
X466533Y268847D03*
X422594Y247396D03*
X429781Y264793D03*
X459773Y264947D03*
X469913Y266896D03*
Y262996D03*
X473292Y261047D03*
X469913Y259096D03*
X481172Y282496D03*
Y270796D03*
X480052Y264947D03*
X473292D03*
Y268847D03*
X476672Y266896D03*
Y262996D03*
X474413Y344896D03*
X481172Y321496D03*
Y325396D03*
Y317596D03*
Y333196D03*
X463671Y319386D03*
X466734Y287074D03*
X442020Y339220D03*
X438240Y339380D03*
X451883Y342646D03*
X448503Y344597D03*
X481172Y298096D03*
X469913D03*
Y301996D03*
X481172Y305896D03*
X477792Y284447D03*
Y296147D03*
Y300047D03*
Y292247D03*
X481172Y294196D03*
X469913D03*
Y290296D03*
X474413Y329296D03*
X468783Y332897D03*
X474413Y333196D03*
Y325396D03*
X477792Y323446D03*
X430089Y338428D03*
X426494Y338361D03*
X463800Y289500D03*
X464273Y342947D03*
X471033Y339047D03*
X456900Y333000D03*
X481172Y329296D03*
X471033Y342947D03*
X466100Y300021D03*
X460893Y344896D03*
X481172Y286396D03*
X477792Y311747D03*
X469913Y309797D03*
Y313696D03*
Y317596D03*
X477792Y339047D03*
Y335147D03*
Y331247D03*
X481172Y340996D03*
Y337096D03*
X453400Y293686D03*
X477792Y346847D03*
X481172Y348796D03*
X477792Y350747D03*
X443993Y381947D03*
Y389747D03*
X454133Y383896D03*
Y387796D03*
X440613Y383896D03*
Y387796D03*
X450753Y381947D03*
Y389747D03*
X464273Y381947D03*
Y389747D03*
X474413Y383896D03*
Y387796D03*
X460893Y383896D03*
Y387796D03*
X471033Y381947D03*
Y389747D03*
X481172Y383896D03*
Y387796D03*
X447373Y383896D03*
X467653Y379996D03*
X447373Y391696D03*
X467653D03*
X447373Y379996D03*
X467653Y383896D03*
X447373Y387796D03*
X467653D03*
X423714Y389747D03*
Y393647D03*
X433854Y383896D03*
Y387796D03*
X423714Y378047D03*
Y381947D03*
X430474D03*
Y389747D03*
X474413Y368296D03*
Y376096D03*
X481172Y364396D03*
X471033Y370247D03*
Y374146D03*
X481172Y368296D03*
Y376096D03*
X427094Y383896D03*
X477792Y370247D03*
X427094Y391696D03*
X477792Y378047D03*
X427094Y379996D03*
X477792Y366347D03*
X427094Y387796D03*
X477792Y374146D03*
X427094Y364396D03*
X423714Y370247D03*
X437233Y366347D03*
Y370247D03*
X423714Y358547D03*
Y366347D03*
X433854Y364396D03*
Y372197D03*
X454133Y368296D03*
Y376096D03*
X464273Y370247D03*
Y374146D03*
X450753Y370247D03*
Y374146D03*
X460893Y368296D03*
Y376096D03*
X443993Y354647D03*
Y362447D03*
X454133Y356596D03*
Y360496D03*
X440613Y356596D03*
Y360496D03*
X450753Y354647D03*
Y362447D03*
X464273Y354647D03*
Y362447D03*
X474413Y356596D03*
Y360496D03*
X460893Y356596D03*
Y360496D03*
X471033Y354647D03*
Y362447D03*
X430474Y366347D03*
X457513Y370247D03*
X447373Y356596D03*
X467653D03*
X430474Y370247D03*
X457513Y378047D03*
X447373Y364396D03*
X467653D03*
X430474Y362447D03*
X457513Y366347D03*
X447373Y352696D03*
X467653D03*
X430474Y374146D03*
X457513D03*
X447373Y360496D03*
X467653D03*
X421464Y348497D03*
X438363Y346546D03*
X424844D03*
X434983Y348497D03*
X428224D03*
X431604Y346546D03*
X471033Y346847D03*
X464273D03*
X457513Y350747D03*
X430474Y358547D03*
X433854Y356596D03*
X437233Y378047D03*
X440613Y376096D03*
X443993Y374147D03*
Y370247D03*
X481172Y356596D03*
X458266Y518157D03*
X460912Y513114D03*
X481691Y518157D03*
X451573D03*
X454619Y513114D03*
X474998Y518157D03*
X478344Y513114D03*
X460912Y534700D03*
X454533D03*
X478344Y535100D03*
X458266Y555957D03*
X460912Y572500D03*
Y550914D03*
X481691Y555957D03*
X451573D03*
X454533Y572500D03*
X454619Y550914D03*
X474998Y555957D03*
X478344Y572900D03*
Y550914D03*
X460912Y588714D03*
X454619D03*
X478344D03*
X458266Y593757D03*
X460912Y610300D03*
X481691Y593757D03*
X454533Y610300D03*
X451573Y593757D03*
X478344Y610700D03*
X474998Y593757D03*
X485037Y34100D03*
X497723Y33700D03*
X521848Y34100D03*
X491344Y33700D03*
X515155Y34100D03*
X534534Y33700D03*
X528155D03*
X485037Y-3700D03*
Y12114D03*
X497723Y-4100D03*
X495077Y17157D03*
X497723Y12114D03*
X521848Y-3700D03*
X518502Y17157D03*
X521848Y12114D03*
X491344Y-4100D03*
X488384Y17157D03*
X491430Y12114D03*
X511809Y17157D03*
X515155Y-3700D03*
Y12114D03*
X534534Y-4100D03*
X531888Y17157D03*
X534534Y12114D03*
X528155Y-4100D03*
X525195Y17157D03*
X528241Y12114D03*
X485037Y71900D03*
Y87714D03*
X497723Y71500D03*
X495077Y92757D03*
X497723Y87714D03*
X521848Y71900D03*
X518502Y92757D03*
X521848Y87714D03*
X491344Y71500D03*
X488384Y92757D03*
X491430Y87714D03*
X511809Y92757D03*
X515155Y71900D03*
Y87714D03*
X534534Y71500D03*
X531888Y92757D03*
X534534Y87714D03*
X528155Y71500D03*
X525195Y92757D03*
X528241Y87714D03*
X485037Y49914D03*
X495077Y54957D03*
X497723Y49914D03*
X518502Y54957D03*
X521848Y49914D03*
X488384Y54957D03*
X491430Y49914D03*
X511809Y54957D03*
X515155Y49914D03*
X531888Y54957D03*
X534534Y49914D03*
X525195Y54957D03*
X528241Y49914D03*
X494927Y112357D03*
X497723Y106964D03*
X518317Y112357D03*
X521113Y106964D03*
X488634Y112357D03*
X491430Y106964D03*
X512024Y112357D03*
X514820Y106964D03*
X531888Y112357D03*
X534534Y106964D03*
X525134Y112357D03*
X528241Y107314D03*
X483432Y220096D03*
X511592Y222047D03*
X514972Y220096D03*
X518352Y222047D03*
X521731Y216196D03*
X531871Y218147D03*
X542011Y208396D03*
X528491Y204496D03*
X538631Y202247D03*
X525111Y222047D03*
Y210346D03*
X521731Y212296D03*
X514972Y208397D03*
Y212296D03*
X508212Y216196D03*
X501452Y220096D03*
X504832Y214247D03*
X498072Y218147D03*
Y214247D03*
X494692Y220096D03*
X542011Y216196D03*
X538631Y218147D03*
X535251Y212296D03*
X531871Y210346D03*
Y214247D03*
X525111D03*
X518352D03*
Y210345D03*
X514972Y216196D03*
X511592Y214247D03*
X504832Y222047D03*
Y218147D03*
X501452Y216196D03*
X494692Y212296D03*
Y216196D03*
X542011Y212296D03*
Y220096D03*
X535251D03*
Y208397D03*
X528491Y212296D03*
X535251Y216196D03*
X484552Y272747D03*
Y276646D03*
X501452Y270796D03*
X511592Y268847D03*
X514972Y255196D03*
X501452D03*
Y251296D03*
X521731Y270796D03*
X514972Y282496D03*
X521731D03*
X508212D03*
X494692D03*
X491312Y280547D03*
X486812Y261047D03*
X483432Y262996D03*
X518352Y261047D03*
X525111D03*
X514972Y251296D03*
X518352Y272747D03*
X521731Y255196D03*
Y251296D03*
X498072Y264947D03*
X511592Y245447D03*
X514972Y243496D03*
X483432Y227896D03*
X486812Y249347D03*
Y253247D03*
X483432Y247396D03*
Y255196D03*
X498072Y280547D03*
X514972Y274696D03*
X525111Y272747D03*
X518352Y257147D03*
X508212Y274696D03*
X504832Y268847D03*
X491312Y272747D03*
X511592D03*
X504832Y276647D03*
X498072Y245447D03*
X494692Y223996D03*
X504832Y225947D03*
X484552Y280547D03*
X518352Y233746D03*
X531871Y241547D03*
Y249347D03*
X528491Y223996D03*
X531871Y237647D03*
X535251Y223996D03*
X542011D03*
X528491Y270796D03*
Y278596D03*
X542011Y270796D03*
X535251Y255196D03*
X531871Y264947D03*
X494692Y266896D03*
X504832Y257147D03*
X508212Y251296D03*
X504832Y249347D03*
X508212Y247396D03*
X518352Y264947D03*
X508212Y243496D03*
X518352Y245447D03*
X531871Y257147D03*
X528491Y255196D03*
X511592Y253247D03*
X525111Y268847D03*
X518352Y241547D03*
Y237647D03*
X521731Y239596D03*
Y243496D03*
X528491Y262996D03*
Y266896D03*
X498072Y249347D03*
X525111D03*
Y245447D03*
X508212Y266896D03*
X521731Y278596D03*
X498072Y276647D03*
X491312D03*
X511592D03*
X504832Y272747D03*
X498072Y253247D03*
Y257147D03*
X518352Y280547D03*
X535251Y243496D03*
X542011Y266896D03*
X538631Y272747D03*
X531871D03*
X538631Y280547D03*
X542011Y282496D03*
X538631Y276646D03*
X535251Y278596D03*
X531871Y280547D03*
X538631Y241547D03*
X542011Y243496D03*
Y251296D03*
Y255196D03*
Y262996D03*
X538631Y261047D03*
X531871Y245447D03*
X538631Y264947D03*
Y268847D03*
X535251Y270796D03*
X542011Y278596D03*
X535251Y274696D03*
Y282496D03*
X528491D03*
X538631Y245447D03*
Y253247D03*
X542011Y259096D03*
X535251Y262996D03*
X511592Y229847D03*
Y225947D03*
Y237647D03*
X508212Y235696D03*
X498072Y229847D03*
X504832Y233746D03*
X494692Y227896D03*
X501452Y235696D03*
X498072Y237647D03*
Y241547D03*
X542011Y227896D03*
Y235696D03*
X535251Y231797D03*
Y227896D03*
X531871Y229847D03*
X525111Y233746D03*
X521731Y223996D03*
X525111Y229847D03*
X514972Y231797D03*
X508212Y227896D03*
X511592Y233746D03*
X504832Y237647D03*
X501452Y227896D03*
Y231797D03*
X494692D03*
X501452Y239596D03*
X494692D03*
X501452Y243496D03*
X542011Y231797D03*
X538631Y233746D03*
Y229847D03*
X531871Y225947D03*
Y233746D03*
X528491Y231797D03*
X525111Y225947D03*
X518352D03*
X521731Y227896D03*
X525111Y257147D03*
X528491Y259096D03*
X525111Y276646D03*
X504832Y280547D03*
X511592D03*
X518352Y276646D03*
Y268847D03*
X498072Y272747D03*
X531871Y253247D03*
X528491Y251296D03*
X525111Y241547D03*
X528491Y239596D03*
X518352Y249347D03*
X513857Y260881D03*
X501452Y262996D03*
X504832Y261047D03*
X501452Y278596D03*
X498072Y268847D03*
X504832Y264947D03*
X494692Y262996D03*
X491312Y264947D03*
X487932Y266896D03*
X491312Y268847D03*
X487932Y270796D03*
X498072Y261047D03*
X494692Y259096D03*
X521731Y262996D03*
X525111Y264947D03*
X494692Y274696D03*
X487932Y313696D03*
X491312Y315647D03*
X484552Y319546D03*
Y331247D03*
X491312Y288347D03*
Y284447D03*
X498072D03*
Y288347D03*
X501452Y286396D03*
X494692Y290296D03*
X498072Y292247D03*
X504832D03*
X518352Y284447D03*
X504832Y288347D03*
Y284447D03*
X508212Y286396D03*
X531871Y315647D03*
X487932Y286396D03*
X514972Y344896D03*
X511592Y342947D03*
X508212Y340996D03*
Y344896D03*
X487932Y290296D03*
X484552Y288347D03*
Y296147D03*
X498072Y339047D03*
X504832Y327347D03*
X508212Y321496D03*
X514972Y340996D03*
X518352Y331247D03*
X521731Y344896D03*
Y321496D03*
X525111Y339047D03*
X535251Y333196D03*
Y325396D03*
X484552Y284447D03*
X487932Y305896D03*
X491312Y303947D03*
X501452Y305896D03*
X494692Y298096D03*
X498072Y307847D03*
X484552Y303947D03*
X487932Y294196D03*
X491312Y296147D03*
X494692Y301996D03*
X487932D03*
X501452Y309797D03*
X487932Y298096D03*
X511592Y311747D03*
X508212Y309797D03*
X511592Y300047D03*
Y303947D03*
X542011Y286396D03*
X531871Y284447D03*
X542011Y290296D03*
X535251Y286396D03*
X542011Y313696D03*
Y309797D03*
X538631Y307847D03*
Y303947D03*
Y300047D03*
X535251Y298096D03*
Y317596D03*
X542011D03*
Y305896D03*
X535251D03*
X542011Y301996D03*
X538631Y296147D03*
X531871D03*
X535251Y313696D03*
X538631Y315647D03*
X484552Y311747D03*
Y315647D03*
X511592Y288347D03*
Y292245D03*
X491312Y323446D03*
X528491Y305896D03*
X518352Y311747D03*
X504832D03*
X508212Y305896D03*
Y301996D03*
X504832Y303947D03*
Y300045D03*
X518352Y303947D03*
X514972Y305896D03*
Y309797D03*
X528491Y301996D03*
Y309797D03*
X525111Y311747D03*
Y307847D03*
Y303947D03*
X521731Y305896D03*
Y309797D03*
X518352Y307847D03*
X514972Y313696D03*
X528491D03*
X521731D03*
X487932Y344896D03*
X484552Y342947D03*
X518352Y296147D03*
Y300047D03*
X521731Y294196D03*
X525111Y288347D03*
X528491Y290296D03*
X525111Y296147D03*
Y292245D03*
X521731Y298096D03*
Y290296D03*
Y286396D03*
X518352Y288347D03*
Y292245D03*
X514972Y298096D03*
X501452Y325396D03*
X498072Y323446D03*
Y315647D03*
X501452Y317596D03*
X498072Y335147D03*
X501452Y321496D03*
X498072Y331247D03*
X501452Y329296D03*
Y313696D03*
X498072Y300047D03*
X508212Y298096D03*
X504832Y296147D03*
X498072D03*
X501452Y294196D03*
X511592Y296147D03*
X498072Y311747D03*
X501452Y301996D03*
X494692Y325396D03*
Y321496D03*
X491312Y319547D03*
X494692Y333196D03*
X491312Y335147D03*
X487932Y333196D03*
Y337096D03*
X484552Y339047D03*
Y335147D03*
X491312Y327347D03*
X494692Y329296D03*
X487932D03*
Y340996D03*
X494692Y313696D03*
X484552Y307847D03*
X491312D03*
Y311747D03*
X494692Y305896D03*
Y317596D03*
X487932Y321496D03*
X484552Y327347D03*
X487932Y325396D03*
X484552Y381947D03*
X494692Y395597D03*
X491312Y401447D03*
X487932Y379996D03*
Y391696D03*
Y387796D03*
X514972Y352696D03*
Y348796D03*
X511592Y350747D03*
Y346847D03*
X508212Y348796D03*
X504832Y362447D03*
X494692Y368296D03*
Y352696D03*
X508212Y356596D03*
X504832Y350747D03*
X511592Y374146D03*
X501452Y383896D03*
X498072Y389747D03*
X494692Y376096D03*
X508212Y379996D03*
X521731Y368296D03*
X518352Y366347D03*
Y358547D03*
X542011Y364396D03*
X538631Y370247D03*
X542011Y372197D03*
Y352696D03*
X525111Y350747D03*
X514972Y399496D03*
X538631Y381947D03*
X531871Y385847D03*
X528491Y391696D03*
X525111Y397546D03*
X531871Y405347D03*
X504832Y370247D03*
X508212Y376096D03*
X501452Y372197D03*
X498072Y370247D03*
X504832Y397546D03*
Y393647D03*
X511592D03*
X501452Y387796D03*
X511592Y385847D03*
X518352D03*
Y381947D03*
Y378047D03*
X508212Y395597D03*
X504832Y389747D03*
X508212Y391696D03*
X504832Y385847D03*
X511592Y381947D03*
X514972Y383896D03*
X521731Y379996D03*
X518352Y374146D03*
Y405347D03*
X525111D03*
Y401447D03*
X528491Y395597D03*
X535251Y399496D03*
X531871Y393647D03*
X538631Y389747D03*
Y385847D03*
X518352Y401447D03*
X521731Y403396D03*
X528491Y399496D03*
X531871Y397546D03*
X535251Y395597D03*
Y391696D03*
Y387796D03*
X542011Y383896D03*
Y391696D03*
Y395597D03*
Y387796D03*
X525111Y370247D03*
X531871D03*
X525111Y362447D03*
X528491Y360496D03*
Y356596D03*
X535251Y352696D03*
X525111Y378047D03*
Y374146D03*
Y366347D03*
X528491Y368296D03*
X521731Y364396D03*
X525111Y358547D03*
X531871Y354647D03*
Y350747D03*
X521731Y376096D03*
X528491Y372197D03*
X542011Y379996D03*
X535251Y376096D03*
X487932Y352696D03*
X484552Y354647D03*
Y350747D03*
Y358547D03*
X487932Y348796D03*
X485037Y513114D03*
X495077Y518157D03*
X497723Y513114D03*
X518502Y518157D03*
X521848Y513114D03*
X488384Y518157D03*
X491430Y513114D03*
X511809Y518157D03*
X515155Y513114D03*
X531888Y518157D03*
X534534Y513114D03*
X525195Y518157D03*
X528241Y513114D03*
X494777Y498487D03*
X497723Y490894D03*
X517902Y498487D03*
X521048Y493844D03*
X488384Y498487D03*
X491430Y491144D03*
X511809Y498487D03*
X514755Y493744D03*
X530792Y498387D03*
X534534Y493394D03*
X524595Y498387D03*
X528191Y493544D03*
X485037Y535100D03*
X497723Y534700D03*
X521848Y535100D03*
X491344Y534700D03*
X515155Y535100D03*
X534534Y534700D03*
X528155D03*
X485037Y572900D03*
Y550914D03*
X495077Y555957D03*
X497723Y572500D03*
Y550914D03*
X518502Y555957D03*
X521848Y572900D03*
Y550914D03*
X488384Y555957D03*
X491344Y572500D03*
X491430Y550914D03*
X511809Y555957D03*
X515155Y572900D03*
Y550914D03*
X531888Y555957D03*
X534534Y572500D03*
Y550914D03*
X525195Y555957D03*
X528155Y572500D03*
X528241Y550914D03*
X485037Y588714D03*
X497723D03*
X521848D03*
X491430D03*
X515155D03*
X534534D03*
X528241D03*
X485037Y610700D03*
X495077Y593757D03*
X498092Y611200D03*
X521848Y610700D03*
X518502Y593757D03*
X488384D03*
X491724Y611668D03*
X515155Y610700D03*
X511809Y593757D03*
X534534Y610300D03*
X531888Y593757D03*
X528155Y610300D03*
X525195Y593757D03*
X558659Y34100D03*
X551966D03*
X571345Y33700D03*
X595470Y34100D03*
X564966Y33700D03*
X588777Y34100D03*
X558659Y-3700D03*
X555313Y17157D03*
X558659Y12114D03*
X551966Y-3700D03*
X548620Y17157D03*
X551966Y12114D03*
X571345Y-4100D03*
X568699Y17157D03*
X571345Y12114D03*
X595470Y-3700D03*
X592124Y17157D03*
X595470Y12114D03*
X564966Y-4100D03*
X561868Y17019D03*
X565052Y12114D03*
X588777Y-3700D03*
X585431Y17157D03*
X588777Y12114D03*
X598817Y17057D03*
X602163Y9157D03*
Y-1743D03*
Y36057D03*
Y27899D03*
X605510D03*
Y-9901D03*
Y16999D03*
Y-1743D03*
Y9157D03*
Y36057D03*
X558659Y71900D03*
X555313Y92757D03*
X558659Y87714D03*
X551966Y71900D03*
X548620Y92757D03*
X551966Y87714D03*
X571345Y71500D03*
X568699Y92757D03*
X571345Y87714D03*
X595470Y71900D03*
X592124Y92757D03*
X595470Y87714D03*
X564966Y71500D03*
X562006Y92757D03*
X565266Y87374D03*
X588777Y71900D03*
X585431Y92757D03*
X588777Y87714D03*
X555313Y54957D03*
X558659Y49914D03*
X548620Y54957D03*
X551966Y49914D03*
X568699Y54957D03*
X571345Y49914D03*
X592124Y54957D03*
X595470Y49914D03*
X562006Y54957D03*
X565052Y49914D03*
X585431Y54957D03*
X588777Y49914D03*
X598817Y92657D03*
X602163Y84757D03*
Y54799D03*
Y46957D03*
X598817Y54857D03*
X602163Y73857D03*
X605510Y92599D03*
Y65699D03*
Y54799D03*
Y46957D03*
Y84757D03*
Y73857D03*
X603163Y103971D03*
X555313Y112357D03*
X558659Y107314D03*
X548620Y112357D03*
X551966Y107314D03*
X605028Y119000D03*
X604977Y110200D03*
X558911Y218147D03*
X555531Y220096D03*
X548771D03*
X545391Y218147D03*
Y214247D03*
X552151Y222047D03*
X548771Y216196D03*
X603273Y198896D03*
X600286Y202921D03*
X599773Y199596D03*
X592300Y220500D03*
X552151Y237647D03*
X555531Y231797D03*
X548771Y227896D03*
X552151Y245447D03*
X548771Y251296D03*
X545391Y237647D03*
X548771Y282496D03*
Y270796D03*
Y262996D03*
X545391Y276646D03*
Y245447D03*
Y253247D03*
X548771Y259096D03*
X545391Y241547D03*
X548771Y247396D03*
X545391Y249347D03*
Y257147D03*
Y261047D03*
Y229847D03*
X548771Y231797D03*
X562616Y223996D03*
X555531Y259096D03*
Y266896D03*
X558911Y268847D03*
X552151D03*
Y276646D03*
X555531Y278596D03*
Y282496D03*
X562640Y231735D03*
X555531Y243496D03*
X552151Y253247D03*
X558911Y249347D03*
Y257147D03*
Y225947D03*
X555531Y262996D03*
X552151Y264947D03*
X555531Y270796D03*
X552151Y272747D03*
X548771Y274696D03*
X552151Y280547D03*
X562630Y227896D03*
X558911Y241547D03*
X555531Y251296D03*
X558911Y253247D03*
X555531Y255196D03*
Y227896D03*
Y223996D03*
X548771D03*
Y321496D03*
X545391Y323446D03*
X548771Y337096D03*
X545391Y342947D03*
X548771Y329296D03*
Y290296D03*
Y294196D03*
X545391Y284447D03*
X560884Y290296D03*
X555831Y294196D03*
X552151Y292245D03*
X545391Y311747D03*
X552151Y319547D03*
Y315647D03*
Y311747D03*
X548771Y305896D03*
X552151Y300047D03*
X548771Y301996D03*
X559211Y331103D03*
X555531Y329296D03*
X559211Y323446D03*
X555531Y321496D03*
X548771Y317596D03*
X555831Y313696D03*
X552151Y307847D03*
Y303947D03*
X555831Y301996D03*
X548771Y298096D03*
X559211Y327347D03*
X552151D03*
X555531Y325396D03*
X555831Y317446D03*
X559212Y385847D03*
X552151Y393647D03*
X545391Y389747D03*
Y393647D03*
X559212Y389747D03*
X545391Y378047D03*
X552151Y374146D03*
X545391D03*
X548771Y364396D03*
Y360496D03*
Y356596D03*
Y383896D03*
Y376096D03*
Y372196D03*
X545391Y370247D03*
Y362447D03*
X552151Y358547D03*
X548771Y352696D03*
X545391Y381947D03*
X548771Y379996D03*
X552151Y366347D03*
Y370247D03*
X563500Y360500D03*
X555531Y372197D03*
X548990Y403670D03*
X555750Y399770D03*
X562591Y348796D03*
X592216Y445152D03*
X595070Y447970D03*
X555313Y518157D03*
X558659Y513114D03*
X548620Y518157D03*
X551966Y513114D03*
X568699Y518157D03*
X571345Y513114D03*
X592124Y518157D03*
X595470Y513114D03*
X562006Y518157D03*
X565266Y512774D03*
X585431Y518157D03*
X588777Y513114D03*
X554792Y498487D03*
X558659Y496144D03*
X548492Y498400D03*
X551366Y493344D03*
X602163Y510157D03*
X598817Y518057D03*
X605510Y528899D03*
Y517999D03*
Y510157D03*
X558659Y535100D03*
X551966D03*
X571345Y534700D03*
X595470Y535100D03*
X564966Y534700D03*
X588777Y535100D03*
X555313Y555957D03*
X558659Y572900D03*
Y550914D03*
X548620Y555957D03*
X551966Y572900D03*
Y550914D03*
X568699Y555957D03*
X571345Y572500D03*
Y550914D03*
X592124Y555957D03*
X595470Y572900D03*
Y550914D03*
X562006Y555957D03*
X564966Y572500D03*
X565266Y550574D03*
X585431Y555957D03*
X588777Y572900D03*
Y550914D03*
X558659Y588714D03*
X551966D03*
X571345D03*
X595470D03*
X565052D03*
X588777D03*
X602163Y574857D03*
Y566699D03*
Y555799D03*
X598817Y555857D03*
X602163Y547957D03*
Y537057D03*
Y585757D03*
X605510Y555799D03*
Y566699D03*
Y585757D03*
Y547957D03*
Y574857D03*
Y537057D03*
X558659Y610700D03*
X555313Y593757D03*
X551966Y610700D03*
X548620Y593757D03*
X571345Y610300D03*
X568699Y593757D03*
X592124D03*
X595470Y610700D03*
X564966Y610300D03*
X562006Y593757D03*
X585431D03*
X588777Y610700D03*
X598817Y593657D03*
X602163Y612657D03*
X605510Y604499D03*
Y593599D03*
Y612657D03*
X661494Y32946D03*
X657250Y-2050D03*
X608856Y16999D03*
X612203D03*
Y9157D03*
X608856D03*
X615549D03*
X608856Y-9901D03*
X612203D03*
X608856Y-1743D03*
X612203D03*
X615549D03*
Y36057D03*
X608856D03*
X612203D03*
Y27899D03*
X608856D03*
X659747Y-12132D03*
X615549Y27899D03*
Y-9901D03*
Y16999D03*
X659700Y22900D03*
X665396Y23000D03*
X615549Y84757D03*
X608856D03*
X612203D03*
X608856Y92599D03*
X612203D03*
X608856Y46957D03*
X612203D03*
X608856Y54799D03*
X615549Y46957D03*
X612203Y54799D03*
X608856Y65699D03*
X612203D03*
X615549Y73857D03*
X608856D03*
X612203D03*
X652718Y93881D03*
X664471Y86061D03*
X662352Y89566D03*
X615549Y92599D03*
Y65699D03*
Y54799D03*
X626040Y98281D03*
X608600Y103000D03*
X613602Y118047D03*
Y109247D03*
X633800Y119000D03*
X658055Y141493D03*
X647555Y143643D03*
X651055Y142893D03*
X654555Y142193D03*
X642673Y139811D03*
X644055Y144493D03*
X635673Y141318D03*
X639173Y140618D03*
X632173Y142018D03*
X628673Y142718D03*
X609482Y124568D03*
X618800Y100100D03*
X644750Y175650D03*
X660600Y170000D03*
Y175000D03*
X611148Y206994D03*
X618648Y219494D03*
Y214494D03*
X608648Y204494D03*
X613648D03*
X610273Y197496D03*
X613773Y196796D03*
X613082Y200676D03*
X609860Y201356D03*
X654950Y253446D03*
X627529Y280441D03*
X618279Y251393D03*
X624500Y240500D03*
X639320Y268000D03*
X643500Y274868D03*
X633410Y269610D03*
Y274610D03*
X651235Y249165D03*
X641665Y281139D03*
X643100Y253700D03*
X649800Y252600D03*
X656100Y275500D03*
X606148Y229494D03*
X617235Y247735D03*
X614456Y244956D03*
X637681Y337390D03*
X628525Y287832D03*
X631250Y289650D03*
X639622Y290210D03*
X643823Y289650D03*
X658500Y284500D03*
X632869Y293720D03*
X648900Y336600D03*
X646520Y297400D03*
X664267Y292668D03*
X637143Y322000D03*
X637561Y312000D03*
Y317000D03*
X637600Y302000D03*
Y307000D03*
X646700Y308850D03*
X658900Y339150D03*
X628950Y293550D03*
X654600Y296000D03*
X662238Y296146D03*
X659694Y351206D03*
X664194D03*
X649194D03*
X654194D03*
X649600Y391200D03*
X640300Y437600D03*
X608800Y463475D03*
Y468475D03*
X609191Y451454D03*
X615300Y457900D03*
X641150Y484300D03*
X653800Y496600D03*
X618430Y491550D03*
X623400Y476300D03*
X629300Y490000D03*
X648500Y477400D03*
X662640Y528330D03*
X608856Y517999D03*
X612203D03*
Y528899D03*
X608856D03*
X615549Y510157D03*
X608856D03*
X612203D03*
X612515Y498752D03*
X609284Y480055D03*
X636500Y493924D03*
X627000Y478300D03*
X611250Y476750D03*
X618800Y474500D03*
X615549Y517999D03*
Y528899D03*
X639120Y475620D03*
X658900Y509300D03*
X639197Y490367D03*
X623600Y521700D03*
X608856Y574857D03*
X612203D03*
X615549D03*
X612203Y566699D03*
X608856D03*
Y555799D03*
X612203D03*
Y547957D03*
X615549D03*
X608856D03*
Y537057D03*
X615549D03*
X612203D03*
X615549Y585757D03*
X612203D03*
X608856D03*
X660217Y576734D03*
X615549Y555799D03*
Y566699D03*
X662000Y589000D03*
X608856Y593599D03*
X612203D03*
X608856Y604499D03*
X612203D03*
X608856Y612657D03*
X615549D03*
X612203D03*
X615549Y604499D03*
Y593599D03*
X665000Y598500D03*
X631741Y615759D03*
X723715Y23462D03*
X692500Y15300D03*
X708000Y26600D03*
X724837Y13852D03*
X714300Y-1900D03*
X680200Y13100D03*
X675235Y36797D03*
X719400Y14300D03*
X679936Y18406D03*
X670227Y34277D03*
X670400Y26100D03*
X701100Y8100D03*
X704450Y4950D03*
X720572Y88700D03*
X715130Y79574D03*
X697200Y79500D03*
X697100Y90600D03*
X670795Y89189D03*
X716894Y84047D03*
X701500Y85500D03*
X694600Y85000D03*
X698300Y85300D03*
X709560Y84648D03*
X685000Y46650D03*
X670503Y115884D03*
X670600Y144900D03*
Y150000D03*
X706500Y207800D03*
X706561Y211417D03*
X705292Y195729D03*
X701956Y195294D03*
X701129Y192106D03*
X709341Y190507D03*
X725725Y241560D03*
X697255Y267098D03*
X710500Y224500D03*
X700400Y257200D03*
X710272Y281911D03*
X706800Y281900D03*
X704500Y252500D03*
X700800Y261300D03*
X690130Y277380D03*
X715200Y258900D03*
X704090Y256080D03*
X689960Y260500D03*
X700000Y233700D03*
X710900Y231660D03*
X677800Y254100D03*
X667700Y275600D03*
X710700Y260200D03*
X710675Y263425D03*
X679300Y261700D03*
X712400Y324400D03*
X711900Y327700D03*
X697120Y305349D03*
Y300349D03*
X704404Y315875D03*
Y310875D03*
X697521Y325500D03*
Y320500D03*
X724000Y291700D03*
X686140Y298260D03*
X695000Y289500D03*
X686600Y335600D03*
X670800Y292600D03*
X667900Y339000D03*
X697352Y335500D03*
Y330500D03*
X705800Y301600D03*
X674700Y339200D03*
X688100Y308600D03*
X688924Y288147D03*
X674469Y287375D03*
X674194Y358467D03*
X683417Y364972D03*
X686619Y392600D03*
X683100Y392200D03*
X691240Y390039D03*
X687427Y384926D03*
X676900Y381800D03*
X669194Y351206D03*
X674194D03*
X679194D03*
X684194D03*
X695700Y346300D03*
X680370Y427770D03*
X680200Y432100D03*
X687400Y411200D03*
X674300Y489500D03*
X679700Y489400D03*
X718546Y500283D03*
X696000Y496800D03*
X669300Y504000D03*
X708500Y512500D03*
X721894Y501346D03*
X726040Y506080D03*
X696600Y581400D03*
X722200Y571300D03*
X718200Y581000D03*
X680029Y577503D03*
X680910Y582000D03*
X693200Y575900D03*
X717612Y598554D03*
X722406Y598950D03*
X756176Y-4300D03*
X782567Y33700D03*
X776188D03*
X782567Y-4100D03*
X779921Y17157D03*
X782567Y12114D03*
X776188Y-4100D03*
X773228Y17157D03*
X776274Y12114D03*
X729500Y23500D03*
X764100Y17100D03*
X760100Y17255D03*
X769881Y9157D03*
X763500Y23940D03*
X765900Y35800D03*
X765400Y-9800D03*
X766300Y-1800D03*
X729600Y17991D03*
X734256D03*
X755000Y17255D03*
X753100Y92111D03*
X782567Y71500D03*
X779921Y92757D03*
X782567Y87714D03*
X776188Y71500D03*
X773228Y92757D03*
X776274Y87714D03*
X779921Y54957D03*
X782567Y49914D03*
X773228Y54957D03*
X776274Y49914D03*
X764100Y55100D03*
X751600Y41000D03*
X755500Y55200D03*
X769881Y46957D03*
X763500Y59700D03*
X766500Y102900D03*
X752900Y101000D03*
X769044Y191348D03*
X770300Y204930D03*
X771232Y214033D03*
X749126Y220843D03*
X761580Y220160D03*
X748700Y257500D03*
X771650Y246451D03*
Y278451D03*
X759700Y232000D03*
X739400Y253400D03*
X739500Y247500D03*
X731662Y247716D03*
X775200Y230500D03*
X775171Y227116D03*
Y234316D03*
X775271Y262716D03*
X775171Y259116D03*
X730000Y254675D03*
X737750Y298894D03*
X771600Y310600D03*
X771700Y342501D03*
X729405Y290725D03*
X737912Y315500D03*
X741512Y315538D03*
X736000Y303400D03*
X775271Y294716D03*
X775171Y291116D03*
X775271Y326716D03*
X775171Y323116D03*
X757956Y328095D03*
X741250Y298856D03*
X743600Y304100D03*
X771400Y374400D03*
X760500Y359800D03*
X775271Y358716D03*
X775171Y355116D03*
X775221Y390716D03*
X775121Y387116D03*
X765007Y348363D03*
X732000Y380000D03*
X739933Y447401D03*
X756000Y525950D03*
X779921Y518157D03*
X782567Y513114D03*
X773228Y518157D03*
X776274Y513114D03*
X743483Y492937D03*
X764400Y528600D03*
X738648Y492050D03*
X763544Y522236D03*
X769500Y510100D03*
X766535Y517900D03*
X763706Y514250D03*
X782567Y534700D03*
X776188D03*
X779921Y555957D03*
X782567Y572500D03*
Y550914D03*
X773228Y555957D03*
X776188Y572500D03*
X776274Y550914D03*
X782567Y588714D03*
X776274D03*
X763300Y566000D03*
X755000D03*
X769500Y547900D03*
Y585700D03*
X764117Y575658D03*
X765100Y537110D03*
X766535Y555700D03*
X732600Y573950D03*
X763450Y585200D03*
X765900Y587300D03*
X782567Y610300D03*
X779921Y593757D03*
X776188Y610300D03*
X773228Y593757D03*
X764400Y604600D03*
X739307Y598850D03*
X755800Y604600D03*
X766535Y593500D03*
X733032Y604000D03*
X843503Y34100D03*
X812999Y33700D03*
X836810Y34100D03*
X849810Y33700D03*
X806692Y34100D03*
X799999D03*
X819378Y33700D03*
X843503Y-3700D03*
X840157Y17157D03*
X843503Y12114D03*
X812999Y-4100D03*
X810039Y17157D03*
X813085Y12114D03*
X833464Y17157D03*
X836810Y-3700D03*
Y12114D03*
X849810Y-4100D03*
X846850Y17157D03*
X849896Y12114D03*
X806692Y-3700D03*
X803346Y17157D03*
X806692Y12114D03*
X799999Y-3700D03*
X796653Y17157D03*
X799999Y12114D03*
X816732Y17157D03*
X819378Y-4100D03*
Y12114D03*
X843503Y71900D03*
X840157Y92757D03*
X843503Y87714D03*
X812999Y71500D03*
X810039Y92757D03*
X813085Y87714D03*
X836810Y71900D03*
X833464Y92757D03*
X836810Y87714D03*
X849810Y71500D03*
X846850Y92757D03*
X849896Y87714D03*
X806692Y71900D03*
X803346Y92757D03*
X806692Y87714D03*
X799999Y71900D03*
X796653Y92757D03*
X799999Y87714D03*
X816732Y92757D03*
X819378Y71500D03*
Y87714D03*
X840157Y54957D03*
X843503Y49914D03*
X810039Y54957D03*
X813085Y49914D03*
X833464Y54957D03*
X836810Y49914D03*
X846850Y54957D03*
X849896Y49914D03*
X803346Y54957D03*
X806692Y49914D03*
X796653Y54957D03*
X799999Y49914D03*
X816732Y54957D03*
X819378Y49914D03*
X798337Y181216D03*
X799300Y195600D03*
X813700D03*
Y198900D03*
X799620Y186547D03*
X804470Y186814D03*
X824000Y402863D03*
X797000Y404700D03*
X851430Y367468D03*
X805600Y403900D03*
X840871Y391380D03*
X837272Y391420D03*
X827800Y402863D03*
X832300D03*
X805367Y407400D03*
X797780Y423484D03*
X840157Y518157D03*
X843503Y513114D03*
X810039Y518157D03*
X813085Y513114D03*
X833464Y518157D03*
X836810Y513114D03*
X846850Y518157D03*
X849896Y513114D03*
X803346Y518157D03*
X806692Y513114D03*
X796653Y518157D03*
X799999Y513114D03*
X816732Y518157D03*
X819378Y513114D03*
X843503Y535100D03*
X812999Y534700D03*
X836810Y535100D03*
X849810Y534700D03*
X806692Y535100D03*
X799999D03*
X819378Y534700D03*
X840157Y555957D03*
X843503Y572900D03*
Y550914D03*
X810039Y555957D03*
X812999Y572500D03*
X813085Y550914D03*
X833464Y555957D03*
X836810Y572900D03*
Y550914D03*
X846850Y555957D03*
X849810Y572500D03*
X849896Y550914D03*
X803346Y555957D03*
X806692Y572900D03*
Y550914D03*
X796653Y555957D03*
X799999Y572900D03*
Y550914D03*
X816732Y555957D03*
X819378Y572500D03*
Y550914D03*
X843503Y588714D03*
X813085D03*
X836810D03*
X849896D03*
X806692D03*
X799999D03*
X819378D03*
X840157Y593757D03*
X843503Y610700D03*
X812999Y610300D03*
X810039Y593757D03*
X833464D03*
X836810Y610700D03*
X846850Y593757D03*
X849810Y610300D03*
X806692Y610700D03*
X803346Y593757D03*
X799999Y610700D03*
X796653Y593757D03*
X816732D03*
X819378Y610300D03*
X856189Y33700D03*
X880314Y34100D03*
X873621D03*
X893000Y33700D03*
X886621D03*
X910432Y34100D03*
X856189Y-4100D03*
X853543Y17157D03*
X856189Y12114D03*
X880314Y-3700D03*
X876968Y17157D03*
X880314Y12114D03*
X873621Y-3700D03*
X870275Y17157D03*
X873621Y12114D03*
X893000Y-4100D03*
X890354Y17157D03*
X893000Y12114D03*
X913779Y17157D03*
X883661D03*
X886621Y-4100D03*
X886707Y12114D03*
X907086Y17157D03*
X910432Y-3700D03*
Y12114D03*
X856189Y71500D03*
X853543Y92757D03*
X856189Y87714D03*
X876968Y92757D03*
X880314Y71900D03*
Y87714D03*
X873621Y71900D03*
X870275Y92761D03*
X873621Y87714D03*
X893000Y71500D03*
X890354Y92757D03*
X893000Y87714D03*
X913779Y92757D03*
X886621Y71500D03*
X883661Y92757D03*
X886707Y87714D03*
X910432Y71900D03*
X907086Y92757D03*
X910432Y87714D03*
X853543Y54957D03*
X856189Y49914D03*
X876968Y54957D03*
X880314Y49914D03*
X870275Y54957D03*
X873621Y49914D03*
X890354Y54957D03*
X893000Y49914D03*
X913779Y54957D03*
X883661D03*
X886707Y49914D03*
X907086Y54957D03*
X910432Y49914D03*
X890354Y112327D03*
X893000Y106934D03*
X913779Y112327D03*
X883661D03*
X886707Y107284D03*
X907086Y112327D03*
X910432Y107284D03*
X913787Y257860D03*
X913700Y242260D03*
X913787Y261760D03*
Y246160D03*
Y273460D03*
Y335860D03*
Y331960D03*
X882008Y321100D03*
X913787Y351460D03*
Y347560D03*
X853543Y518157D03*
X856189Y513114D03*
X876968Y518157D03*
X880314Y513114D03*
X870275Y518161D03*
X873621Y513114D03*
X890354Y518157D03*
X893000Y513114D03*
X913779Y518157D03*
X883661D03*
X886707Y513114D03*
X907086Y518157D03*
X910432Y513114D03*
X889200Y495900D03*
X893000Y495694D03*
X913779Y498487D03*
X882900Y498500D03*
X886500Y490800D03*
X907086Y498487D03*
X910432Y493744D03*
X856189Y534700D03*
X880314Y535100D03*
X873621D03*
X893000Y534700D03*
X886621D03*
X910432Y535100D03*
X853543Y555957D03*
X856189Y572500D03*
Y550914D03*
X876968Y555957D03*
X880314Y572900D03*
Y550914D03*
X870275Y555961D03*
X873621Y572900D03*
Y550914D03*
X893000Y572500D03*
X890354Y555957D03*
X893000Y550914D03*
X913779Y555957D03*
X886621Y572500D03*
X883661Y555957D03*
X886707Y550914D03*
X910432Y572900D03*
X907086Y555957D03*
X910432Y550914D03*
X856189Y588714D03*
X880314D03*
X873621D03*
X893000D03*
X886707D03*
X910432D03*
X853543Y593757D03*
X856189Y610300D03*
X876968Y593757D03*
X880314Y610700D03*
X870275Y593761D03*
X873621Y610700D03*
X893000Y610300D03*
X890354Y593757D03*
X913779D03*
X886621Y610300D03*
X883661Y593757D03*
X907086D03*
X910432Y610700D03*
X917125Y34100D03*
X929811Y33700D03*
X923432D03*
X947243Y34100D03*
X917125Y-3700D03*
Y12114D03*
X929811Y-4100D03*
X927165Y17157D03*
X929811Y12114D03*
X950590Y17157D03*
X923432Y-4100D03*
X920472Y17157D03*
X923518Y12114D03*
X947243Y-3700D03*
X943897Y17157D03*
X947243Y12114D03*
X917125Y71900D03*
Y87714D03*
X929811Y71500D03*
X927165Y92757D03*
X929811Y87714D03*
X950590Y92757D03*
X923432Y71500D03*
X920472Y92757D03*
X923518Y87714D03*
X947243Y71900D03*
X943897Y92757D03*
X947243Y87714D03*
X917125Y49914D03*
X927165Y54957D03*
X929811Y49914D03*
X950590Y54957D03*
X920472D03*
X923518Y49914D03*
X943897Y54957D03*
X947243Y49914D03*
X917125Y107284D03*
X927165Y112327D03*
X929811Y106934D03*
X950590Y109700D03*
X953786Y107684D03*
X920472Y112327D03*
X923518Y107284D03*
X944497Y110927D03*
X947243Y105084D03*
X924227Y205210D03*
X920847Y207159D03*
X927607Y218860D03*
X930987Y216909D03*
X934367Y218860D03*
X947887Y214960D03*
X958026Y216909D03*
Y220809D03*
X944507Y216909D03*
Y220809D03*
X954647Y214960D03*
X951267Y213009D03*
X937747Y220809D03*
X951267Y216909D03*
Y220809D03*
X934367Y203260D03*
Y211060D03*
X944507Y205210D03*
Y209109D03*
X930987Y205210D03*
Y209109D03*
X941127Y203260D03*
Y211060D03*
X937747Y201309D03*
Y213009D03*
Y205210D03*
Y209109D03*
X917467D03*
X927607Y199360D03*
X924227Y201309D03*
X944507Y197409D03*
X924227Y209109D03*
X920847Y203260D03*
X930987Y228610D03*
X937747Y224709D03*
X920847Y257860D03*
X934367Y230559D03*
X937747Y228610D03*
X927607Y222760D03*
X947887D03*
X954647D03*
X920847Y242260D03*
Y261760D03*
Y246160D03*
Y250060D03*
X927607Y226660D03*
X951267Y224709D03*
X920847Y253960D03*
X917467Y248109D03*
X930987Y224709D03*
X934367Y222760D03*
X917467Y255909D03*
X974926Y238360D03*
Y246160D03*
X971546Y240309D03*
Y244209D03*
X930987Y267609D03*
X927607Y238360D03*
X930987Y236409D03*
X934367Y250060D03*
X937747Y248109D03*
X927607Y242260D03*
X934367Y238360D03*
X937747Y263709D03*
X927607Y257860D03*
X930987Y255909D03*
X934367Y269560D03*
X937747Y267609D03*
X927607Y261760D03*
X934367Y257860D03*
X930987Y248109D03*
X937747Y244209D03*
Y259809D03*
X927607Y246160D03*
X937747Y240309D03*
X927607Y265660D03*
X934367Y261760D03*
X930987Y244209D03*
X934367Y242260D03*
X930987Y263709D03*
X947887Y261760D03*
X944507Y232509D03*
X947887Y230559D03*
X951267Y244209D03*
X954647Y242260D03*
X944507Y236409D03*
X951267Y232509D03*
X961406Y230559D03*
X968166Y234460D03*
Y222760D03*
X971546Y224709D03*
X954647Y257860D03*
X961406Y234460D03*
X964786Y236409D03*
Y224709D03*
X971546Y228610D03*
X974926Y257860D03*
Y261760D03*
X944507Y252009D03*
X947887Y250060D03*
X951267Y263709D03*
X954647Y261760D03*
X944507Y255909D03*
X951267Y252009D03*
X947887Y242260D03*
X954647Y238360D03*
Y253960D03*
X944507Y240309D03*
X961406Y226660D03*
X964786Y263709D03*
X954647Y234460D03*
X971546Y232509D03*
X964786Y275409D03*
X944507Y259809D03*
X951267Y255909D03*
X947887Y238360D03*
X964786Y228610D03*
Y267609D03*
X951267Y236409D03*
X968166Y230559D03*
X964786Y271509D03*
X947887Y257860D03*
X961406Y265660D03*
Y273460D03*
X971546Y267609D03*
Y271509D03*
X958026Y267609D03*
Y271509D03*
X968166Y265660D03*
Y273460D03*
X937747Y279310D03*
X917000Y276000D03*
X920847Y277360D03*
X924227Y279310D03*
Y283209D03*
X927607Y281260D03*
X920847D03*
X916967Y279310D03*
X934367Y281260D03*
X930987Y279310D03*
Y283209D03*
X937747D03*
X944507D03*
Y279310D03*
X958026D03*
X954647Y281260D03*
X958026Y283209D03*
X951267Y279310D03*
Y283209D03*
X961406Y281260D03*
X941127D03*
X947887D03*
X917467Y271509D03*
X961406Y242260D03*
X964786Y244209D03*
X961406Y246160D03*
X964786Y248109D03*
X958026D03*
X968166Y250060D03*
X971546Y252009D03*
X944507Y267609D03*
X947887Y269560D03*
X951267Y271509D03*
X947887Y273460D03*
X941127D03*
X927607D03*
X974926Y277360D03*
X971546Y279310D03*
X944507Y271509D03*
X924227D03*
X920847Y335860D03*
Y331960D03*
Y343660D03*
Y339760D03*
X917467Y345609D03*
Y337809D03*
X937747Y333909D03*
X930987Y330009D03*
Y341709D03*
X927607Y339760D03*
X937747Y330009D03*
X934367Y328060D03*
Y339760D03*
X927607Y335860D03*
Y331960D03*
X934367Y335860D03*
X930987Y333909D03*
X937747Y337809D03*
X954647Y339760D03*
X947887Y335860D03*
X954647D03*
X951267Y333909D03*
X944507Y341709D03*
Y337809D03*
X968166Y328060D03*
Y335860D03*
X951267Y341709D03*
X947887Y339760D03*
X968166Y324160D03*
Y331960D03*
X954647Y343660D03*
X964786Y326110D03*
Y333909D03*
X974926Y328060D03*
Y331960D03*
X961406Y328060D03*
Y331960D03*
X971546Y326110D03*
Y333909D03*
X937747Y287109D03*
X920500Y304660D03*
Y300760D03*
X930987Y302709D03*
X924227D03*
X920500Y311960D03*
X927607Y304660D03*
X924227Y306609D03*
X930987D03*
Y310509D03*
X934367Y304660D03*
X924227Y310509D03*
X920500Y308560D03*
Y289060D03*
X934367Y296860D03*
X930987Y294909D03*
X920500Y296860D03*
Y292959D03*
X927607Y296860D03*
X924227Y298809D03*
X930987D03*
X920500Y285500D03*
X924227Y287109D03*
X930987D03*
X934367Y289060D03*
X924227Y291009D03*
X930987D03*
X927607Y289060D03*
X937747Y302709D03*
Y306609D03*
Y310509D03*
Y291009D03*
Y294909D03*
Y298809D03*
Y314409D03*
X924227D03*
X930987D03*
X934367Y312460D03*
X927607D03*
X920847Y324160D03*
X924227Y318309D03*
X920547Y316160D03*
X917167Y318309D03*
Y322209D03*
X917467Y326110D03*
X920847Y320260D03*
X971546Y294909D03*
X964786Y291009D03*
X951267Y287109D03*
X958026D03*
X961406Y296860D03*
X964786Y298809D03*
Y302709D03*
X971546D03*
X961406Y304660D03*
X958026Y302709D03*
X951267D03*
X968166Y308560D03*
X964786Y306609D03*
X968166Y304660D03*
X971546Y306609D03*
X974926Y304660D03*
Y308560D03*
X951267Y310509D03*
X954647Y304660D03*
X958026Y306609D03*
Y310509D03*
X951267Y306609D03*
X944507Y302709D03*
Y306609D03*
Y310509D03*
X941127Y304660D03*
X947887D03*
X944507Y294909D03*
Y287109D03*
X971546Y298809D03*
X974926Y285160D03*
Y296860D03*
Y289060D03*
X968166Y285160D03*
X964786Y287109D03*
X944507Y291009D03*
X941127Y289060D03*
Y296860D03*
X944507Y298809D03*
X947887Y289060D03*
Y296860D03*
X968166D03*
X964786Y294909D03*
X971546Y291009D03*
Y287109D03*
X968166Y289060D03*
X961406D03*
X958026Y298809D03*
X951267D03*
Y291009D03*
X958026D03*
X954647Y289060D03*
Y296860D03*
X958026Y294909D03*
X951267D03*
X944507Y314409D03*
X951267D03*
X958026D03*
X961406Y312460D03*
X954647D03*
X941127D03*
X947887D03*
X951267Y326110D03*
X958026Y322209D03*
X954647Y320260D03*
X961406D03*
X954647Y324160D03*
X951267Y322209D03*
X964786Y318309D03*
X971546D03*
X974926Y320260D03*
X968166Y316360D03*
X974926D03*
X971546Y314409D03*
X947887Y320260D03*
X941127D03*
X934367D03*
X927607Y324160D03*
X944507Y326110D03*
Y330009D03*
X971546Y341709D03*
Y345609D03*
X937747Y372909D03*
X930987Y369010D03*
Y380709D03*
X927607Y378760D03*
X937747Y369010D03*
X934367Y367060D03*
Y378760D03*
X927607Y374860D03*
X947887D03*
Y382660D03*
X958026Y376809D03*
Y380709D03*
X944507Y376809D03*
Y380709D03*
X954647Y374860D03*
Y382660D03*
X920847Y351460D03*
Y347560D03*
X934367Y374860D03*
X951267Y376809D03*
X927607Y370959D03*
X951267Y384609D03*
X937747Y376809D03*
X951267Y372909D03*
X930987D03*
X951267Y380709D03*
X974926Y351460D03*
Y359260D03*
X971546Y353409D03*
Y357309D03*
X934367Y359260D03*
X930987Y361209D03*
X937747Y349509D03*
X934367Y347560D03*
X927607Y355360D03*
Y359260D03*
X934367Y386560D03*
Y394359D03*
X944507Y388509D03*
Y392410D03*
X930987Y388509D03*
Y392410D03*
X941127Y386560D03*
Y394359D03*
X937747Y353409D03*
X930987Y349509D03*
X934367Y355360D03*
X937747Y388509D03*
X927607Y351460D03*
X937747Y396309D03*
Y357309D03*
Y384609D03*
X930987Y353409D03*
X937747Y392410D03*
X951267Y365109D03*
X947887Y367060D03*
X954647Y355360D03*
X951267Y353409D03*
X944507Y361209D03*
Y365109D03*
X968166Y363160D03*
X961406Y367060D03*
X971546Y372909D03*
X968166Y374860D03*
X964786Y361209D03*
X961406Y363160D03*
X971546Y369010D03*
X964786Y372909D03*
X947887Y347560D03*
X944507Y345609D03*
X951267D03*
X954647Y359260D03*
X947887Y355360D03*
X951267Y361209D03*
X968166Y367060D03*
X944507Y357309D03*
X961406Y370959D03*
X954647Y363160D03*
X971546Y365109D03*
X947887Y359260D03*
X964786Y369010D03*
Y349509D03*
Y353409D03*
X961406Y355360D03*
Y347560D03*
Y351460D03*
X924227Y400209D03*
X930987D03*
X920847Y394359D03*
X917467Y392410D03*
X944507Y400209D03*
X964786Y384609D03*
Y380709D03*
X920847Y398260D03*
X927607D03*
X958026Y349509D03*
X924227Y396309D03*
X917125Y513114D03*
X927165Y518157D03*
X929811Y513114D03*
X950590Y518157D03*
X920472D03*
X923518Y513114D03*
X943897Y518157D03*
X947243Y513114D03*
X917192Y493919D03*
X927165Y498644D03*
X929811Y493244D03*
X950700Y493300D03*
X954000Y494700D03*
X920700Y498644D03*
X923600Y493744D03*
X944000Y493100D03*
X947443Y494944D03*
X917125Y535100D03*
X929811Y534700D03*
X923432D03*
X947243Y535100D03*
X917125Y572900D03*
Y550914D03*
X929811Y572500D03*
X927165Y555957D03*
X929811Y550914D03*
X950590Y555957D03*
X923432Y572500D03*
X920472Y555957D03*
X923518Y550914D03*
X947243Y572900D03*
X943897Y555957D03*
X947243Y550914D03*
X917125Y588714D03*
X929811D03*
X923518D03*
X947243D03*
X917125Y610700D03*
X929811Y610300D03*
X927165Y593757D03*
X950590D03*
X923432Y610300D03*
X920472Y593757D03*
X947243Y610700D03*
X943897Y593757D03*
X988446Y250060D03*
X978306Y236409D03*
Y248109D03*
Y240309D03*
Y244209D03*
X985066Y240309D03*
Y244209D03*
X981686Y238360D03*
Y246160D03*
X978306Y255909D03*
Y263709D03*
X988446Y257860D03*
Y261760D03*
X985066Y255909D03*
Y263709D03*
X981686Y253960D03*
Y265660D03*
Y257860D03*
Y261760D03*
X995206Y277360D03*
Y281260D03*
X998586Y267609D03*
Y271509D03*
Y275409D03*
Y279310D03*
Y283209D03*
X1022245Y253960D03*
X1025625Y252009D03*
X1017735Y264300D03*
X1014355Y266300D03*
X1021115Y262300D03*
X1024495Y260300D03*
X1027875Y258400D03*
X1031255Y256400D03*
X1034635Y254259D03*
X1005345Y263709D03*
X1001965Y265660D03*
X1008725Y261760D03*
X1006665Y277360D03*
Y281260D03*
X1015485Y257860D03*
X1018865Y255909D03*
X1012105Y259809D03*
X981686Y222760D03*
X978306Y224709D03*
X981686Y226660D03*
X985066Y228610D03*
X978306D03*
X981686Y230559D03*
X985066Y232509D03*
X1008725Y250060D03*
X1001965D03*
X995206D03*
X1005345Y252009D03*
X998586D03*
X1008725Y253960D03*
X1001965D03*
X995206D03*
X1005345Y255909D03*
X998586D03*
X1001965Y257860D03*
X995206D03*
X998586Y259809D03*
X995206Y261760D03*
X988446Y269560D03*
X985066Y271509D03*
X978306D03*
X988446Y273460D03*
X981686D03*
X985066Y275409D03*
X978306D03*
X988446Y277360D03*
X981686D03*
X985066Y279310D03*
X978306D03*
X1015485Y250060D03*
X1012105Y252009D03*
X991826D03*
X998586Y337809D03*
X981686Y335860D03*
Y343660D03*
X991826Y337809D03*
Y341709D03*
X978306Y337809D03*
Y341709D03*
X988446Y335860D03*
Y343660D03*
X985066Y337809D03*
Y333909D03*
Y341709D03*
X995206Y296860D03*
X985066Y294909D03*
Y287109D03*
X988446Y285160D03*
X991826Y287109D03*
X978306Y298809D03*
Y287109D03*
X981686Y285160D03*
X978306Y294909D03*
X981686Y296860D03*
Y289060D03*
X978306Y291009D03*
X998586Y302709D03*
Y306609D03*
Y310509D03*
Y287109D03*
Y294909D03*
Y291009D03*
Y298809D03*
X985066Y302709D03*
X978306D03*
X988446Y304660D03*
Y308560D03*
X985066Y306609D03*
X995206Y304660D03*
Y308560D03*
X991826Y306609D03*
X978306D03*
X981686Y308560D03*
Y304660D03*
X995206Y300760D03*
X991826Y302709D03*
X995206Y292959D03*
X988446Y296860D03*
X991826Y294909D03*
X995206Y289060D03*
X988446D03*
X991826Y291009D03*
X985066D03*
X995206Y285160D03*
X985066Y298809D03*
X991826D03*
X998586Y314409D03*
X995206Y312460D03*
X998586Y318309D03*
Y322209D03*
Y326110D03*
Y330009D03*
X995206Y316360D03*
X1006665Y300760D03*
Y304660D03*
Y308560D03*
Y285160D03*
Y296860D03*
Y289060D03*
Y292959D03*
X1008725Y335860D03*
X1005345Y333909D03*
X1001965Y331960D03*
X1007595Y327609D03*
X1021115Y335409D03*
X1018865Y341709D03*
X1017735Y333460D03*
X1015485Y339760D03*
X1024495Y337360D03*
X1012105Y337809D03*
X1006665Y312460D03*
X1014355Y331509D03*
X1010975Y329560D03*
X1027875Y339309D03*
X1034635Y343209D03*
X1031255Y341260D03*
X1006665Y324160D03*
Y316360D03*
Y320260D03*
X1022245Y343660D03*
X981686Y324160D03*
X988446Y320260D03*
X985066Y322209D03*
Y318309D03*
X988446Y324160D03*
Y328060D03*
X981686D03*
X985066Y326110D03*
X981686Y320260D03*
X978306Y322209D03*
Y318309D03*
X981686Y316360D03*
X978306Y314409D03*
X985066D03*
X998586Y341709D03*
Y345609D03*
X1001965Y343660D03*
Y339760D03*
X1008725Y343660D03*
X1012105Y345609D03*
X1005345Y341709D03*
X978306Y353409D03*
Y361209D03*
Y349509D03*
Y357309D03*
X985066Y353409D03*
Y357309D03*
X981686Y351460D03*
Y359260D03*
X985066Y345609D03*
X1005345D03*
X1032385Y353409D03*
X1035765Y355360D03*
X985066Y376809D03*
X981686Y374860D03*
X978306Y372909D03*
X981686Y370959D03*
X978306Y369010D03*
X985066D03*
X981686Y367060D03*
X985066Y365109D03*
X1085721Y220096D03*
X1095861Y222047D03*
X1082341D03*
X1092481Y220096D03*
X1089101Y218147D03*
Y222047D03*
X1065242Y220096D03*
Y216196D03*
X1075582Y222047D03*
X1072202Y220096D03*
X1068822Y218147D03*
Y222047D03*
X1065242Y239596D03*
Y243496D03*
X1068822Y245447D03*
X1085721Y227896D03*
X1095861Y225947D03*
X1082341D03*
X1092481Y227896D03*
X1089101Y229847D03*
Y225947D03*
X1075582D03*
X1065242Y227896D03*
Y231797D03*
X1072202Y227896D03*
X1068822Y225947D03*
Y229847D03*
X1075582Y233746D03*
Y241547D03*
X1085721Y235696D03*
Y239596D03*
X1072202Y235696D03*
Y239596D03*
X1082341Y233746D03*
Y241547D03*
X1095861Y233746D03*
Y241547D03*
X1092481Y235696D03*
Y239596D03*
X1078962Y231797D03*
X1099241D03*
X1078962Y243496D03*
X1099241D03*
X1078962Y235696D03*
X1099241D03*
X1078962Y239596D03*
X1099241D03*
X1038015Y256500D03*
X1041395Y254259D03*
X1048154D03*
X1051534Y256500D03*
X1044774Y256400D03*
X1054914Y254500D03*
X1067692Y254000D03*
X1071072Y255728D03*
X1087971Y257800D03*
X1091351Y259600D03*
X1094731Y261500D03*
X1098111Y263400D03*
X1084591Y255497D03*
X1081212Y257600D03*
X1092481Y247396D03*
X1089101Y245447D03*
X1085721Y247396D03*
X1089101Y249347D03*
X1092481Y251296D03*
X1095861Y249347D03*
Y253247D03*
X1072202Y247396D03*
X1079859Y265000D03*
X1038015Y345160D03*
X1044774D03*
X1051534D03*
X1098111Y344597D03*
X1044256Y338341D03*
X1076435Y343595D03*
X1042524Y355360D03*
X1093601Y381947D03*
Y389747D03*
X1090221Y383896D03*
Y387796D03*
X1096981Y383896D03*
Y391696D03*
Y379996D03*
Y387796D03*
X1073322Y389747D03*
Y393647D03*
X1083462Y383896D03*
Y387796D03*
X1073322Y378047D03*
Y381947D03*
X1080082D03*
Y389747D03*
X1076702Y383896D03*
Y391696D03*
Y379996D03*
Y387796D03*
Y364396D03*
X1073322Y370247D03*
X1086841Y366347D03*
Y370247D03*
X1073322Y358547D03*
Y366347D03*
X1083462Y364396D03*
Y372197D03*
X1093601Y354647D03*
Y362447D03*
X1090221Y356596D03*
Y360496D03*
X1080082Y366347D03*
X1096981Y356596D03*
X1080082Y370247D03*
X1096981Y364396D03*
X1080082Y362447D03*
X1096981Y352696D03*
X1080082Y374146D03*
X1096981Y360496D03*
X1041395Y347109D03*
X1048154D03*
X1071072Y348497D03*
X1087971Y346546D03*
X1074452D03*
X1081212D03*
X1077832Y348497D03*
X1084591D03*
X1061039Y359351D03*
X1060963Y370959D03*
X1060694Y355360D03*
X1061055Y363160D03*
X1052664Y353409D03*
X1064371Y367060D03*
X1060694Y382660D03*
Y378760D03*
X1086841Y378047D03*
X1090221Y376096D03*
X1093601Y374146D03*
Y370247D03*
X1049284Y355360D03*
X1080082Y358547D03*
X1083462Y356596D03*
X1110520Y33700D03*
X1134645Y34100D03*
X1104141Y33700D03*
X1127952Y34100D03*
X1147331Y33700D03*
X1140952D03*
X1110520Y-4100D03*
X1107874Y17157D03*
X1110520Y12114D03*
X1134645Y-3700D03*
X1131299Y17157D03*
X1134645Y12114D03*
X1101181Y17157D03*
X1104141Y-4100D03*
X1104227Y12114D03*
X1127952Y-3700D03*
X1124606Y17157D03*
X1127952Y12114D03*
X1147331Y-4100D03*
X1144685Y17157D03*
X1147331Y12114D03*
X1140952Y-4100D03*
X1137992Y17157D03*
X1141038Y12114D03*
X1110520Y71500D03*
X1107874Y92757D03*
X1110520Y87714D03*
X1134645Y71900D03*
X1131299Y92757D03*
X1134645Y87714D03*
X1101181Y92757D03*
X1104141Y71500D03*
X1104227Y87714D03*
X1127952Y71900D03*
X1124606Y92757D03*
X1127952Y87714D03*
X1147331Y71500D03*
X1144685Y92757D03*
X1147331Y87714D03*
X1140952Y71500D03*
X1137992Y92757D03*
X1141038Y87714D03*
X1107874Y54957D03*
X1110520Y49914D03*
X1131299Y54957D03*
X1134645Y49914D03*
X1101181Y54957D03*
X1104227Y49564D03*
X1124606Y54957D03*
X1127952Y49914D03*
X1144685Y54957D03*
X1147331Y49914D03*
X1137992Y54957D03*
X1141038Y49914D03*
X1144535Y112357D03*
X1147331Y106964D03*
X1138242Y112357D03*
X1141038Y106964D03*
X1106001Y220096D03*
X1116141Y222047D03*
X1102621D03*
X1112761Y220096D03*
X1126280D03*
X1122900Y222047D03*
X1133040Y216196D03*
Y220096D03*
X1109381Y218147D03*
X1129660D03*
X1109381Y222047D03*
X1129660D03*
Y210346D03*
X1133040Y212296D03*
X1144300Y216196D03*
Y212296D03*
X1147680Y218147D03*
X1154440Y214247D03*
X1151060Y220096D03*
X1157820Y216196D03*
X1144300Y220096D03*
X1147680Y214247D03*
X1151060Y216196D03*
X1154440Y218147D03*
Y222047D03*
X1161200Y214247D03*
X1134160Y272747D03*
Y276646D03*
X1151060Y270796D03*
Y255196D03*
Y251296D03*
X1154440Y280547D03*
X1157820Y282496D03*
X1144300D03*
X1140920Y280547D03*
X1136420Y261047D03*
X1133040Y262996D03*
X1147680Y264947D03*
X1106001Y227896D03*
X1116141Y225947D03*
X1102621D03*
X1112761Y227896D03*
X1126280D03*
X1133040D03*
Y231797D03*
X1122900Y225947D03*
X1109381Y229847D03*
X1129660Y225947D03*
X1109381D03*
X1129660Y229847D03*
X1116141Y233746D03*
Y241547D03*
X1126280Y235696D03*
Y239596D03*
X1112761Y235696D03*
Y239596D03*
X1122900Y233746D03*
Y241547D03*
X1119521Y231797D03*
Y243496D03*
Y235696D03*
Y239596D03*
X1106001Y235696D03*
Y239596D03*
X1102621Y233746D03*
Y241547D03*
X1106001Y247396D03*
Y255196D03*
X1116141Y249347D03*
Y253247D03*
X1102621Y249347D03*
Y253247D03*
X1112761Y247396D03*
Y255196D03*
X1126280Y247396D03*
Y255196D03*
X1136420Y249347D03*
Y253247D03*
X1122900Y249347D03*
Y253247D03*
X1133040Y247396D03*
Y255196D03*
X1109381Y245447D03*
X1129660D03*
X1109381Y257147D03*
X1129660D03*
X1109381Y249347D03*
X1129660D03*
X1109381Y253247D03*
X1129660D03*
X1147680Y280547D03*
X1157820Y274696D03*
X1154440Y268847D03*
X1140920Y272747D03*
X1114340Y280560D03*
X1154440Y276647D03*
X1101491Y265400D03*
X1104871Y267300D03*
X1119521Y282496D03*
X1116141Y268847D03*
X1112761Y262996D03*
X1116141Y261047D03*
X1119521Y278596D03*
X1144300Y223996D03*
X1154440Y225947D03*
X1147680Y245447D03*
X1127400Y280547D03*
Y276646D03*
X1134160Y280547D03*
X1102336Y274819D03*
X1108125Y276799D03*
X1144300Y266896D03*
X1154440Y257147D03*
X1157820Y251296D03*
X1154440Y249347D03*
X1157820Y247396D03*
X1107600Y271900D03*
X1147680Y249347D03*
X1157820Y266896D03*
X1147680Y276647D03*
X1140920D03*
X1161200Y276646D03*
X1154440Y272747D03*
X1147680Y253247D03*
Y257147D03*
X1109381Y264947D03*
X1151060Y243496D03*
X1144300Y239596D03*
X1151060Y235696D03*
X1144300Y227896D03*
X1154440Y233746D03*
X1147680Y229847D03*
X1154440Y237647D03*
X1157820Y227896D03*
X1147680Y241547D03*
Y237647D03*
X1151060Y239596D03*
X1144300Y231797D03*
X1151060D03*
Y227896D03*
X1157820Y235696D03*
X1161200Y237647D03*
Y280547D03*
X1130780Y282496D03*
X1119521Y266896D03*
Y262996D03*
X1122900Y261047D03*
X1119521Y259096D03*
X1157820Y243496D03*
X1147680Y272747D03*
X1151060Y278596D03*
X1133040Y239596D03*
X1137540Y266896D03*
X1147680Y268847D03*
X1137540Y270796D03*
X1140920Y268847D03*
Y264947D03*
X1144300Y262996D03*
X1126280Y266896D03*
X1129660Y264947D03*
X1122900D03*
Y268847D03*
X1126280Y262996D03*
X1154440Y264947D03*
X1147680Y261047D03*
X1144300Y259096D03*
X1151060Y262996D03*
X1154440Y261047D03*
X1144300Y274696D03*
X1124021Y344896D03*
X1130780Y321496D03*
X1137540Y313696D03*
X1130780Y325396D03*
X1140920Y315647D03*
X1134160Y319547D03*
X1130780Y317596D03*
Y333196D03*
X1134160Y331247D03*
X1151060Y337096D03*
X1140920Y288347D03*
Y284447D03*
X1147680D03*
Y288347D03*
X1151060Y286396D03*
X1144300Y290296D03*
X1147680Y292247D03*
X1154440D03*
Y288347D03*
Y284447D03*
X1157820Y286396D03*
X1114839Y320075D03*
X1113132Y291702D03*
X1113500Y323400D03*
X1137540Y286396D03*
X1101491Y342646D03*
X1119521Y301996D03*
Y298096D03*
Y294196D03*
Y290296D03*
X1118391Y332897D03*
X1127400Y284447D03*
Y300047D03*
X1130780Y294196D03*
X1127400Y296147D03*
Y292247D03*
X1130780Y298096D03*
Y305896D03*
X1137540Y290296D03*
X1134160Y296147D03*
Y288347D03*
X1124021Y325396D03*
X1127400Y323446D03*
X1124021Y329296D03*
Y333196D03*
X1154440Y327347D03*
X1147680Y339047D03*
X1157820Y321496D03*
X1134160Y284447D03*
X1157820Y309797D03*
X1120641Y339047D03*
X1113881Y342947D03*
X1130780Y329296D03*
Y286396D03*
X1134160Y311747D03*
Y315647D03*
X1161200Y288347D03*
Y292247D03*
X1140920Y323446D03*
X1147680Y307847D03*
X1151060Y309797D03*
Y305896D03*
X1144300Y301996D03*
Y298096D03*
X1137540Y301996D03*
X1134160Y303947D03*
X1137540Y298096D03*
X1140920Y303947D03*
X1137540Y305896D03*
X1140920Y296147D03*
X1137540Y294196D03*
X1120641Y342947D03*
X1140920D03*
X1110501Y344896D03*
X1119521Y309797D03*
Y313696D03*
Y317596D03*
X1127400Y311747D03*
X1154440D03*
X1157820Y305896D03*
X1154440Y303947D03*
X1157820Y301996D03*
X1154440Y300047D03*
X1134160Y307847D03*
X1151060Y294196D03*
X1147680Y300047D03*
Y296147D03*
X1140920Y307847D03*
Y311747D03*
X1151060Y301996D03*
X1144300Y305896D03*
X1147680Y311747D03*
X1157820Y298096D03*
X1154440Y296147D03*
X1134160Y335147D03*
Y339047D03*
X1140920Y319547D03*
X1144300Y313696D03*
X1151060D03*
X1144300Y325396D03*
Y321496D03*
X1151060Y329296D03*
X1147680Y335147D03*
Y331247D03*
X1140920Y335147D03*
X1144300Y333196D03*
X1151060Y325396D03*
Y321496D03*
X1147680Y323446D03*
X1137540Y329296D03*
X1144300D03*
X1140920Y327347D03*
X1130780Y340996D03*
Y337096D03*
X1127400Y331247D03*
Y335147D03*
Y339047D03*
X1147680Y315647D03*
X1151060Y317596D03*
X1137540Y337096D03*
Y340996D03*
Y333196D03*
X1134160Y342947D03*
X1137540Y344896D03*
X1144300Y317596D03*
X1137540Y321496D03*
X1134160Y327347D03*
X1137540Y325396D03*
X1109200Y325100D03*
X1127400Y346847D03*
X1130780Y348796D03*
X1127400Y350747D03*
X1103741Y383896D03*
Y387796D03*
X1100361Y381947D03*
Y389747D03*
X1113881Y381947D03*
Y389747D03*
X1124021Y383896D03*
Y387796D03*
X1110501Y383896D03*
Y387796D03*
X1120641Y381947D03*
Y389747D03*
X1134160Y381947D03*
Y389747D03*
X1144300Y395597D03*
Y399496D03*
X1130780Y383896D03*
Y387796D03*
X1140920Y401447D03*
Y393647D03*
X1117261Y379996D03*
X1137540D03*
X1117261Y391696D03*
X1137540D03*
X1117261Y383896D03*
X1137540D03*
X1117261Y387796D03*
X1137540D03*
X1124021Y368296D03*
Y376096D03*
X1130780Y364396D03*
X1134160Y374146D03*
X1120641Y370247D03*
Y374146D03*
X1130780Y368296D03*
Y376096D03*
X1127400Y370247D03*
Y378047D03*
Y366347D03*
Y374146D03*
X1103741Y368296D03*
Y376096D03*
X1113881Y370247D03*
Y374146D03*
X1100361Y370247D03*
Y374146D03*
X1110501Y368296D03*
Y376096D03*
X1103741Y356596D03*
Y360496D03*
X1100361Y354647D03*
Y362447D03*
X1113881Y354647D03*
Y362447D03*
X1124021Y356596D03*
Y360496D03*
X1110501Y356596D03*
Y360496D03*
X1120641Y354647D03*
Y362447D03*
X1107121Y370247D03*
X1117261Y356596D03*
X1107121Y378047D03*
X1117261Y364396D03*
X1107121Y366347D03*
X1117261Y352696D03*
X1107121Y374146D03*
X1117261Y360496D03*
X1157820Y356596D03*
X1144300Y352696D03*
X1154440Y350747D03*
Y362447D03*
X1144300Y368296D03*
X1157820Y379996D03*
X1147680Y389747D03*
X1144300Y376096D03*
X1151060Y383896D03*
X1161200Y362447D03*
X1157820Y364396D03*
X1154440Y370246D03*
X1157820Y376096D03*
X1151060Y372196D03*
X1147680Y378047D03*
X1144300Y379996D03*
Y387796D03*
X1161200Y358547D03*
Y366347D03*
X1157820Y368296D03*
Y372196D03*
X1154440Y374146D03*
X1151060Y376096D03*
X1147680Y381947D03*
X1144300Y383896D03*
X1161200Y354647D03*
X1107121Y350747D03*
X1113881Y346847D03*
X1147680Y370247D03*
Y374146D03*
X1120641Y346847D03*
X1161200Y389747D03*
X1154440Y397546D03*
Y393647D03*
X1151060Y387796D03*
X1157820Y395597D03*
X1154440Y389747D03*
X1157820Y391696D03*
X1154440Y385847D03*
X1140920Y354647D03*
X1161201Y401447D03*
X1157820Y383896D03*
X1137540Y356596D03*
X1156699Y401447D03*
X1134160Y358547D03*
X1137540Y352696D03*
X1130780Y356596D03*
X1134160Y354647D03*
Y350747D03*
X1137540Y348796D03*
X1107874Y518157D03*
X1110520Y513114D03*
X1131299Y518157D03*
X1134645Y513114D03*
X1101181Y518157D03*
X1104227Y513114D03*
X1124606Y518157D03*
X1127952Y513114D03*
X1144685Y518157D03*
X1147331Y513114D03*
X1137992Y518157D03*
X1141038Y513114D03*
X1144385Y498487D03*
X1147331Y490894D03*
X1137992Y498487D03*
X1141038Y491144D03*
X1110520Y534700D03*
X1134645Y535100D03*
X1104141Y534700D03*
X1127952Y535100D03*
X1147331Y534700D03*
X1140952D03*
X1107874Y555957D03*
X1110520Y572500D03*
Y550914D03*
X1131299Y555957D03*
X1134645Y572900D03*
Y550914D03*
X1101181Y555957D03*
X1104141Y572500D03*
X1104227Y550914D03*
X1124606Y555957D03*
X1127952Y572900D03*
Y550914D03*
X1147331Y572500D03*
X1144685Y555957D03*
X1147331Y550914D03*
X1140952Y572500D03*
X1137992Y555957D03*
X1141038Y550914D03*
X1110520Y588714D03*
X1134645D03*
X1104227D03*
X1127952D03*
X1147331D03*
X1141038D03*
X1110520Y610300D03*
X1107874Y593757D03*
X1134645Y610700D03*
X1131299Y593757D03*
X1101181D03*
X1104141Y610300D03*
X1124606Y593757D03*
X1127952Y610700D03*
X1147700Y611200D03*
X1144685Y593757D03*
X1137992D03*
X1141332Y611668D03*
X1171456Y34100D03*
X1164763D03*
X1184142Y33700D03*
X1208267Y34100D03*
X1177763Y33700D03*
X1201574Y34100D03*
X1220953Y33700D03*
X1214574D03*
X1171456Y-3700D03*
X1168110Y17157D03*
X1171456Y12114D03*
X1164763Y-3700D03*
X1161417Y17157D03*
X1164763Y12114D03*
X1184142Y-4100D03*
X1181496Y17157D03*
X1184142Y12114D03*
X1204921Y17157D03*
X1208267Y-3700D03*
Y12114D03*
X1177763Y-4100D03*
X1174803Y17157D03*
X1177849Y12114D03*
X1198228Y17157D03*
X1201574Y-3700D03*
Y12114D03*
X1220953Y-4100D03*
X1218307Y17157D03*
X1220953Y12114D03*
X1214574Y-4100D03*
X1211614Y17157D03*
X1214660Y12114D03*
X1171456Y71900D03*
X1168110Y92757D03*
X1171456Y87714D03*
X1164763Y71900D03*
X1161417Y92757D03*
X1164763Y87714D03*
X1181496Y92757D03*
X1184142Y71500D03*
Y87714D03*
X1208267Y71900D03*
X1204921Y92757D03*
X1208267Y87714D03*
X1177763Y71500D03*
X1174803Y92757D03*
X1177849Y87714D03*
X1201574Y71900D03*
X1198228Y92757D03*
X1201574Y87714D03*
X1220953Y71500D03*
X1218307Y92757D03*
X1220953Y87714D03*
X1214574Y71500D03*
X1211614Y92757D03*
X1214874Y87374D03*
X1168110Y54957D03*
X1171456Y49914D03*
X1161417Y54957D03*
X1164763Y49914D03*
X1181496Y54957D03*
X1184142Y49914D03*
X1204921Y54957D03*
X1208267Y49914D03*
X1174803Y54957D03*
X1177849Y49914D03*
X1198228Y54957D03*
X1201574Y49914D03*
X1218307Y54957D03*
X1220953Y49914D03*
X1211614Y54957D03*
X1214660Y49914D03*
X1167925Y112357D03*
X1170721Y106964D03*
X1161632Y112357D03*
X1164428Y106964D03*
X1181496Y112357D03*
X1184142Y106964D03*
X1204921Y112357D03*
X1208267Y107314D03*
X1174742Y112357D03*
X1177849Y107314D03*
X1198228Y112357D03*
X1201574Y107314D03*
X1208519Y218147D03*
X1167960Y222047D03*
X1164580Y220096D03*
X1161200Y222047D03*
X1171339Y216196D03*
X1181479Y218147D03*
X1191619Y208397D03*
X1209033Y183907D03*
X1188239Y202247D03*
X1181479Y202547D03*
X1174719D03*
X1178099Y204496D03*
X1181479Y214247D03*
X1178099Y212296D03*
X1184859Y208397D03*
Y220096D03*
X1191619Y216196D03*
X1194999Y214247D03*
Y218147D03*
X1198379Y220096D03*
X1201759Y222047D03*
X1164580Y212296D03*
Y208397D03*
X1167960Y214247D03*
X1174719Y210346D03*
X1184859Y216196D03*
X1181479Y210346D03*
X1184859Y212296D03*
X1188239Y218147D03*
X1191619Y220096D03*
Y212296D03*
X1198379Y216196D03*
X1205139Y220096D03*
X1164580Y216196D03*
X1167960Y210346D03*
X1171339Y212296D03*
X1174719Y214247D03*
Y222047D03*
X1221767Y175858D03*
X1220580Y179810D03*
X1161200Y268847D03*
X1164580Y255196D03*
X1171339Y270796D03*
X1164580Y282496D03*
X1167960Y280547D03*
X1171339Y282496D03*
X1167960Y261047D03*
X1174719D03*
X1164580Y251296D03*
X1167960Y272747D03*
X1171339Y255196D03*
Y251296D03*
X1161200Y245447D03*
X1164580Y243496D03*
Y274696D03*
X1174719Y272747D03*
X1167960Y257147D03*
X1161200Y272747D03*
X1191619Y223996D03*
X1178099D03*
X1167960Y233746D03*
X1178099Y270796D03*
Y278596D03*
X1181479Y249347D03*
Y237647D03*
Y241547D03*
X1184859Y223996D03*
X1201759Y237647D03*
X1198379Y227896D03*
X1205139Y231797D03*
X1201759Y245447D03*
X1194999Y237647D03*
X1198379Y251296D03*
X1181479Y264947D03*
X1184859Y255196D03*
X1191619Y270796D03*
X1198379Y262996D03*
X1194999Y276646D03*
X1198379Y282496D03*
Y270796D03*
X1178099Y266896D03*
X1162300Y264947D03*
X1167960Y249347D03*
X1181479Y257147D03*
X1178099Y255196D03*
X1161200Y253247D03*
X1174719Y268847D03*
X1167960Y241547D03*
Y245447D03*
Y237647D03*
X1171339Y239596D03*
Y243496D03*
X1174719Y241547D03*
X1178099Y239596D03*
X1174719Y249347D03*
Y245447D03*
X1171339Y278596D03*
X1178099Y262996D03*
X1205139Y255196D03*
X1208519Y249347D03*
X1201759Y253247D03*
X1205139Y243496D03*
X1212199Y239596D03*
X1205139Y235696D03*
X1212199Y227896D03*
X1208519Y225947D03*
X1205139Y282496D03*
X1201759Y280547D03*
X1198379Y274696D03*
X1201759Y272747D03*
X1205139Y270796D03*
X1201759Y264947D03*
X1205139Y262996D03*
X1208519Y257147D03*
Y253247D03*
X1205139Y251296D03*
X1208519Y241547D03*
Y237647D03*
X1205139Y239596D03*
X1212199Y231797D03*
Y223996D03*
X1205139Y278596D03*
X1201759Y276646D03*
Y268847D03*
X1208519D03*
X1205139Y266896D03*
Y259096D03*
Y223996D03*
X1198379D03*
X1205139Y227896D03*
X1178099Y282496D03*
X1184859Y262996D03*
X1191619Y259096D03*
X1194999Y261047D03*
Y257147D03*
X1188239Y253247D03*
X1194999Y249347D03*
X1198379Y247396D03*
X1191619Y243496D03*
X1188239Y241547D03*
X1181479Y245447D03*
X1184859Y278596D03*
X1188239Y276646D03*
Y280547D03*
X1181479Y272747D03*
X1188239Y268847D03*
X1191619Y266896D03*
X1181479Y280547D03*
X1188239Y261047D03*
X1191619Y262996D03*
X1198379Y259096D03*
X1191619Y255196D03*
Y251296D03*
X1194999Y253247D03*
Y245447D03*
Y241547D03*
X1188239Y245447D03*
X1184859Y243496D03*
Y282496D03*
Y274696D03*
X1191619Y282496D03*
Y278596D03*
X1184859Y270796D03*
X1188239Y272747D03*
Y264947D03*
X1174719Y229847D03*
X1167960Y225947D03*
X1174719Y233746D03*
X1181479Y229847D03*
X1184859Y227896D03*
Y231797D03*
X1191619Y235696D03*
Y227896D03*
X1198379Y231797D03*
X1161200Y233746D03*
Y229847D03*
X1171339Y227896D03*
Y223996D03*
X1174719Y225947D03*
X1178099Y231797D03*
X1181479Y233746D03*
Y225947D03*
X1188239Y229847D03*
Y233746D03*
X1191619Y231797D03*
X1194999Y229847D03*
X1161200Y225947D03*
X1164580Y231797D03*
X1174719Y257147D03*
X1178099Y259096D03*
X1174719Y276646D03*
X1167960D03*
Y268847D03*
X1181479Y253247D03*
X1178099Y251296D03*
X1167960Y264947D03*
X1171339Y262996D03*
X1174719Y264947D03*
X1208519Y229847D03*
X1184859Y337096D03*
X1178099Y340996D03*
X1181479Y339047D03*
Y342947D03*
X1178099Y344896D03*
X1201759Y331247D03*
Y335147D03*
Y342947D03*
X1198379Y344896D03*
Y333196D03*
X1201759Y339047D03*
X1205139Y340996D03*
X1181479Y331247D03*
X1167960Y284447D03*
X1198379Y321496D03*
X1194999Y323446D03*
X1181479Y315647D03*
X1171339Y344896D03*
X1174719Y339047D03*
X1164580Y340996D03*
X1167960Y331247D03*
X1171339Y321496D03*
X1184859Y325396D03*
Y333196D03*
X1198379Y337096D03*
Y329296D03*
X1194999Y342947D03*
X1174719Y323446D03*
X1181479D03*
X1174719Y327347D03*
X1178099Y333196D03*
X1171339Y329296D03*
X1167960Y335147D03*
X1171339Y340996D03*
X1174719Y319547D03*
X1178099Y321496D03*
Y325396D03*
Y329296D03*
X1174719Y331247D03*
X1171339Y333196D03*
Y337096D03*
X1161200Y311747D03*
X1198379Y290296D03*
Y294196D03*
X1161200Y300047D03*
Y303947D03*
X1201759Y292247D03*
X1205439Y290296D03*
Y294196D03*
Y286596D03*
X1208819Y284447D03*
X1184859Y286396D03*
X1191619D03*
X1194999Y284447D03*
X1181479D03*
X1191619Y290296D03*
Y313696D03*
Y309797D03*
X1188239Y307847D03*
Y303947D03*
Y300047D03*
X1184859Y298096D03*
Y344896D03*
X1191619D03*
Y340996D03*
Y337096D03*
X1188239Y331247D03*
X1194999Y327347D03*
X1188239D03*
X1184859Y317596D03*
X1191619D03*
X1194999Y311747D03*
X1191619Y305896D03*
X1184859D03*
X1191619Y301996D03*
X1188239Y296147D03*
X1181479D03*
X1184859Y340996D03*
X1188239Y342947D03*
X1194999Y339047D03*
X1191619Y333196D03*
Y329296D03*
Y325396D03*
X1188239Y323446D03*
X1184859Y313696D03*
X1188239Y315647D03*
X1174719Y303947D03*
X1167960D03*
X1178099Y309797D03*
X1171339Y305896D03*
X1164580Y309797D03*
Y305896D03*
X1167960Y307847D03*
Y311747D03*
X1171339Y309797D03*
X1178099Y301996D03*
X1174719Y311747D03*
Y307847D03*
X1178099Y305896D03*
Y313696D03*
X1171339D03*
X1164580D03*
X1174719Y292247D03*
Y288347D03*
X1171339Y286396D03*
Y290296D03*
X1167960Y300047D03*
X1164580Y298096D03*
X1167960Y296147D03*
Y292247D03*
Y288347D03*
X1161200Y296147D03*
X1178099Y290296D03*
X1171339Y298096D03*
Y294196D03*
X1174719Y296147D03*
Y346847D03*
X1178099Y348796D03*
Y352696D03*
X1201759Y346847D03*
X1167960Y358547D03*
X1174719Y350747D03*
X1167960Y366347D03*
X1171339Y368296D03*
X1161200Y374146D03*
X1178099Y391696D03*
X1174719Y397546D03*
X1164580Y399496D03*
X1188239Y370247D03*
X1191619Y372197D03*
Y364396D03*
Y352696D03*
X1181479Y385847D03*
Y405347D03*
X1188239Y381947D03*
X1208819Y385847D03*
X1164580Y368296D03*
X1167960Y350747D03*
Y354647D03*
X1164580Y360496D03*
Y364396D03*
X1167960Y346847D03*
X1171339Y352696D03*
X1184859Y348796D03*
X1188239Y346847D03*
X1178099Y387796D03*
X1171339D03*
Y391696D03*
X1167960Y393647D03*
X1164580Y395597D03*
X1178099Y379996D03*
Y383896D03*
X1174719Y385847D03*
X1171339Y383896D03*
X1174719Y389747D03*
X1171339Y395596D03*
X1164580Y391696D03*
Y387796D03*
X1178099Y376096D03*
X1181479Y381947D03*
X1188239Y354647D03*
Y358547D03*
Y362447D03*
X1181479D03*
Y366347D03*
X1184859Y372197D03*
Y376096D03*
Y379996D03*
X1188239Y350747D03*
X1191619Y356596D03*
X1184859Y360496D03*
X1181479Y358547D03*
X1184859Y364396D03*
Y368296D03*
X1188239Y374146D03*
X1181479Y378047D03*
X1174719Y370247D03*
X1181479D03*
X1171339Y364396D03*
X1178099Y360496D03*
Y356596D03*
X1184859Y352696D03*
X1161200Y393647D03*
Y385847D03*
X1167960D03*
Y381947D03*
Y378047D03*
X1174719D03*
Y374146D03*
Y366347D03*
X1178099Y368296D03*
X1174719Y362447D03*
Y358547D03*
X1181479Y354647D03*
Y350747D03*
X1161200Y381947D03*
X1164580Y383896D03*
X1171339Y379996D03*
X1167960Y374146D03*
X1171339Y376096D03*
X1178099Y372197D03*
X1167960Y405347D03*
X1194999Y378047D03*
X1201759Y374146D03*
X1194999D03*
X1198379Y364396D03*
Y360496D03*
Y356596D03*
X1174719Y405347D03*
Y401447D03*
X1178099Y395596D03*
X1184859Y399496D03*
X1181479Y393647D03*
X1188239Y389747D03*
Y385847D03*
X1191619Y379996D03*
X1198379Y383896D03*
X1167960Y401447D03*
X1198379Y376096D03*
Y372197D03*
X1194999Y370247D03*
Y362447D03*
X1201759Y358547D03*
X1198379Y352696D03*
X1171339Y403396D03*
X1178099Y399496D03*
X1181479Y397546D03*
X1184859Y395596D03*
Y391696D03*
Y387796D03*
X1191619Y383896D03*
X1194999Y381947D03*
X1198379Y379996D03*
X1164580Y376096D03*
X1194999Y350747D03*
X1198379Y348796D03*
X1168110Y518157D03*
X1171456Y513114D03*
X1161417Y518157D03*
X1164763Y513114D03*
X1181496Y518157D03*
X1184142Y513114D03*
X1204921Y518157D03*
X1208267Y513114D03*
X1174803Y518157D03*
X1177849Y513114D03*
X1198228Y518157D03*
X1201574Y513114D03*
X1218307Y518157D03*
X1220953Y513114D03*
X1211614Y518157D03*
X1214874Y512774D03*
X1167510Y498487D03*
X1170656Y493844D03*
X1161417Y498487D03*
X1164363Y493744D03*
X1180400Y498387D03*
X1184142Y493394D03*
X1204400Y498487D03*
X1208267Y496144D03*
X1174203Y498387D03*
X1177799Y493544D03*
X1198100Y498400D03*
X1200974Y493344D03*
X1171456Y535100D03*
X1164763D03*
X1184142Y534700D03*
X1208267Y535100D03*
X1177763Y534700D03*
X1201574Y535100D03*
X1220953Y534700D03*
X1214574D03*
X1171456Y572900D03*
X1168110Y555957D03*
X1171456Y550914D03*
X1164763Y572900D03*
X1161417Y555957D03*
X1164763Y550914D03*
X1184142Y572500D03*
X1181496Y555957D03*
X1184142Y550914D03*
X1208267Y572900D03*
X1204921Y555957D03*
X1208267Y550914D03*
X1177763Y572500D03*
X1174803Y555957D03*
X1177849Y550914D03*
X1201574Y572900D03*
X1198228Y555957D03*
X1201574Y550914D03*
X1218307Y555957D03*
X1220953Y572500D03*
Y550914D03*
X1211614Y555957D03*
X1214574Y572500D03*
X1214874Y550574D03*
X1171456Y588714D03*
X1164763D03*
X1184142D03*
X1208267D03*
X1177849D03*
X1201574D03*
X1220953D03*
X1214660D03*
X1168110Y593757D03*
X1171456Y610700D03*
X1161417Y593757D03*
X1164763Y610700D03*
X1181496Y593757D03*
X1184142Y610300D03*
X1208267Y610700D03*
X1204921Y593757D03*
X1174803D03*
X1177763Y610300D03*
X1198228Y593757D03*
X1201574Y610700D03*
X1218307Y593757D03*
X1220953Y610300D03*
X1211614Y593757D03*
X1214574Y610300D03*
X1245078Y34100D03*
X1238385D03*
X1245078Y-3700D03*
X1241732Y17157D03*
X1245078Y12114D03*
X1238385Y-3700D03*
X1235039Y17157D03*
X1238385Y12114D03*
X1251771Y27899D03*
Y36057D03*
X1248425Y17057D03*
X1258464Y36057D03*
Y27899D03*
X1265157Y36057D03*
X1261811D03*
Y27899D03*
Y16999D03*
X1258464D03*
X1265157Y9157D03*
X1251771D03*
Y-1743D03*
X1261811Y-9901D03*
X1258464D03*
X1261811Y-1743D03*
X1265157D03*
X1258464D03*
X1255118Y-9901D03*
Y27899D03*
Y16999D03*
Y-1743D03*
Y36057D03*
Y9157D03*
X1265157Y27899D03*
Y-9901D03*
Y16999D03*
X1276346Y-10250D03*
X1245078Y71900D03*
X1241732Y92757D03*
X1245078Y87714D03*
X1238385Y71900D03*
X1235039Y92757D03*
X1238385Y87714D03*
X1241732Y54957D03*
X1245078Y49914D03*
X1235039Y54957D03*
X1238385Y49914D03*
X1251771Y54799D03*
X1248425Y54857D03*
X1251771Y46957D03*
X1258464D03*
Y54799D03*
X1261811Y46957D03*
Y54799D03*
Y65699D03*
X1258464D03*
X1251771Y84757D03*
X1248425Y92657D03*
X1265157Y73857D03*
X1261811D03*
X1258464D03*
X1261811Y84757D03*
X1258464D03*
X1265157D03*
X1251771Y73857D03*
X1261811Y92599D03*
X1258464D03*
X1255118Y65699D03*
Y54799D03*
Y92599D03*
Y46957D03*
Y84757D03*
Y73857D03*
X1265157Y65699D03*
Y92599D03*
Y54799D03*
X1270350Y98300D03*
X1268111Y58040D03*
X1251344Y127925D03*
X1259950Y144650D03*
X1277100Y122670D03*
X1272100Y141603D03*
X1264550Y114670D03*
X1277100Y114800D03*
X1261030Y105350D03*
X1277600Y106200D03*
X1248616Y133817D03*
X1237704Y148423D03*
X1268576Y117788D03*
X1250200Y122900D03*
X1251980Y106960D03*
X1262569Y147201D03*
X1243948Y154916D03*
X1269810Y154398D03*
X1275470Y99390D03*
X1252000Y145300D03*
X1257800Y120800D03*
X1255400Y108000D03*
X1252437Y140192D03*
X1249025Y130460D03*
X1240000Y129500D03*
X1259200Y168350D03*
X1281799Y193190D03*
X1267800Y161800D03*
X1271400Y161900D03*
X1240309D03*
X1267050Y169800D03*
X1233902Y173337D03*
X1241381Y172040D03*
X1246655Y176395D03*
X1263300Y169450D03*
X1268404Y246304D03*
X1279393Y247602D03*
X1270478Y243490D03*
X1277504Y250346D03*
X1272761Y240220D03*
X1283720Y223870D03*
X1249230Y402022D03*
X1262700Y461804D03*
X1262900Y466504D03*
X1277978Y491571D03*
X1241732Y518157D03*
X1245078Y513114D03*
X1235039Y518157D03*
X1238385Y513114D03*
X1278573Y519596D03*
X1265157Y510157D03*
X1261811Y517999D03*
X1258464Y510157D03*
Y517999D03*
X1261811Y510157D03*
X1248425Y518057D03*
X1251771Y510157D03*
X1258464Y528899D03*
X1261811D03*
X1255120Y518000D03*
Y510158D03*
X1271300Y510600D03*
X1271105Y498516D03*
X1274576Y510235D03*
X1265157Y528876D03*
Y517999D03*
X1262843Y497553D03*
X1258126Y469540D03*
X1245078Y535100D03*
X1238385D03*
X1241732Y555957D03*
X1245078Y572900D03*
Y550914D03*
X1238385Y572900D03*
X1235039Y555957D03*
X1238385Y550914D03*
X1245078Y588714D03*
X1238385D03*
X1265157Y547957D03*
X1261811D03*
X1258464D03*
X1251771D03*
X1265157Y537057D03*
X1261811D03*
X1251771D03*
X1258464D03*
X1265157Y585757D03*
X1261811D03*
X1258464D03*
X1251771D03*
X1261811Y555799D03*
X1258464D03*
X1251771D03*
X1248425Y555857D03*
X1251771Y566699D03*
Y574857D03*
X1265157D03*
X1261811D03*
X1258464D03*
X1261811Y566699D03*
X1258464D03*
X1273200Y582200D03*
X1255120Y555144D03*
Y574834D03*
Y537034D03*
X1265157Y566676D03*
Y555799D03*
X1277200Y539100D03*
X1270400Y593600D03*
X1241732Y593757D03*
X1245078Y610700D03*
X1238385D03*
X1235039Y593757D03*
X1258464Y593599D03*
X1261811D03*
X1248425Y593657D03*
X1251771Y612657D03*
X1258464Y604499D03*
X1261811D03*
X1265157Y612657D03*
X1261811D03*
X1258464D03*
X1255120Y593600D03*
Y612634D03*
X1265157Y604476D03*
Y593599D03*
X1293600Y-17000D03*
X1293816Y-13533D03*
X1292692Y1008D03*
X1296908Y36900D03*
X1287700Y-16700D03*
X1303774Y-18842D03*
X1298422Y74000D03*
X1330300Y83500D03*
X1336850Y76450D03*
X1327168Y61483D03*
X1304685Y78827D03*
X1298754Y83233D03*
X1336900Y61600D03*
X1343260Y53770D03*
X1327500Y51547D03*
X1327452Y55544D03*
X1309700Y83300D03*
X1336500Y81100D03*
X1324127Y50827D03*
X1337400Y72000D03*
X1301219Y89141D03*
X1304500Y40066D03*
X1296935Y51335D03*
X1323000Y83000D03*
X1308400Y79600D03*
X1306900Y131744D03*
X1301900Y124400D03*
X1325125Y100001D03*
X1310098Y150040D03*
X1293700Y121800D03*
X1295700Y144450D03*
X1327900Y142918D03*
X1301770Y101300D03*
X1320500Y145000D03*
X1325100D03*
X1287790Y156575D03*
X1310175Y154696D03*
X1299907Y159808D03*
X1295500Y159970D03*
X1300300Y169900D03*
X1315130Y164870D03*
X1315180Y169950D03*
X1326474Y216500D03*
X1338224Y209051D03*
X1305171Y164767D03*
X1310061Y165235D03*
X1344462Y209272D03*
X1323030Y216531D03*
X1330100Y165000D03*
Y170000D03*
X1340100Y165000D03*
X1345100D03*
Y170000D03*
X1340100D03*
X1335100D03*
Y165000D03*
X1320100D03*
X1325100D03*
X1320100Y170000D03*
X1325100D03*
X1345050Y272350D03*
X1300444Y267919D03*
X1309462Y240229D03*
X1288800Y233900D03*
X1320289Y237671D03*
X1331400Y237900D03*
X1342400D03*
X1315100Y237645D03*
X1325900Y237900D03*
X1336900D03*
X1320400Y232118D03*
X1331400D03*
X1342400D03*
X1314900D03*
X1325900D03*
X1336900D03*
X1331650Y317250D03*
X1338700Y284700D03*
X1323750Y319750D03*
X1320900Y321300D03*
X1335250Y344250D03*
X1319310Y300795D03*
X1336336Y333825D03*
X1302768Y296942D03*
X1331720Y334810D03*
X1326300Y341309D03*
X1341375Y314675D03*
Y319675D03*
X1341740Y306760D03*
X1336240D03*
X1316600Y305500D03*
X1306290Y298255D03*
X1308887Y285015D03*
X1319888Y290205D03*
X1323688D03*
X1345700Y285300D03*
X1341740Y301243D03*
X1336240D03*
X1335400Y284900D03*
X1302203Y314439D03*
X1315496Y361190D03*
X1342570Y368220D03*
X1326014Y347732D03*
X1296468Y437500D03*
X1325100Y457500D03*
Y452500D03*
X1320100Y457500D03*
Y452500D03*
X1315100D03*
X1310100D03*
X1315100Y457500D03*
X1305100D03*
Y452500D03*
X1310100Y457500D03*
X1330100D03*
Y452500D03*
X1300315Y427902D03*
X1335100Y427500D03*
Y432500D03*
X1300438Y433001D03*
X1318054Y460507D03*
X1340100Y432500D03*
X1304200Y466600D03*
Y462030D03*
X1309870Y499254D03*
X1287770Y501897D03*
X1299450Y484950D03*
X1320300Y498300D03*
X1316100Y543400D03*
X1308500Y540784D03*
X1324707Y545493D03*
X1327956Y545655D03*
X1318500Y539900D03*
X1305500Y542500D03*
X1296295Y615596D03*
X1301384Y618119D03*
X1400616Y13795D03*
X1376094Y4406D03*
X1380678Y-422D03*
X1380950Y30232D03*
X1379025Y-9799D03*
X1407422Y13139D03*
X1377009Y39753D03*
X1347500Y83000D03*
X1355500D03*
X1358500Y74500D03*
X1363500Y77400D03*
X1370975Y67225D03*
X1370849Y59349D03*
X1371910Y48800D03*
X1351500Y83000D03*
X1367700Y86450D03*
X1371500Y63200D03*
X1351488Y74000D03*
X1372300Y86400D03*
X1406546Y43116D03*
X1383171Y57549D03*
X1401300Y149600D03*
X1384600Y108500D03*
X1381359Y108496D03*
X1388100Y108500D03*
X1371500Y101000D03*
X1404200Y119200D03*
X1402500Y116300D03*
X1399100Y166900D03*
X1396933Y215763D03*
X1353569Y208960D03*
X1348569D03*
X1367789Y209216D03*
X1384671Y214832D03*
X1402020Y165561D03*
X1350100Y170000D03*
X1380100Y165000D03*
X1355100Y170000D03*
X1360100D03*
X1355100Y165000D03*
X1360100D03*
X1350100D03*
X1365100Y170000D03*
Y165000D03*
X1370100D03*
X1375100Y170000D03*
X1370100D03*
X1375100Y165000D03*
X1380100Y170000D03*
X1399852Y252353D03*
X1407274Y245652D03*
X1353400Y237900D03*
X1364400D03*
X1375400D03*
X1386400D03*
X1347900D03*
X1358900D03*
X1369900D03*
X1380900D03*
X1391900D03*
X1353400Y232118D03*
X1364400D03*
X1375400D03*
X1347900D03*
X1358900D03*
X1369900D03*
X1380900D03*
X1391900D03*
X1365246Y285931D03*
X1363700Y321600D03*
X1367200D03*
X1352400Y285000D03*
X1396470Y330014D03*
X1392400Y330800D03*
X1400400Y335400D03*
X1388450Y331250D03*
X1359200Y322200D03*
X1364260Y331619D03*
X1349134Y317436D03*
X1360294Y315025D03*
X1371090Y315395D03*
X1380904Y315947D03*
X1392226Y315658D03*
X1400558Y320157D03*
X1349134Y321145D03*
X1360294Y318825D03*
X1371090Y319195D03*
X1380904Y319747D03*
X1392226Y319458D03*
X1400558Y316357D03*
X1353142Y306760D03*
X1364044Y306690D03*
X1374840Y307130D03*
X1386048Y307310D03*
X1397635Y307630D03*
X1347642Y306760D03*
X1358544Y306690D03*
X1369340Y307130D03*
X1380548Y307310D03*
X1392135Y307630D03*
X1403037D03*
X1368200Y284000D03*
X1353672Y299605D03*
X1364014Y300815D03*
X1374820Y301219D03*
X1386101Y301465D03*
X1397635Y302051D03*
X1347892Y299741D03*
X1358514Y300815D03*
X1369320Y301219D03*
X1380601Y301465D03*
X1392135Y302051D03*
X1403037Y302046D03*
X1355300Y321675D03*
X1381431Y284259D03*
X1394370Y384230D03*
X1378207Y394568D03*
X1394260Y351170D03*
X1389500Y360500D03*
X1391845Y348325D03*
X1388300Y346200D03*
X1371600Y368700D03*
X1374300Y377885D03*
Y381485D03*
X1380872Y378098D03*
X1380900Y383164D03*
X1388900Y387800D03*
X1378200Y346900D03*
X1377028Y458125D03*
X1372028D03*
X1360100Y447500D03*
Y452500D03*
Y457500D03*
X1385100Y452500D03*
Y447500D03*
X1390100Y457500D03*
X1389900Y447400D03*
X1390100Y452500D03*
X1395100Y432500D03*
Y447500D03*
Y427500D03*
X1349800Y458200D03*
X1350100Y447500D03*
Y452500D03*
X1375100Y447500D03*
X1362560Y463478D03*
X1370100Y452500D03*
X1375100D03*
X1385100Y427500D03*
Y442500D03*
Y437500D03*
X1390100Y432500D03*
X1389900Y427400D03*
X1385100Y432500D03*
X1365100D03*
Y427500D03*
Y437500D03*
X1380100Y442500D03*
Y437500D03*
X1370100D03*
X1375100D03*
X1370100Y447500D03*
X1403027Y520231D03*
X1395242Y520301D03*
X1347546Y476897D03*
X1380741Y487489D03*
X1360863Y481673D03*
X1362841Y492823D03*
X1383263Y493673D03*
X1381041Y482575D03*
X1360741Y486523D03*
X1362880Y497556D03*
X1383241Y498595D03*
X1396035Y514863D03*
X1347196Y472941D03*
X1354462Y474141D03*
X1350500Y475100D03*
X1386241Y487323D03*
X1366341Y481823D03*
X1368441Y492723D03*
X1388741Y493623D03*
X1386241Y482623D03*
X1366309Y486618D03*
X1368441Y497523D03*
X1388719Y498745D03*
X1399721Y537509D03*
X1379053Y581864D03*
X1390595Y549328D03*
X1375961Y569473D03*
X1376000Y565700D03*
X1382000Y589500D03*
X1375600Y589700D03*
X1400216Y560128D03*
X1396158Y537595D03*
X1380890Y615820D03*
X1386921Y620689D03*
X1390851D03*
X1375961Y600673D03*
X1375861Y597073D03*
X1375961Y593473D03*
X1382100Y592800D03*
X1410600Y9100D03*
X1425081Y48412D03*
X1411546Y43116D03*
X1453700Y83750D03*
X1457000Y82000D03*
X1420337Y45477D03*
X1416837D03*
X1451021Y151626D03*
X1438348Y155908D03*
X1468700Y163100D03*
X1458569Y192143D03*
X1458908Y187699D03*
X1459548Y221731D03*
X1446331Y197285D03*
X1422281Y221479D03*
X1447999Y205645D03*
X1451366Y165296D03*
X1408247Y206270D03*
X1422196Y218052D03*
X1452728Y243306D03*
X1452200Y254500D03*
X1430365Y262624D03*
X1448500Y257700D03*
X1458318Y243000D03*
X1426905Y267045D03*
X1464150Y235550D03*
X1455600Y254826D03*
X1433057Y257388D03*
X1447154Y251710D03*
X1441750Y236800D03*
X1467040Y260357D03*
X1466006Y265300D03*
X1426658Y274252D03*
X1461348Y244350D03*
X1444850Y242730D03*
X1408250Y333000D03*
X1413387Y320033D03*
Y316233D03*
X1408537Y307630D03*
X1413720Y307634D03*
X1419333Y307598D03*
X1443500Y327900D03*
X1468399Y324930D03*
X1408537Y302046D03*
X1413720Y301983D03*
X1419220D03*
X1444311Y324366D03*
X1466970Y320235D03*
X1420075Y388402D03*
X1413735Y391302D03*
X1420075Y383375D03*
X1420515Y368585D03*
X1420075Y393402D03*
X1413735Y396302D03*
X1420075Y378375D03*
X1420515Y373585D03*
X1452699Y404060D03*
X1457300Y373600D03*
X1444400Y371600D03*
X1413400Y361300D03*
X1464400Y390800D03*
X1450400Y354300D03*
X1448000Y431500D03*
X1431900Y437100D03*
X1447700Y442500D03*
X1431900Y448000D03*
X1448000Y437000D03*
X1431900Y442600D03*
X1447500Y448000D03*
X1431900Y453500D03*
X1414107Y447267D03*
X1458300Y442675D03*
X1431690Y521530D03*
X1410486Y529792D03*
X1458060Y495020D03*
X1464553Y508872D03*
X1428500Y521000D03*
X1461267Y489790D03*
X1412941Y489523D03*
X1413193Y482532D03*
X1436600Y482900D03*
X1436541Y494423D03*
X1412741Y494223D03*
X1413041Y477423D03*
X1436396Y477691D03*
X1436441Y489323D03*
X1451533Y527867D03*
X1460661Y484891D03*
X1418241Y489523D03*
X1418441Y482523D03*
X1441842Y482924D03*
X1442041Y494423D03*
X1418341D03*
Y477323D03*
X1442141Y477623D03*
X1442041Y489223D03*
X1441252Y548631D03*
X1451150Y569900D03*
Y573200D03*
X1439822Y537382D03*
X1429026Y541026D03*
X1428281Y546119D03*
X1413600Y531300D03*
X1432560Y561160D03*
X1436160Y561200D03*
X1428791Y535512D03*
X1419600Y531500D03*
X1410950Y589670D03*
X1441409Y561117D03*
X1453533Y532667D03*
X1426870Y530800D03*
X1423800Y534800D03*
X1425243Y562260D03*
X1421560Y563455D03*
X1460200Y606200D03*
X1477100Y2400D03*
X1522600Y-6500D03*
X1504400Y20300D03*
X1481600Y5300D03*
X1501900Y-9124D03*
X1485242Y4589D03*
X1506300Y-6600D03*
X1521092Y21665D03*
X1520700Y7100D03*
X1513700Y7082D03*
X1519599Y86117D03*
X1524557Y88336D03*
X1505673Y146346D03*
X1473354Y153246D03*
X1485210Y134837D03*
X1476761Y157400D03*
X1483366Y120746D03*
Y115902D03*
X1484113Y128513D03*
X1485755Y131671D03*
X1518376Y111499D03*
X1476761Y152725D03*
X1518438Y100926D03*
X1494939Y159500D03*
X1510184Y142614D03*
X1503466Y142486D03*
X1500703Y158233D03*
X1514425Y134180D03*
X1520150Y127600D03*
X1475200Y142600D03*
X1496038Y154229D03*
X1488300Y158300D03*
X1500643Y154819D03*
X1513136Y157081D03*
X1496726Y120588D03*
X1496658Y115088D03*
X1500700Y127250D03*
X1500806Y133339D03*
X1518514Y130991D03*
X1524900Y139100D03*
X1526310Y142190D03*
X1524284Y112773D03*
X1474717Y110370D03*
X1482455Y124222D03*
X1502000Y147500D03*
X1490674Y98787D03*
X1524744Y133656D03*
X1496713Y174853D03*
X1504706Y164871D03*
X1511100Y186275D03*
X1492597Y172636D03*
X1488900Y172576D03*
X1474883Y182275D03*
X1478089Y182650D03*
X1470382Y188372D03*
X1472758Y216495D03*
X1513900Y218000D03*
X1519243Y191627D03*
X1487716Y218650D03*
X1477388Y172988D03*
X1497237Y217281D03*
X1497493Y162078D03*
X1512700Y205100D03*
X1488300Y161700D03*
X1498022Y221900D03*
X1512525Y208944D03*
X1492136Y199125D03*
X1493200Y162700D03*
X1512500Y199837D03*
X1510638Y166240D03*
X1516872Y208863D03*
X1491438Y221137D03*
X1510800Y193330D03*
X1515060Y192443D03*
X1507524Y218600D03*
X1472200Y243000D03*
X1482004Y222483D03*
X1525650Y248700D03*
X1470950Y229669D03*
X1526150Y234300D03*
X1486926Y247834D03*
X1516549Y234278D03*
X1516613Y240656D03*
X1521962Y278650D03*
X1512790Y240099D03*
X1499681Y279910D03*
X1507003Y272249D03*
X1492753Y273724D03*
X1484000Y257500D03*
X1492697Y267303D03*
X1475004Y246287D03*
X1474520Y251740D03*
X1482400Y248000D03*
X1487500Y244500D03*
X1505946Y254432D03*
X1519300Y245196D03*
X1499070Y255934D03*
X1470556Y256900D03*
X1484700Y251800D03*
X1527657Y278700D03*
X1503842Y245678D03*
X1504772Y259229D03*
X1523580Y237960D03*
X1496812Y273718D03*
X1479700Y224801D03*
X1504461Y274426D03*
X1520413Y239498D03*
X1491265Y226492D03*
X1483457Y244568D03*
X1474096Y256706D03*
X1497082Y277987D03*
X1526936Y307015D03*
X1529734Y319714D03*
X1473231Y320250D03*
X1499723Y300106D03*
X1471562Y325531D03*
X1512182Y293317D03*
X1497179Y306372D03*
X1508455Y313041D03*
X1523935Y318901D03*
X1514067Y315626D03*
X1484100Y330115D03*
X1501550Y293750D03*
X1482550Y333600D03*
X1487000Y333300D03*
X1503538Y318068D03*
X1518006Y286706D03*
X1499987Y288487D03*
X1496628Y288440D03*
X1520766Y341000D03*
X1505000Y340990D03*
X1508650Y287500D03*
X1510851Y340113D03*
X1500840Y319870D03*
X1504370Y330970D03*
X1518060Y317520D03*
X1470276Y330774D03*
X1493268Y293943D03*
X1496900Y293900D03*
X1525677Y311835D03*
X1499829Y341250D03*
X1530500Y287700D03*
X1510584Y330640D03*
X1526900Y292866D03*
X1470257Y321929D03*
X1493290Y287984D03*
X1483506Y326061D03*
X1514100Y321792D03*
X1517115Y330005D03*
X1507025Y391034D03*
X1493375Y380894D03*
X1505075D03*
X1501175Y394414D03*
X1499225Y391034D03*
Y384274D03*
X1487525Y397794D03*
X1493375Y394414D03*
X1489475D03*
X1487525Y384274D03*
X1489475Y387654D03*
X1514265Y355542D03*
X1499225Y377514D03*
X1495325Y391034D03*
X1493375Y387654D03*
X1505075Y394414D03*
X1501175Y387654D03*
X1495325Y377514D03*
X1524575Y394414D03*
X1530425Y384274D03*
X1487525Y377514D03*
X1517367Y349964D03*
X1472940Y384030D03*
X1473255Y372654D03*
X1525561Y350253D03*
X1511000Y350627D03*
X1505075Y387654D03*
Y401174D03*
X1501175D03*
X1507025Y404554D03*
X1522625Y391034D03*
X1495325Y397794D03*
X1499225D03*
Y404554D03*
X1493375Y401174D03*
X1489475D03*
X1507025Y384274D03*
X1501175Y380894D03*
X1522625Y404554D03*
X1481000Y350000D03*
X1502970Y350610D03*
X1496000Y350000D03*
X1528475Y380894D03*
X1522625Y397794D03*
X1528475Y401174D03*
Y387654D03*
X1529829Y362655D03*
X1516775Y380894D03*
X1526659Y397500D03*
X1528475Y394414D03*
X1524575Y380894D03*
X1522476Y361907D03*
X1507025Y377514D03*
X1520675Y394414D03*
X1522625Y377514D03*
X1530425D03*
X1518725Y397794D03*
Y391034D03*
Y384274D03*
X1510925Y397794D03*
X1512875Y401174D03*
Y394414D03*
X1530425Y391034D03*
X1514925Y358844D03*
X1484600Y394100D03*
X1495325Y384274D03*
X1483868Y390233D03*
X1483664Y362914D03*
X1520675Y401174D03*
X1516775D03*
Y394414D03*
X1510925Y377514D03*
X1512875Y380894D03*
X1515328Y363389D03*
X1518725Y377514D03*
X1522625Y384274D03*
X1510925Y391034D03*
X1516775Y387654D03*
X1512875D03*
X1510925Y384274D03*
X1478163Y354940D03*
X1530425Y397794D03*
X1489475Y380894D03*
X1524575Y387654D03*
X1503878Y364717D03*
X1485300Y443484D03*
X1489475Y450306D03*
X1491425Y453686D03*
X1493375Y457066D03*
X1499225Y460446D03*
X1493375Y450306D03*
X1489475Y457066D03*
X1495325Y460446D03*
X1497275Y463826D03*
X1483375Y458375D03*
X1530425Y467206D03*
X1516700Y409900D03*
X1528475Y407934D03*
X1512875Y463826D03*
X1510925Y467206D03*
X1507025D03*
X1508975Y463826D03*
X1501175Y428214D03*
X1495325Y418074D03*
X1499225Y424834D03*
X1516775Y463826D03*
X1505075D03*
X1524575D03*
X1493375Y414694D03*
X1489475D03*
X1491425Y411314D03*
X1487525D03*
X1493375Y443546D03*
X1489475D03*
X1491425Y440166D03*
X1487525D03*
X1516775Y457066D03*
X1528475Y463826D03*
X1524575Y407624D03*
X1514825Y467206D03*
X1499225Y411314D03*
X1501175Y407934D03*
X1499225Y440166D03*
X1524575Y457066D03*
X1505075D03*
X1501175Y443546D03*
X1485250Y408017D03*
X1501200Y450600D03*
X1521800Y419900D03*
X1508975Y457066D03*
X1505715Y441368D03*
X1497200Y421200D03*
X1491425Y446926D03*
X1493375Y428214D03*
X1489475D03*
X1493375Y436786D03*
X1489475D03*
X1499225Y446926D03*
Y453686D03*
X1491425Y460446D03*
X1499225Y467206D03*
X1489475Y463826D03*
X1491425Y467206D03*
X1487525Y460446D03*
X1495325Y467206D03*
X1485030Y463690D03*
X1491400Y424600D03*
X1487500D03*
X1489475Y421454D03*
X1493375D03*
X1520675Y463826D03*
X1505075Y407934D03*
X1497273Y407610D03*
X1489475Y407934D03*
X1493375D03*
X1520675Y470586D03*
X1503400Y524663D03*
X1524575Y470586D03*
X1520675Y477346D03*
X1512875Y470586D03*
X1472500Y509810D03*
X1474400Y517200D03*
X1482200Y477800D03*
X1497275Y470586D03*
Y477346D03*
X1489475D03*
X1499225Y473966D03*
X1493375Y470586D03*
X1495325Y473966D03*
X1493375Y477346D03*
X1491425Y480726D03*
X1501175Y477346D03*
X1530425Y487486D03*
X1528475Y484106D03*
X1520675D03*
X1524575Y477346D03*
X1512875D03*
X1497275Y484106D03*
X1499225Y487486D03*
X1503125Y473966D03*
X1507025D03*
X1501175Y484106D03*
X1505075D03*
X1503125Y480726D03*
X1505075Y477346D03*
X1508975Y484106D03*
X1507025Y480726D03*
X1510925Y487486D03*
X1512875Y484106D03*
X1493375D03*
X1491425Y487486D03*
X1495325Y480726D03*
Y487486D03*
X1526525Y480726D03*
X1530425D03*
X1524575Y484106D03*
X1522625Y480726D03*
X1516775Y477346D03*
X1472250Y485100D03*
X1470643Y495299D03*
X1482958Y486118D03*
X1485100Y469900D03*
X1487525Y480726D03*
X1478700Y533700D03*
X1500445Y619956D03*
X1523450Y612900D03*
X1519850Y613000D03*
X1487912Y611632D03*
X1484312Y611732D03*
X1549600Y-10800D03*
X1538520Y11911D03*
X1590431Y-6702D03*
X1544882Y-6900D03*
X1592829Y24460D03*
X1589623Y24528D03*
X1543500Y3400D03*
X1540000D03*
X1581947Y-6702D03*
X1545111Y24172D03*
X1580398Y-600D03*
Y5400D03*
X1571500Y-1406D03*
X1556200Y94800D03*
X1579100Y69000D03*
X1577269Y95344D03*
X1535300Y78490D03*
X1590949Y97850D03*
X1583374Y81319D03*
X1574780Y90992D03*
X1587359Y84348D03*
X1545250Y88360D03*
X1546370Y84180D03*
X1592715Y70817D03*
X1575018Y71213D03*
X1556810Y71760D03*
X1541413Y155259D03*
X1541765Y114000D03*
X1541421Y106742D03*
X1580275Y101041D03*
X1553500Y157000D03*
X1552171Y133000D03*
X1563108Y126423D03*
X1582500Y109900D03*
X1577700Y140149D03*
X1567520Y133354D03*
X1549000Y115571D03*
X1549187Y104713D03*
X1589200Y121800D03*
X1589622Y112876D03*
X1557981Y141470D03*
X1541390Y136498D03*
X1573153Y103721D03*
X1576606Y104392D03*
X1588500Y106788D03*
X1588000Y100500D03*
X1542685Y133321D03*
X1574197Y127915D03*
X1531726Y123800D03*
X1576506Y143416D03*
X1572395Y110754D03*
X1558100Y128926D03*
X1554627Y100877D03*
X1558136D03*
X1558100Y138025D03*
Y133526D03*
X1541434Y139871D03*
X1542000Y126246D03*
X1591800Y164900D03*
X1566486Y181270D03*
X1535065Y164300D03*
X1552051Y172053D03*
X1571501Y180031D03*
X1568488Y164058D03*
X1562150Y160700D03*
X1583874Y217746D03*
X1582249Y191716D03*
X1572817Y169910D03*
X1570294Y167384D03*
X1535425Y188016D03*
X1535000Y207200D03*
X1557979Y188844D03*
X1543100Y184128D03*
X1553500Y165400D03*
X1548178Y190880D03*
X1558000Y205100D03*
X1545023Y161675D03*
X1561925Y192675D03*
X1566858Y175192D03*
X1549693Y196707D03*
X1552063Y202031D03*
X1558042Y172448D03*
X1593218Y191776D03*
X1557787Y192236D03*
X1561538Y174649D03*
X1587549Y192000D03*
X1582699Y252646D03*
X1561104Y234255D03*
X1537972Y236000D03*
X1532237Y247801D03*
X1567000Y259560D03*
X1552900Y281700D03*
X1579867Y265445D03*
X1563157Y258164D03*
X1533596Y273504D03*
X1542751Y240477D03*
X1542690Y236050D03*
X1531935Y224160D03*
X1541325Y245090D03*
X1568120Y251710D03*
X1545802Y233529D03*
X1584568Y281339D03*
X1571876Y255800D03*
X1558700Y252000D03*
X1568365Y247761D03*
X1551404Y309376D03*
X1533228Y325000D03*
X1550619Y303087D03*
X1534400Y296029D03*
X1587800Y308200D03*
X1538450Y314300D03*
X1578790Y290920D03*
X1550800Y296200D03*
X1577486Y307621D03*
X1532850Y303950D03*
X1548024Y322145D03*
X1585479Y316610D03*
X1570574Y341776D03*
X1554932Y332171D03*
X1538406Y330157D03*
X1573950Y338050D03*
X1537500Y292800D03*
X1581834Y318591D03*
X1559800Y285300D03*
X1559500Y290300D03*
X1575645Y320664D03*
X1588551Y341410D03*
X1548334Y325497D03*
X1581940Y295820D03*
X1582800Y312100D03*
X1548273Y313227D03*
X1565000Y290500D03*
X1543864Y311399D03*
X1590212Y315425D03*
X1551250Y320303D03*
X1590176Y331844D03*
X1554775Y295328D03*
X1548100Y342200D03*
X1534833Y309798D03*
X1560500Y350000D03*
X1553825Y377514D03*
X1557534Y353400D03*
X1533589Y366361D03*
X1553825Y391034D03*
X1546025D03*
X1532367Y356530D03*
X1581822Y365770D03*
X1569584Y378002D03*
X1563575Y394414D03*
X1557725Y397794D03*
X1571375Y387654D03*
X1569425Y397794D03*
X1550639Y350200D03*
X1563575Y401174D03*
X1569425Y391034D03*
X1553825Y397794D03*
X1542300Y376717D03*
X1546025Y397794D03*
X1551875Y394414D03*
Y387654D03*
X1549950Y404490D03*
X1565525Y384274D03*
X1587684Y362653D03*
X1590154Y354762D03*
X1557725Y377514D03*
X1586500Y354900D03*
X1559675Y401174D03*
X1542125Y397794D03*
X1583208Y404941D03*
X1565525Y391034D03*
X1547975Y394414D03*
X1540175Y387654D03*
Y380894D03*
Y401174D03*
X1542932Y355740D03*
X1547975Y387654D03*
X1571450Y359650D03*
X1536275Y401174D03*
Y387654D03*
X1534325Y384274D03*
X1536275Y380894D03*
X1534325Y397794D03*
X1540175Y394414D03*
X1534325Y391034D03*
X1582600Y389300D03*
X1559675Y387654D03*
Y394414D03*
X1551875Y380894D03*
X1557725Y391034D03*
X1536275Y394414D03*
X1557725Y404554D03*
X1563575Y387654D03*
X1567475Y401174D03*
X1566922Y359681D03*
X1567121Y363217D03*
X1551875Y401174D03*
X1565525Y397794D03*
Y377514D03*
X1559675Y380894D03*
X1571375Y394414D03*
X1532375Y401174D03*
X1563575Y380894D03*
X1546182Y355446D03*
X1534325Y377514D03*
X1542125Y460446D03*
X1538225D03*
X1549925Y467206D03*
X1557725D03*
X1569425Y453686D03*
X1559675Y407934D03*
X1561625Y446926D03*
X1551875Y450306D03*
X1536275Y463826D03*
X1532375D03*
X1534325Y467206D03*
X1538225D03*
X1585560Y421324D03*
X1583773Y436137D03*
X1544075Y463826D03*
X1543850Y451400D03*
X1553825Y411314D03*
X1544150Y409900D03*
X1553825Y440166D03*
Y446926D03*
X1549926Y411312D03*
X1540175Y407934D03*
X1536275D03*
X1532375D03*
X1555775D03*
Y414694D03*
X1565525Y418074D03*
X1561625D03*
Y411314D03*
X1565525D03*
X1561625Y440166D03*
X1557725D03*
X1565525Y424834D03*
X1569425D03*
X1536300Y455200D03*
X1553825Y453686D03*
X1547000Y435650D03*
X1551875Y436786D03*
X1549925Y440166D03*
X1540653Y454588D03*
X1532349Y455200D03*
X1549925Y460446D03*
X1583208Y416752D03*
X1591350Y445300D03*
X1542125Y467206D03*
X1559595Y450631D03*
X1569425Y446926D03*
X1591430Y409440D03*
X1565525Y453686D03*
X1551875Y443546D03*
X1571375Y436786D03*
X1587573Y445300D03*
X1587550Y456550D03*
X1565525Y467206D03*
X1561625D03*
X1567475Y463826D03*
X1569425Y467206D03*
X1553825Y460446D03*
X1567475Y443546D03*
X1571375D03*
X1563575Y450306D03*
X1567475Y436786D03*
X1569425Y440166D03*
X1565525Y460446D03*
X1563575Y463826D03*
X1582300Y446100D03*
X1565525Y446926D03*
X1559675Y457066D03*
X1546025Y460446D03*
X1557725D03*
X1551875Y470586D03*
X1549925Y480726D03*
X1551875Y477346D03*
X1546025Y473966D03*
X1547975Y477346D03*
X1559675Y470586D03*
X1533595Y505530D03*
X1559675Y484106D03*
X1561625Y480726D03*
X1557725Y487486D03*
X1561625D03*
X1567475Y484106D03*
X1563575D03*
X1559675Y477346D03*
X1565525Y487486D03*
X1563575Y477346D03*
X1571375D03*
X1590580Y472370D03*
X1536275Y477346D03*
X1534325Y480726D03*
Y473966D03*
X1538225Y480726D03*
X1532375Y484106D03*
Y477346D03*
X1540175Y470586D03*
X1563575D03*
X1561625Y473966D03*
X1565525D03*
X1567475Y477346D03*
X1584970Y472370D03*
X1542125Y487486D03*
X1540175Y484106D03*
X1546025Y487486D03*
X1551875Y484106D03*
X1538225Y487486D03*
X1542125Y480726D03*
X1544075Y484106D03*
X1547975D03*
X1550990Y586588D03*
X1554358Y587258D03*
X1592934Y592396D03*
X1587610Y579550D03*
X1585155Y538574D03*
X1581730Y537170D03*
X1565389Y585721D03*
X1535565Y591658D03*
X1579900Y606050D03*
X1586700Y620100D03*
X1540477Y620308D03*
X1540700Y613700D03*
X1545407Y598393D03*
X1541384Y601262D03*
X1546075Y618145D03*
X1544050Y615296D03*
X1579680Y610279D03*
X1534968Y597268D03*
X1573500Y619500D03*
X1577000D03*
X1572950Y593950D03*
X1601650Y24160D03*
X1617500Y-14500D03*
X1597800Y24300D03*
X1637482Y21623D03*
X1653100Y11500D03*
X1638550Y7200D03*
X1623900Y4600D03*
X1598602Y3437D03*
X1599000Y61500D03*
X1596050Y75400D03*
X1632006Y94500D03*
X1640900Y66900D03*
X1630826Y88087D03*
X1614997Y84403D03*
X1625075Y80182D03*
X1597867Y93900D03*
X1597987Y79500D03*
X1619000Y38500D03*
X1606579Y86726D03*
X1614169Y95004D03*
X1617347Y94581D03*
X1599500Y75000D03*
X1649900Y78600D03*
X1653000Y77600D03*
X1643500Y80400D03*
X1635337Y73500D03*
X1627489Y74960D03*
X1632020Y97871D03*
X1632000Y73500D03*
X1628788Y97800D03*
X1621100Y69600D03*
X1620900Y81300D03*
X1593241Y134295D03*
X1598300Y116477D03*
X1598449Y120760D03*
X1600000Y104243D03*
X1648000Y100597D03*
X1594452Y111377D03*
X1654685Y121790D03*
X1613741Y112341D03*
X1593756Y129048D03*
X1647852Y197374D03*
X1651000Y178628D03*
X1603300Y185100D03*
X1627326Y182759D03*
X1654015Y217239D03*
X1615362Y213507D03*
X1650600Y186300D03*
X1648349Y182276D03*
X1645700Y214050D03*
X1602185Y180709D03*
X1635351Y185444D03*
X1598006Y192421D03*
X1595291Y166423D03*
X1644290Y196383D03*
X1635621Y208259D03*
X1601870Y270470D03*
X1643106Y233913D03*
X1600810Y266006D03*
X1636914Y270900D03*
X1596300Y250320D03*
X1627024Y253387D03*
X1631300Y280400D03*
X1637281Y260922D03*
X1597201Y238188D03*
X1643775Y246137D03*
X1637281Y254322D03*
X1617498Y273433D03*
X1632128Y225472D03*
X1637269Y264421D03*
X1622000Y279495D03*
X1627043Y256900D03*
X1636684Y283141D03*
X1610290Y265352D03*
X1638216Y246021D03*
X1604222Y268107D03*
X1608764Y322440D03*
X1608850Y343835D03*
X1638086Y319664D03*
X1625400Y327667D03*
X1602776Y331304D03*
X1652991Y321341D03*
X1620159Y332004D03*
X1638063Y326504D03*
X1631015Y328350D03*
X1635355Y324228D03*
X1639040Y316343D03*
X1625846Y286154D03*
X1609172Y339630D03*
X1636800Y287956D03*
X1602215Y363981D03*
X1610140Y358350D03*
X1609271Y348166D03*
X1621727Y395374D03*
X1612825Y405438D03*
X1622100Y400600D03*
X1630400Y391800D03*
X1629300Y385400D03*
X1630750Y404800D03*
X1613452Y387098D03*
X1638991Y352037D03*
X1621800Y381500D03*
Y386300D03*
X1595800Y405900D03*
X1639750Y445477D03*
X1630219Y446000D03*
X1621000Y440500D03*
X1621044Y433364D03*
X1621182Y427091D03*
X1603719Y412000D03*
X1611638Y454809D03*
X1612100Y446000D03*
X1646480Y443880D03*
X1611642Y461877D03*
X1630150Y427663D03*
X1593400Y432200D03*
X1639774Y439486D03*
X1623705Y467855D03*
X1639822Y453140D03*
X1647200Y430450D03*
X1640625Y429460D03*
X1621226Y445026D03*
X1615061Y463157D03*
X1596500Y455500D03*
X1617900Y409900D03*
X1595200Y412700D03*
X1651754Y488025D03*
X1626518Y528029D03*
X1627622Y524928D03*
X1631975Y527700D03*
X1597380Y495416D03*
X1600780D03*
X1617300Y519000D03*
X1625485Y494188D03*
X1623551Y525015D03*
X1621783Y498617D03*
X1620030Y525066D03*
X1594280Y472370D03*
X1645969Y514870D03*
X1617700Y475957D03*
X1614000Y475970D03*
X1639271Y491135D03*
X1639391Y513065D03*
X1629778Y507294D03*
X1642670Y514939D03*
X1629500Y491500D03*
X1649336Y511502D03*
X1641470Y506403D03*
X1644651Y505500D03*
X1649545Y515215D03*
X1601540Y588793D03*
X1622330Y592325D03*
X1594110Y611510D03*
X1619700Y617300D03*
X1617600Y619800D03*
X1680033Y-16711D03*
X1666500Y10500D03*
X1680034Y2863D03*
X1697300Y73296D03*
X1689250Y86000D03*
X1692300Y56900D03*
X1658600Y44700D03*
X1667000Y88000D03*
X1693900Y73300D03*
X1708610Y85121D03*
X1713900Y87900D03*
X1696870Y86093D03*
X1711000Y55525D03*
X1712600Y46100D03*
X1707268Y77668D03*
X1669000Y92000D03*
X1709184Y88811D03*
X1678627Y54616D03*
X1684248Y56746D03*
X1690500Y73950D03*
X1715100Y70500D03*
X1659000Y88000D03*
X1661900Y92400D03*
X1704824Y90049D03*
X1664500Y99000D03*
X1672200Y112200D03*
X1696907Y99077D03*
X1664135Y131239D03*
X1657835D03*
Y156436D03*
X1678400Y103000D03*
X1674800Y103100D03*
X1659643Y213505D03*
X1687550Y213751D03*
X1674912Y183000D03*
X1673530Y209974D03*
X1708350Y175050D03*
X1660800Y181900D03*
X1663400Y179475D03*
X1667140Y182300D03*
X1669849Y193067D03*
X1702400Y193450D03*
X1664321Y195244D03*
X1658082Y195298D03*
X1655978Y207827D03*
X1705666Y198055D03*
X1671688Y182925D03*
X1688046Y174447D03*
X1664390Y201163D03*
X1660440Y200789D03*
X1667356Y213096D03*
X1691439Y174354D03*
X1713000Y185000D03*
X1674019Y175990D03*
X1713596Y175795D03*
X1676750Y206050D03*
X1681116Y238614D03*
X1657500Y259700D03*
X1657567Y264600D03*
X1657498Y269700D03*
Y274700D03*
Y279900D03*
X1715837Y246178D03*
X1715078Y250231D03*
X1657494Y292816D03*
X1657498Y284900D03*
X1664453Y308557D03*
X1660972Y401447D03*
X1660834Y404934D03*
X1660890Y397300D03*
X1673074Y453185D03*
X1675120Y439731D03*
X1679145Y461950D03*
X1667588Y434149D03*
X1668100Y418700D03*
X1678303Y442765D03*
X1667946Y412987D03*
X1673550Y442696D03*
X1714530Y519900D03*
X1710594D03*
X1676800Y483800D03*
X1681650Y510673D03*
X1687606Y500938D03*
X1672265Y473600D03*
X1681115Y525218D03*
X1716490Y506970D03*
X1681500Y482000D03*
X1671050Y487000D03*
Y490850D03*
X1672159Y494042D03*
X1655790Y476593D03*
X1705767Y482434D03*
X1698354Y486873D03*
X1701617Y482706D03*
X1680133Y535489D03*
X1710389Y577787D03*
X1699600Y578100D03*
X1710000Y604500D03*
Y600000D03*
X1701291Y602268D03*
X1741544Y9151D03*
X1749085Y9177D03*
X1744900Y9100D03*
X1725474Y69250D03*
X1746328Y59011D03*
X1760016Y65774D03*
X1771707Y86500D03*
X1767250Y94500D03*
Y89500D03*
X1766333Y59116D03*
X1775000Y53500D03*
X1750400Y47400D03*
X1720100Y46100D03*
X1720500Y52440D03*
X1757998Y73637D03*
X1731350Y92140D03*
X1757772Y90174D03*
X1765015Y119100D03*
X1776828Y155211D03*
X1748425Y119190D03*
X1768886Y156173D03*
X1719000Y190500D03*
X1719080Y236152D03*
X1718820Y249032D03*
X1727896Y246175D03*
X1719080Y232852D03*
X1720651Y246141D03*
X1749462Y232955D03*
X1746900Y249804D03*
X1751900Y249700D03*
X1722251Y250532D03*
X1724181Y246159D03*
X1730996Y442804D03*
X1737150Y450850D03*
X1719089Y472104D03*
X1728700Y470200D03*
X1719560Y501770D03*
X1766100Y521124D03*
X1722347Y471811D03*
X1750800Y516100D03*
X1762715Y521085D03*
X1753807Y548183D03*
X1757478Y548192D03*
X1767529Y566200D03*
X1764300Y570900D03*
X1742200Y552863D03*
X1724899Y584748D03*
X1733000Y557000D03*
X1767141Y555500D03*
X1756578Y586743D03*
X1724250Y588250D03*
X1743000Y574500D03*
X1730759Y548162D03*
X1722500Y562000D03*
X1754897Y578750D03*
X1742381Y588530D03*
X1767500Y559800D03*
X1738498Y554255D03*
X1750399Y603201D03*
X1739714Y604967D03*
X1716950Y603450D03*
X1735000Y621002D03*
X1764823Y613600D03*
X1725133Y614896D03*
X1766400Y599400D03*
X1770600Y600800D03*
X1764912Y618718D03*
X1728341Y614851D03*
X1819800Y2100D03*
X1813913Y2287D03*
X1799462Y8830D03*
X1804462D03*
X1790078Y11860D03*
X1795078Y11900D03*
X1792700Y36871D03*
X1797700Y36804D03*
X1831000Y-16300D03*
X1828874Y-13520D03*
X1815150Y26650D03*
X1779750Y36530D03*
X1791500Y26918D03*
X1808100Y21800D03*
X1813795Y12165D03*
X1819837Y21700D03*
X1786865Y22375D03*
X1823600Y8800D03*
X1797700Y21018D03*
X1837500Y35700D03*
X1838850Y13160D03*
X1836700Y-18900D03*
X1804800Y-1500D03*
X1816723Y9781D03*
X1826414Y35486D03*
X1835600Y3900D03*
X1824240Y83680D03*
X1802119Y56581D03*
X1799438Y44328D03*
X1827000Y94550D03*
X1827150Y97800D03*
X1827100Y81600D03*
X1798454Y82256D03*
X1788216Y59197D03*
X1821350Y98270D03*
X1803300Y39900D03*
X1808363Y40033D03*
X1812352Y36949D03*
X1838500Y40400D03*
X1820457Y39128D03*
X1829580Y38620D03*
X1810100Y114700D03*
X1808226Y136171D03*
X1803509Y128500D03*
X1807818Y124179D03*
X1813118Y127976D03*
X1815026Y121478D03*
X1788000Y129000D03*
X1815883Y133277D03*
X1808313Y111705D03*
X1807509Y128500D03*
X1814900Y116900D03*
X1783252Y109044D03*
X1796500Y120000D03*
X1815348Y143437D03*
X1803058Y143733D03*
X1830316Y102163D03*
X1827500Y144900D03*
X1837090Y149830D03*
X1839667Y151994D03*
X1809810Y155858D03*
X1800792Y122691D03*
X1824990Y103620D03*
X1787373Y120188D03*
X1816418Y127976D03*
X1807166Y147401D03*
X1800420Y148240D03*
X1821261Y170012D03*
X1824200Y176900D03*
X1830415Y196567D03*
X1785500Y164000D03*
X1836100Y179700D03*
X1836900Y165800D03*
X1787000Y175500D03*
X1778900Y165800D03*
X1834103Y176021D03*
X1833629Y170807D03*
X1836932Y170486D03*
X1816125Y169492D03*
X1834400Y216900D03*
X1785500Y168000D03*
X1822877Y235852D03*
X1826085Y236034D03*
X1822638Y232106D03*
X1826662Y232191D03*
X1784440Y232938D03*
X1804388Y249904D03*
X1831700Y252272D03*
X1837857Y468630D03*
X1834100Y523900D03*
X1814852Y519901D03*
X1810350Y525650D03*
X1809700Y506875D03*
X1820400Y501100D03*
X1837200Y525700D03*
X1813500Y526500D03*
X1816584Y530542D03*
X1810200Y513300D03*
X1837300Y472276D03*
X1825900Y523500D03*
X1815200Y501500D03*
X1794100Y521900D03*
X1798250Y529200D03*
X1803900Y491500D03*
X1795200Y525700D03*
X1836600Y521600D03*
X1831600Y529000D03*
X1833700Y497300D03*
X1781300Y537800D03*
X1837475Y573835D03*
X1829051Y591299D03*
X1809600Y582800D03*
X1793660Y560570D03*
X1811100Y586800D03*
X1816458Y587480D03*
X1829300Y572900D03*
X1793100Y578500D03*
X1816020Y571448D03*
X1812802Y578693D03*
X1780394Y561076D03*
X1837534Y579322D03*
X1792805Y574675D03*
X1832500Y539500D03*
X1829000Y536315D03*
X1832200Y567760D03*
X1791349Y589122D03*
X1788300Y585100D03*
X1810863Y560637D03*
X1816175Y567669D03*
X1838224Y586650D03*
X1783700Y576400D03*
X1785050Y584550D03*
X1792100Y566900D03*
X1816330Y545260D03*
X1816100Y576200D03*
X1829176Y584287D03*
X1809309Y555713D03*
X1839126Y583354D03*
X1831500Y544500D03*
Y548000D03*
X1831800Y552300D03*
X1837000Y534900D03*
X1782300Y555900D03*
X1778675Y592224D03*
X1794500Y612500D03*
X1791500Y606500D03*
X1782700Y610900D03*
X1795000Y599600D03*
X1791323Y594030D03*
X1805000Y606500D03*
X1788290Y612006D03*
X1787500Y600500D03*
X1784200Y593924D03*
X1900256Y-14760D03*
X1841060Y35540D03*
X1882999Y7383D03*
X1883041Y15814D03*
X1893094Y-12642D03*
X1876792Y18461D03*
X1876881Y22181D03*
X1878000Y73950D03*
X1843107Y97988D03*
X1848208Y49427D03*
X1889218Y51030D03*
Y46030D03*
Y61030D03*
Y56030D03*
X1842250Y84000D03*
Y90750D03*
X1858600Y74300D03*
X1849426Y90700D03*
Y95500D03*
X1883200Y76600D03*
X1850600Y41348D03*
X1875600Y156300D03*
X1857110Y113600D03*
X1881324Y153250D03*
X1890974Y105600D03*
X1898102Y107325D03*
X1885700Y141200D03*
X1897536Y114600D03*
Y120510D03*
X1887497Y105444D03*
X1878753Y139893D03*
X1867280Y135406D03*
X1881165Y105561D03*
X1885102Y101134D03*
X1866606Y109967D03*
X1857849Y148079D03*
X1872254Y138618D03*
X1872400Y144619D03*
X1871521Y153593D03*
X1888639Y147042D03*
X1893640D03*
X1894855Y142122D03*
X1899855D03*
X1861932Y146431D03*
X1857919Y156123D03*
X1869668Y146750D03*
X1864904Y114735D03*
X1895060Y136099D03*
X1897507Y124450D03*
X1895673Y151800D03*
X1868843Y207920D03*
X1874236Y213800D03*
X1893238Y208042D03*
X1863650Y189750D03*
X1877880Y203780D03*
X1847200Y202050D03*
X1884340Y217866D03*
X1840900Y179700D03*
X1845700D03*
X1896710Y194380D03*
X1882452Y195888D03*
X1901100Y194200D03*
X1889400Y191200D03*
X1886200Y161000D03*
X1875700Y184800D03*
X1864637Y201861D03*
X1876700Y207600D03*
X1872100Y207900D03*
X1861243Y183100D03*
X1862000Y177500D03*
X1884000Y188100D03*
X1884400Y183700D03*
X1858686Y180377D03*
X1858500Y200100D03*
X1864000Y184900D03*
X1878789Y213663D03*
X1891880Y204370D03*
X1856874Y219443D03*
X1864464Y198466D03*
X1885465Y166285D03*
X1855000Y167100D03*
X1850723Y219250D03*
X1865100Y174600D03*
X1877517Y217988D03*
X1840149Y244425D03*
X1843449D03*
X1885000Y227500D03*
X1899816Y235035D03*
X1844444Y224035D03*
X1854374Y248790D03*
X1854720Y253700D03*
X1846517Y253500D03*
X1850220D03*
X1896529Y235080D03*
X1892274D03*
X1842857Y468630D03*
X1878100Y450200D03*
X1868167Y467855D03*
X1863137Y452710D03*
X1859059Y448076D03*
X1858633Y452803D03*
X1901574Y454422D03*
X1875900Y453600D03*
X1867500Y447900D03*
X1859530Y516430D03*
X1842400Y516800D03*
X1841900Y498800D03*
X1900890Y477200D03*
X1864339Y509560D03*
X1863000Y480000D03*
X1859600Y476200D03*
X1852719Y487575D03*
Y492575D03*
X1876945Y471316D03*
X1877407Y479046D03*
X1857450Y473654D03*
X1855206Y471112D03*
X1847000Y487500D03*
X1860000Y495500D03*
X1842764Y528136D03*
X1869914Y517225D03*
X1866688Y517128D03*
X1870100Y561150D03*
X1844018Y586482D03*
X1868200Y590939D03*
X1858528Y544528D03*
X1875850Y567200D03*
X1840690Y557190D03*
X1878500Y553500D03*
X1858500Y540000D03*
X1852250Y547900D03*
X1858681Y568087D03*
X1879862Y581862D03*
X1896899Y557790D03*
X1900729Y569557D03*
X1864580Y537060D03*
X1878736Y533040D03*
X1868110Y536000D03*
X1845407Y533178D03*
X1900250Y533700D03*
X1856573Y576534D03*
X1895523Y586365D03*
X1857812Y557245D03*
X1866800Y588000D03*
X1869800Y557100D03*
X1878875Y565475D03*
X1847070Y537610D03*
X1882300Y565550D03*
X1885100Y584300D03*
X1848900Y590750D03*
X1845000Y590800D03*
X1873510Y541710D03*
X1875600Y588500D03*
X1840700Y563800D03*
X1854530Y533132D03*
X1896358Y595255D03*
X1916078Y-16368D03*
X1918352Y89300D03*
X1923300Y94300D03*
X1920300Y68300D03*
X1917600Y66000D03*
X1948472Y80362D03*
X1933914Y96040D03*
X1946500Y104974D03*
X1940700Y136300D03*
X1908327Y149353D03*
X1904215Y142812D03*
X1909216D03*
X1943752Y137548D03*
X1947078Y139300D03*
X1963400Y141100D03*
X1921264Y153000D03*
X1937900Y153600D03*
X1923800Y151000D03*
X1927000Y152200D03*
X1934256Y99459D03*
X1934544Y127957D03*
X1929000Y158600D03*
X1926952Y156049D03*
X1952726Y102950D03*
X1914500Y113300D03*
X1940500Y157600D03*
X1932998Y119438D03*
X1923329Y99475D03*
X1947000Y142600D03*
X1923837Y118800D03*
X1937728Y99441D03*
X1925358Y140685D03*
X1903150Y217250D03*
X1910123Y217349D03*
X1957334Y201269D03*
X1939300Y204300D03*
X1917024Y193600D03*
X1929700Y163400D03*
X1921500Y193600D03*
X1940240Y169970D03*
X1939550Y165600D03*
X1931483Y199350D03*
X1940647Y161600D03*
X1909421Y208805D03*
X1909438Y204307D03*
X1904042Y204895D03*
X1903917Y201472D03*
X1925400Y196300D03*
X1929090Y193190D03*
X1939400Y198400D03*
X1934100Y193400D03*
X1935600Y176300D03*
X1932837Y186700D03*
X1925000Y192000D03*
X1918489Y212513D03*
X1943500Y209500D03*
X1930500Y209464D03*
X1918143Y219848D03*
X1927064Y207564D03*
X1938400Y178200D03*
X1939200Y194300D03*
X1935600Y198700D03*
X1950981Y191218D03*
X1963300Y191000D03*
X1952717Y198614D03*
X1943217Y221154D03*
Y217645D03*
X1942000Y440500D03*
X1937430Y464785D03*
X1904724Y447930D03*
X1939845Y445055D03*
X1947550Y485350D03*
X1956500Y507470D03*
X1938300Y486250D03*
X1957250Y512050D03*
X1937300Y508900D03*
X1919230Y483430D03*
X1919000Y487210D03*
X1919510Y475100D03*
Y479200D03*
X1939000Y476600D03*
X1956606Y526671D03*
X1957212Y479521D03*
X1957063Y474769D03*
X1945000Y474000D03*
X1948200Y474300D03*
X1928620Y482710D03*
X1956300Y515900D03*
X1959300Y518000D03*
X1908300Y514500D03*
X1942328Y508712D03*
X1963000Y573000D03*
X1921244Y533750D03*
X1951900Y534900D03*
X1963097Y551000D03*
X1934200Y573700D03*
X1935400Y583000D03*
X1940800Y537300D03*
X1945900Y549900D03*
X1923500Y579500D03*
X1948100Y538700D03*
X1923400Y583000D03*
X1923600Y575500D03*
X1926600Y559500D03*
X1923600Y565100D03*
X1923000Y568700D03*
X1959120Y547050D03*
X1958940Y538890D03*
X1961715Y555639D03*
X1918880Y586460D03*
X1961771Y591744D03*
X1962950Y566600D03*
X1956191Y548700D03*
X1962500Y578500D03*
X1958500Y535000D03*
X1907500Y545600D03*
X1907200Y551600D03*
X1932390Y590100D03*
X1959400Y601100D03*
X1934350Y609250D03*
X1923504Y592500D03*
X1911750Y592800D03*
X1927000Y614500D03*
X1914700Y594600D03*
X1963300Y612800D03*
X1938130Y601480D03*
X1967580Y104721D03*
X1972598Y165236D03*
X1967200Y521600D03*
X1964270Y511410D03*
X1968375Y509375D03*
X1972700Y576400D03*
Y549950D03*
X1964890Y534940D03*
X1965400Y619500D03*
X1456000Y360700D03*
X1460400Y353000D03*
X1459111Y356353D03*
X1467597Y363000D03*
X1463870Y367869D03*
X1453900Y353350D03*
X1453251Y356676D03*
X1552500Y358500D03*
X1550417Y362607D03*
X352357Y359260D03*
X345598D03*
X355737Y376809D03*
Y388509D03*
X348978Y376809D03*
X342218Y388509D03*
Y376809D03*
X345598Y390460D03*
X352357Y386560D03*
X342218Y384609D03*
X341892Y396301D03*
X345598Y386560D03*
X348978Y388509D03*
X342218Y380709D03*
X351192Y402800D03*
X345598Y378760D03*
X348978Y380709D03*
X345598Y367060D03*
X348978Y372909D03*
X342218D03*
X352357Y378760D03*
Y374860D03*
X359117Y386560D03*
X355737Y380709D03*
X359117Y374860D03*
X355737Y372909D03*
X348978Y369010D03*
X352357Y367060D03*
X355737Y384609D03*
X345598Y355360D03*
X348978Y357309D03*
X345598Y351460D03*
X348978Y361209D03*
X345598Y363160D03*
X342218Y369010D03*
X352357Y351460D03*
Y363160D03*
X359117D03*
X355737Y361209D03*
Y369010D03*
X352357Y355360D03*
X355737Y357309D03*
X359117Y351460D03*
X348978Y384609D03*
X345598Y374860D03*
X324187Y499793D03*
X321061Y518157D03*
X327754Y512792D03*
X324407Y515364D03*
Y509999D03*
X326922Y497170D03*
X314368Y518057D03*
X311021Y510114D03*
X334447Y512792D03*
X331100Y515364D03*
X354526Y518157D03*
X354307Y512792D03*
X351179Y515364D03*
X347833Y512792D03*
X344486Y510114D03*
Y515364D03*
X337793Y509999D03*
X341140Y518157D03*
X334447D03*
X317714Y510114D03*
X321334Y533100D03*
X321123Y552000D03*
X321334Y570900D03*
X321192Y589800D03*
X334292Y533100D03*
Y552000D03*
Y570900D03*
Y589800D03*
X321061Y555857D03*
X327754Y547914D03*
X324407Y555857D03*
Y547914D03*
X314368Y555857D03*
X311021Y547914D03*
X334446D03*
X331100Y555857D03*
X354526D03*
X354525Y547922D03*
X351179Y555857D03*
X347833Y547922D03*
X344486D03*
Y555857D03*
X337793Y547914D03*
X341140Y555857D03*
X334447D03*
X327754Y585714D03*
X324407D03*
X311021D03*
X334446D03*
X354525Y585722D03*
X347833D03*
X344486D03*
X337793Y585714D03*
X317714Y536957D03*
Y547914D03*
Y574757D03*
Y585714D03*
X321061Y593657D03*
Y607292D03*
X324407Y593657D03*
Y609864D03*
X314368Y607292D03*
X311021Y609864D03*
X314368Y593657D03*
X331100D03*
X354526D03*
Y607292D03*
X351179Y593657D03*
X344486Y609864D03*
Y593657D03*
X337793Y609864D03*
X341140Y607292D03*
Y593657D03*
X334447Y607292D03*
Y593657D03*
X317714Y609864D03*
X372637Y359260D03*
X365877D03*
X359117D03*
X376017Y376809D03*
X369257D03*
X382777Y388509D03*
X369257D03*
X362497D03*
X376017D03*
X389537D03*
Y376809D03*
X382777D03*
X362497D03*
X396296Y388509D03*
Y376809D03*
X403056D03*
Y388509D03*
X372637Y390460D03*
X396296Y384609D03*
X372637Y386560D03*
X392916D03*
X389537Y384609D03*
X399676Y390460D03*
X376017Y372909D03*
X369257Y384609D03*
X396296Y380709D03*
X369257Y372909D03*
X362497D03*
X372637Y378760D03*
X362497Y380709D03*
X372637Y374860D03*
X365877D03*
X376017Y380709D03*
X365877Y378760D03*
X382777Y384609D03*
X386157Y374860D03*
X399676Y378760D03*
X396296Y369010D03*
X386157Y386560D03*
X389537Y372909D03*
X403056Y380709D03*
X399676Y374860D03*
X379397Y386560D03*
X369257Y380709D03*
X382777D03*
Y372909D03*
X379397Y378760D03*
Y374860D03*
X392916Y378760D03*
X362497Y384609D03*
X359117Y378760D03*
X386157D03*
X392916Y374860D03*
X389537Y380709D03*
X396296Y372909D03*
X376017Y384609D03*
X379397Y367060D03*
X365877Y355360D03*
X403056Y361209D03*
X369257Y369010D03*
X362497D03*
X369257Y361209D03*
X362497D03*
X372637Y367060D03*
X365877D03*
X372637Y363160D03*
X365877D03*
X382777Y369010D03*
X389537Y361209D03*
X399676Y367060D03*
Y363160D03*
X382777Y361209D03*
X392916Y367060D03*
X403056Y372909D03*
Y369010D03*
X376017Y361209D03*
X369257Y357309D03*
X376017D03*
X386157Y367060D03*
X372637Y355360D03*
X379397Y363160D03*
X359117Y355360D03*
X362497Y357309D03*
X359117Y367060D03*
X386157Y363160D03*
X392916D03*
X389537Y369010D03*
X396296Y361209D03*
X376017Y369010D03*
X365877Y351460D03*
X403056Y396309D03*
X411086Y394359D03*
X399676Y386560D03*
X398546Y402900D03*
X402892Y400400D03*
X385244Y504027D03*
X363760Y529293D03*
X404722Y515364D03*
X401375Y512792D03*
X414761Y518157D03*
X398029Y515364D03*
X404722Y509999D03*
X414761Y512792D03*
X408068Y518157D03*
X394682Y512792D03*
X411415Y510114D03*
X394587Y529026D03*
X376785Y538305D03*
X376892Y577500D03*
X408184Y533100D03*
Y552000D03*
Y589800D03*
Y570900D03*
X404723Y555857D03*
X401376Y547922D03*
X364565Y555842D03*
X361320D03*
X414763Y555857D03*
X398029Y555842D03*
X404723Y547922D03*
X414763D03*
X408069Y555842D03*
X394682Y550592D03*
X401377Y585722D03*
X404723D03*
X414763D03*
X394682Y588392D03*
X376892Y581127D03*
X370596Y585614D03*
X411416Y536957D03*
X411415Y547921D03*
X411416Y574757D03*
Y585722D03*
X394682Y569492D03*
X404723Y593657D03*
X365311Y593642D03*
X364565Y612242D03*
X361964Y593642D03*
X361218Y612242D03*
X414761Y607292D03*
X414763Y593657D03*
X398029Y593642D03*
X404722Y609864D03*
X408068Y607292D03*
X408069Y593642D03*
X378600Y606200D03*
X371312Y604709D03*
X411415Y609864D03*
X394682Y607292D03*
X438187Y510114D03*
X435192Y499400D03*
X431494Y515364D03*
X444880D03*
Y510114D03*
X428147Y512792D03*
X421454Y518157D03*
X434840Y512792D03*
X424801Y515364D03*
X438187D03*
X421368Y533100D03*
X434395Y532904D03*
X433508Y552000D03*
X421368D03*
X420634Y589800D03*
X433508Y570900D03*
X421368D03*
X433500Y589800D03*
X421456Y547922D03*
Y585722D03*
X438189Y547922D03*
X431494Y555842D03*
X444880Y555859D03*
Y547922D03*
X428149D03*
X421456Y555857D03*
X434842Y547922D03*
X424801Y555842D03*
X438187Y555859D03*
X438189Y585722D03*
X444880D03*
X428149D03*
X434842D03*
X421454Y612560D03*
X438187Y609864D03*
X444880D03*
X431494Y593642D03*
X444880Y593659D03*
X421454Y607292D03*
X421456Y593657D03*
X424801Y593642D03*
X438187Y593659D03*
X957283Y-1843D03*
Y9300D03*
X957600Y13200D03*
X957700Y32100D03*
X970800Y13200D03*
X970942Y32100D03*
X957283Y35957D03*
X957765Y-7180D03*
X957283Y17057D03*
X970669Y-7108D03*
Y17057D03*
X974015D03*
Y9114D03*
Y-4536D03*
X963976Y-7108D03*
X960629Y-4536D03*
X963976Y17057D03*
X960629Y9114D03*
X967322Y35957D03*
Y-4536D03*
Y9114D03*
X957558Y50729D03*
X970800Y50860D03*
X970942Y69900D03*
X957774Y87394D03*
X957200Y73800D03*
X957283Y54857D03*
Y92657D03*
X970669Y92757D03*
X974015Y89964D03*
Y84599D03*
X963976Y92657D03*
X960629Y84714D03*
X970669Y54857D03*
X974015D03*
Y46914D03*
X963976Y54857D03*
X960629Y46914D03*
X967322Y73757D03*
Y84714D03*
Y46914D03*
X983900Y13200D03*
Y32100D03*
X1026700Y1700D03*
X977362Y9114D03*
X1014173D03*
X1010826D03*
X984054D03*
X980708Y17057D03*
X1004134Y-7108D03*
Y17057D03*
X1004133Y9122D03*
X1000787Y17057D03*
X997441Y9122D03*
X994094Y-4536D03*
Y9122D03*
Y17057D03*
X987401Y9114D03*
Y-4536D03*
X990748Y-7108D03*
Y17057D03*
X984055Y-7108D03*
Y17057D03*
X1020866Y-1858D03*
X1027202Y-11005D03*
X983900Y51000D03*
Y69900D03*
X1014350Y73000D03*
X1030400Y56500D03*
X1031600Y42900D03*
X977362Y87392D03*
X984055D03*
X980708Y89964D03*
X1004023Y92757D03*
Y87392D03*
X1000787Y89964D03*
X997441Y87392D03*
X994094Y84714D03*
Y89964D03*
X987401Y84599D03*
X990748Y92757D03*
X984055D03*
X977362Y46914D03*
X1014173Y54842D03*
X1010826D03*
X984054Y46914D03*
X980708Y54857D03*
X1004134D03*
X1004133Y46922D03*
X1000787Y54857D03*
X997441Y46922D03*
X994094D03*
Y54857D03*
X987401Y46914D03*
X990748Y54857D03*
X984055D03*
X1020650Y46900D03*
X1030300Y63200D03*
X1035900Y98800D03*
X998586Y209109D03*
Y220809D03*
X991826D03*
X1005345Y209109D03*
Y220809D03*
X1001965Y211060D03*
X1025625Y209109D03*
Y220809D03*
X1012105D03*
Y209109D03*
X1018865Y220809D03*
X1032385D03*
Y209109D03*
X1022245Y207159D03*
X991826Y205210D03*
X1022245Y211060D03*
X995206Y207159D03*
X991826Y209109D03*
X998586Y205210D03*
X1018865Y213009D03*
X998586Y216909D03*
X1001965Y218860D03*
X995206D03*
X991826Y213009D03*
X988446Y214960D03*
X1025625Y216909D03*
X1015485Y218860D03*
X1022245D03*
X1012105Y216909D03*
X1032385Y213009D03*
X1035765Y211060D03*
X1029005Y207159D03*
X1018865Y216909D03*
X1032385D03*
X1029005Y218860D03*
X1008725Y211060D03*
X1012105Y213009D03*
X1008725Y218860D03*
X1005345Y216909D03*
Y213009D03*
X1035765Y218860D03*
X1025625Y213009D03*
X991826Y216909D03*
X995206Y211060D03*
X998586Y213009D03*
X995206Y238360D03*
X1029005D03*
X1008725D03*
X1001965D03*
X1035765D03*
X1015485D03*
X1022245D03*
X991826Y224709D03*
X995206Y230559D03*
X1025625Y224709D03*
X988446Y222760D03*
X1022245D03*
X1015485D03*
X1018865Y224709D03*
X1012105D03*
X1035765Y222760D03*
X1001965D03*
X998586Y224709D03*
X1032385D03*
X1029005Y222760D03*
X1008725D03*
X1005345Y224709D03*
X998586Y228610D03*
X1001965Y230559D03*
X998586Y236409D03*
Y240309D03*
X1029005Y230559D03*
X1015485Y242260D03*
X1001965Y234460D03*
X995206Y242260D03*
Y234460D03*
X991826Y240309D03*
Y228610D03*
Y236409D03*
X1022245Y234460D03*
X1015485D03*
X1022245Y230559D03*
X1015485D03*
X1018865Y236409D03*
X1012105D03*
X1018865Y228610D03*
X1012105D03*
X1032385D03*
Y236409D03*
X1025625D03*
X1018865Y240309D03*
X1025625D03*
X1035765Y230559D03*
X1022245Y242260D03*
X1029005Y234460D03*
X1008725Y242260D03*
X1012105Y240309D03*
X1008725Y230559D03*
Y234460D03*
X1005345Y228610D03*
Y236409D03*
X1001965Y242260D03*
X1005345Y240309D03*
X1035765Y234460D03*
X1025625Y228610D03*
X995206Y222760D03*
X1032385Y240309D03*
X1035765Y242260D03*
X1029005D03*
X1043800Y-9700D03*
X1057792Y13200D03*
Y32100D03*
X1083116Y13200D03*
Y32100D03*
X1070976Y13200D03*
Y32100D03*
X1071062Y-1817D03*
X1071064Y9122D03*
X1054331Y17057D03*
X1050985Y9122D03*
X1087797D03*
X1087795Y-4536D03*
X1064369Y-7108D03*
X1094488Y-4536D03*
X1064371Y17057D03*
X1081102Y17042D03*
X1094488Y17059D03*
Y9122D03*
X1054331D03*
X1054330Y-4536D03*
X1077757Y9122D03*
X1064371D03*
X1071062Y-7108D03*
X1071064Y17057D03*
X1057677Y17042D03*
X1057676Y-7108D03*
X1084450Y9122D03*
X1074409Y17042D03*
X1087795Y17059D03*
X1044290Y11792D03*
X1044291Y-2200D03*
X1061024Y35957D03*
X1061023Y-4536D03*
X1061024Y9122D03*
X1057792Y51000D03*
Y69900D03*
X1083116Y51000D03*
X1070976D03*
X1083116Y69900D03*
X1070976D03*
X1044100Y54700D03*
X1071064Y46922D03*
Y73757D03*
X1054330Y89964D03*
X1050983Y87392D03*
X1087795Y84714D03*
X1064369Y92757D03*
X1081102Y89964D03*
X1094488D03*
Y84714D03*
X1047637Y89964D03*
X1054330Y84599D03*
X1077755Y87392D03*
X1064369D03*
X1071062Y92757D03*
X1057676D03*
X1084448Y87392D03*
X1074409Y89964D03*
X1087795D03*
X1044290Y87392D03*
X1054331Y54857D03*
X1050985Y46922D03*
X1087797D03*
X1064371Y54857D03*
X1081102Y54842D03*
X1094488Y54859D03*
Y46922D03*
X1047637Y54842D03*
X1054331Y46922D03*
X1077757D03*
X1064371D03*
X1071064Y54857D03*
X1057677Y54842D03*
X1084450Y46922D03*
X1074409Y54842D03*
X1087795Y54859D03*
X1044290Y49592D03*
X1061024Y73757D03*
X1061023Y84714D03*
X1061024Y46922D03*
X1044290Y68964D03*
X1050983Y103116D03*
X1064427D03*
X1077304Y103100D03*
X1057734Y103116D03*
X1071120D03*
X1045904Y220809D03*
X1057314D03*
Y209109D03*
X1045904D03*
X1039145D03*
Y220809D03*
X1049284Y207159D03*
X1042524Y211060D03*
X1039145Y213009D03*
X1045904D03*
Y216909D03*
X1049284Y218860D03*
X1057314Y216909D03*
X1042524Y218860D03*
X1039145Y216909D03*
X1049284Y211060D03*
X1042524Y238360D03*
X1045904Y240309D03*
Y228610D03*
X1039145Y224709D03*
X1049284Y222760D03*
X1042524D03*
X1045904Y224709D03*
X1057314Y236409D03*
X1039145D03*
X1049284Y230559D03*
Y234460D03*
X1042524Y230559D03*
X1057314Y224709D03*
Y228610D03*
X1049284Y238360D03*
X1042524Y234460D03*
X1039145Y228610D03*
X1045904Y236409D03*
X1049284Y242260D03*
X1039145Y240309D03*
X1042524Y242260D03*
X973795Y499793D03*
X970669Y518157D03*
X974015Y515364D03*
Y509999D03*
X963976Y518057D03*
X960629Y510114D03*
X967322D03*
X970942Y533100D03*
X970731Y552000D03*
X970942Y570900D03*
X970731Y589800D03*
X970669Y555857D03*
X974015D03*
Y547914D03*
X963976Y555857D03*
X960629Y547914D03*
X974015Y585714D03*
X960629D03*
X967322Y536957D03*
Y574757D03*
Y547914D03*
Y585714D03*
X957765Y607220D03*
X970669Y593657D03*
Y607292D03*
X974015Y593657D03*
Y609864D03*
X963976Y607292D03*
X960629Y609864D03*
X963976Y593657D03*
X967322Y609864D03*
X995206Y359260D03*
X998586Y376809D03*
X991826Y388509D03*
X995206Y390460D03*
X991826Y376809D03*
X1001965Y359260D03*
X1008725D03*
X1015485D03*
X1022245D03*
X1032385Y388509D03*
Y376809D03*
X1005345D03*
Y388509D03*
X1001965Y386560D03*
X1025625Y376809D03*
Y388509D03*
X1018865Y376809D03*
X1012105D03*
X1018865Y388509D03*
X1012105D03*
X991826Y384609D03*
X991500Y396301D03*
X1022245Y390460D03*
X995206Y386560D03*
X1022245D03*
X998586Y388509D03*
X991826Y380709D03*
X1000800Y402800D03*
X995206Y378760D03*
X998586Y380709D03*
X1025625Y372909D03*
X1018865Y384609D03*
X995206Y367060D03*
X998586Y372909D03*
X991826D03*
X1018865D03*
X1012105D03*
X1022245Y378760D03*
X1012105Y380709D03*
X1022245Y374860D03*
X1015485D03*
X1025625Y380709D03*
X1015485Y378760D03*
X1032385Y384609D03*
X1035765Y374860D03*
Y386560D03*
X1029005D03*
X1018865Y380709D03*
X1001965Y378760D03*
Y374860D03*
X1032385Y380709D03*
Y372909D03*
X1029005Y378760D03*
Y374860D03*
X1008725Y386560D03*
X1012105Y384609D03*
X1008725Y378760D03*
X1005345Y380709D03*
X1008725Y374860D03*
X1005345Y372909D03*
X998586Y369010D03*
X1001965Y367060D03*
X1005345Y384609D03*
X1035765Y378760D03*
X1025625Y384609D03*
X995206Y355360D03*
X998586Y357309D03*
X1029005Y367060D03*
X1015485Y355360D03*
X995206Y351460D03*
X998586Y361209D03*
X995206Y363160D03*
X991826Y357309D03*
Y369010D03*
Y361209D03*
X1018865Y369010D03*
X1012105D03*
X1018865Y361209D03*
X1012105D03*
X1022245Y367060D03*
X1015485D03*
X1022245Y363160D03*
X1015485D03*
X1032385Y369010D03*
Y361209D03*
X1025625D03*
X1018865Y357309D03*
X1001965Y351460D03*
Y363160D03*
X1025625Y357309D03*
X1035765Y367060D03*
X1022245Y355360D03*
X1029005Y363160D03*
X1008725Y355360D03*
X1012105Y357309D03*
X1008725Y363160D03*
Y367060D03*
X1005345Y361209D03*
Y369010D03*
X1001965Y355360D03*
X1005345Y357309D03*
X1008725Y351460D03*
X1035765Y363160D03*
X1025625Y369010D03*
X998586Y384609D03*
X995206Y374860D03*
X1015485Y351460D03*
X1034200Y506956D03*
X1035750Y503006D03*
X977362Y512792D03*
X976530Y497170D03*
X984055Y512792D03*
X980708Y515364D03*
X1004134Y518157D03*
X1003915Y512792D03*
X1000787Y515364D03*
X997441Y512792D03*
X994094Y510114D03*
Y515364D03*
X987401Y509999D03*
X990748Y518157D03*
X984055D03*
X983900Y533100D03*
Y552000D03*
Y570900D03*
Y589800D03*
X1026500Y577500D03*
X977362Y547914D03*
X1014173Y555842D03*
X1010928D03*
X984054Y547914D03*
X980708Y555857D03*
X1004134D03*
X1004133Y547922D03*
X1000787Y555857D03*
X997441Y547922D03*
X994094D03*
Y555857D03*
X987401Y547914D03*
X990748Y555857D03*
X984055D03*
X977362Y585714D03*
X984054D03*
X1004133Y585722D03*
X997441D03*
X994094D03*
X987401Y585714D03*
X1026500Y581000D03*
X1019800Y555800D03*
X1014919Y593642D03*
X1014173Y612242D03*
X1011572Y593642D03*
X1010826Y612242D03*
X980708Y593657D03*
X1004134D03*
Y607292D03*
X1000787Y593657D03*
X994094Y609864D03*
Y593657D03*
X987401Y609864D03*
X990748Y593657D03*
Y607292D03*
X984055D03*
Y593657D03*
X1020700Y604600D03*
X1029777Y613581D03*
X1039145Y388509D03*
X1045904D03*
X1052664D03*
X1039145Y376809D03*
X1045904D03*
X1052664D03*
X1045904Y384609D03*
X1042524Y386560D03*
X1039145Y384609D03*
X1049284Y390460D03*
X1045904Y380709D03*
X1049284Y378760D03*
X1045904Y369010D03*
X1039145Y372909D03*
X1052664Y380709D03*
X1049284Y374860D03*
X1042524Y378760D03*
Y374860D03*
X1039145Y380709D03*
X1045904Y372909D03*
X1052664Y361209D03*
X1039145D03*
X1049284Y367060D03*
Y363160D03*
X1042524Y367060D03*
X1052664Y372909D03*
Y369010D03*
X1042524Y363160D03*
X1039145Y369010D03*
X1045904Y361209D03*
X1052664Y396309D03*
X1060694Y394359D03*
X1049284Y386560D03*
X1048154Y402900D03*
X1052500Y400400D03*
X1054330Y515364D03*
X1050983Y512792D03*
X1087795Y510114D03*
X1084800Y499400D03*
X1064369Y518157D03*
X1081102Y515364D03*
X1094488D03*
Y510114D03*
X1047637Y515364D03*
X1054330Y509999D03*
X1077755Y512792D03*
X1064369D03*
X1071062Y518157D03*
X1057676D03*
X1084448Y512792D03*
X1074409Y515364D03*
X1087795D03*
X1044290Y512792D03*
X1061023Y510114D03*
X1044195Y529026D03*
X1057792Y552000D03*
Y533100D03*
Y570900D03*
Y589800D03*
X1070976Y552000D03*
Y533100D03*
X1084003Y532904D03*
X1083116Y552000D03*
X1070976Y570900D03*
X1070242Y589800D03*
X1083116Y570900D03*
X1083108Y589800D03*
X1071064Y547922D03*
Y585722D03*
X1054331Y555857D03*
X1050984Y547922D03*
X1087797D03*
X1064371Y555857D03*
X1081102Y555842D03*
X1094488Y555859D03*
Y547922D03*
X1047637Y555842D03*
X1054331Y547922D03*
X1077757D03*
X1064371D03*
X1071064Y555857D03*
X1057677Y555842D03*
X1084450Y547922D03*
X1074409Y555842D03*
X1087795Y555859D03*
X1044290Y550592D03*
X1050985Y585722D03*
X1087797D03*
X1094488D03*
X1054331D03*
X1077757D03*
X1064371D03*
X1084450D03*
X1044290Y588392D03*
X1061024Y536957D03*
Y574757D03*
Y547922D03*
Y585722D03*
X1044290Y569492D03*
X1071062Y612560D03*
X1054331Y593657D03*
X1087795Y609864D03*
X1064369Y607292D03*
X1094488Y609864D03*
X1064371Y593657D03*
X1081102Y593642D03*
X1094488Y593659D03*
X1047637Y593642D03*
X1054330Y609864D03*
X1071064Y593657D03*
X1071062Y607292D03*
X1057677Y593642D03*
X1057676Y607292D03*
X1074409Y593642D03*
X1087795Y593659D03*
X1061023Y609864D03*
X1044290Y607292D03*
G54D107*
X1854501Y195587D03*
X1859854Y501441D03*
X1952756Y589960D03*
X1944882Y582086D03*
X1952756D03*
X1944882Y574212D03*
X1952756D03*
X1944882Y566338D03*
X1952756D03*
X1944882Y558464D03*
Y589960D03*
X1952756Y558464D03*
X1944882Y605708D03*
X1952756D03*
X1944882Y597834D03*
X1952756D03*
G54D93*
X1638131Y475946D03*
G54D71*
X-4488Y425472D03*
X99980Y136909D03*
X1472000Y-5000D03*
Y-15000D03*
X1462000Y-5000D03*
Y-15000D03*
X1452000Y-5000D03*
Y-15000D03*
X1442000Y-5000D03*
Y-15000D03*
X1525000D03*
X1515000D03*
X1505000D03*
X1482000D03*
X1492000Y-5000D03*
Y-15000D03*
X1482000Y-5000D03*
X1575000Y-15000D03*
X1565000D03*
X1555000D03*
X1545000D03*
X1535000D03*
X1713503Y-5000D03*
Y-15000D03*
X1703503Y-5000D03*
Y-15000D03*
X1743503D03*
X1733503Y-5000D03*
Y-15000D03*
X1743503Y-5000D03*
X1779504D03*
X1769504D03*
Y-15000D03*
X1809504D03*
X1799504Y-5000D03*
Y-15000D03*
X1789504Y-5000D03*
Y-15000D03*
X1819504Y-5000D03*
Y-15000D03*
X1809504Y-5000D03*
G54D48*
X40500Y-42250D03*
Y-52250D03*
X60500Y-42250D03*
X80500D03*
X100500D03*
X60500Y-52250D03*
X80500D03*
X100500D03*
X120500Y-42250D03*
X140500D03*
X120500Y-52250D03*
X140500D03*
X467246Y-52301D03*
Y-42301D03*
X487246Y-52301D03*
Y-42301D03*
X507246Y-52301D03*
Y-42301D03*
X527246Y-52301D03*
Y-42301D03*
X547246Y-52301D03*
Y-42301D03*
X567246Y-52301D03*
Y-42301D03*
X798984Y-52057D03*
Y-42057D03*
X818984Y-52057D03*
Y-42057D03*
X838984Y-52057D03*
Y-42057D03*
X858984Y-52057D03*
Y-42057D03*
X878984Y-52057D03*
Y-42057D03*
X898984Y-52057D03*
Y-42057D03*
X1135583Y-52285D03*
Y-42285D03*
X1155583Y-52285D03*
Y-42285D03*
X1392258Y-52257D03*
Y-42257D03*
X1412258Y-52257D03*
Y-42257D03*
X1432258Y-52257D03*
Y-42257D03*
X1452258Y-52257D03*
Y-42257D03*
G54D110*
X1922248Y518328D03*
G54D105*
X1724807Y451179D03*
X1851250Y584622D03*
Y576748D03*
Y568874D03*
Y561000D03*
G54D95*
X1674921Y528523D03*
X1773347D03*
Y545059D03*
G54D79*
X638541Y171945D03*
Y454425D03*
X752641Y159945D03*
X1288068Y171945D03*
Y454425D03*
X1402168Y159945D03*
Y442425D03*
G54D68*
X40512Y458744D03*
G54D63*
X-15748Y116969D03*
Y132717D03*
X787D03*
X28740Y124843D03*
Y140591D03*
G54D70*
X30512Y467244D03*
X40512D03*
G54D106*
X1809665Y618663D03*
X1819665D03*
X1829665D03*
G54D75*
X63093Y202300D03*
X72936D03*
X82779D03*
X1914911Y495775D03*
X1934597D03*
X1924754D03*
G54D65*
X-14488Y434094D03*
X-4488D03*
X5512D03*
X15512D03*
X89980Y145531D03*
X99980D03*
X109980D03*
X119980D03*
G54D81*
X1401516Y23976D03*
G54D58*
X1466694Y375787D03*
G54D61*
X1705772Y567874D03*
G54D91*
X1613893Y43277D03*
X1617393D03*
G54D73*
X94683Y31978D03*
Y13078D03*
Y69778D03*
Y50878D03*
Y532955D03*
Y514079D03*
Y570755D03*
Y589679D03*
Y551879D03*
Y608555D03*
X637793Y-5822D03*
Y13078D03*
Y69778D03*
Y50878D03*
Y88678D03*
Y532955D03*
Y514079D03*
Y570755D03*
Y589679D03*
Y551879D03*
Y608555D03*
X744293Y-5822D03*
Y31978D03*
Y13078D03*
Y69778D03*
Y88678D03*
Y50878D03*
Y532955D03*
Y514079D03*
Y570755D03*
Y589679D03*
Y551879D03*
Y608555D03*
X1287403Y-5822D03*
Y31978D03*
Y13078D03*
Y69778D03*
Y88678D03*
Y50878D03*
Y532955D03*
Y514079D03*
Y551879D03*
Y608555D03*
G54D64*
X-7874Y216181D03*
Y325315D03*
G54D53*
X163777Y3233D03*
X133659D03*
X120273D03*
X143699D03*
X163777Y78833D03*
Y41033D03*
X120273Y78833D03*
X133659D03*
X143699D03*
X120273Y41033D03*
X133659D03*
X143699D03*
X163777Y579833D03*
Y542033D03*
X143699Y579833D03*
X133659D03*
X143699Y542033D03*
X133659D03*
Y617633D03*
X143699D03*
X163777D03*
X217321Y3233D03*
X207281D03*
X193895D03*
X187203D03*
X173817Y22923D03*
X177163D03*
Y-14877D03*
X173817D03*
X177163Y3233D03*
X217321Y78833D03*
Y41033D03*
X187203Y78833D03*
X193895D03*
X207281D03*
X193895Y41033D03*
X207281D03*
X187203D03*
X177163D03*
X173817Y60723D03*
X177163D03*
Y78833D03*
Y523923D03*
X173817D03*
X217321Y579833D03*
Y542033D03*
X173817Y561723D03*
X177163D03*
Y579833D03*
X207281D03*
X193895D03*
X187203D03*
X177163Y542033D03*
X207281D03*
X193895D03*
X187203D03*
X217321Y617633D03*
X177163D03*
X207281D03*
X193895D03*
X187203D03*
X177163Y599523D03*
X173817D03*
X280903Y3233D03*
X290943D03*
X247439Y22923D03*
X250785D03*
Y3233D03*
X237399D03*
X260825D03*
X247439Y-14877D03*
X250785D03*
X267517Y3233D03*
X280903Y78833D03*
X290943D03*
Y41033D03*
X280903D03*
X267517Y78833D03*
X237399D03*
X250785D03*
X260825D03*
X250785Y60723D03*
X247439D03*
X250785Y41033D03*
X260825D03*
X237399D03*
X267517D03*
X250785Y523923D03*
X247439D03*
X280903Y579833D03*
X290943D03*
X280903Y542033D03*
X290943D03*
X250785Y579833D03*
X260825D03*
X237399D03*
X250785Y561723D03*
X247439D03*
X267517Y579833D03*
X260825Y542033D03*
X237399D03*
X250785D03*
X267517D03*
X290943Y617633D03*
X280903D03*
X260825D03*
X250785D03*
X237399D03*
X267517D03*
X250785Y599523D03*
X247439D03*
X468305Y22923D03*
X454919Y3233D03*
X468305D03*
X471651D03*
X468305Y-14877D03*
X454919Y78833D03*
X468305D03*
X471651D03*
X468305Y41033D03*
X471651D03*
X468305Y60723D03*
X454919Y41033D03*
X468305Y523923D03*
X471651Y579833D03*
X468305D03*
Y561723D03*
X454919Y579833D03*
Y542033D03*
X468305D03*
X471651D03*
X454919Y617633D03*
X468305D03*
X471651D03*
X468305Y599523D03*
X541927Y22923D03*
X515155Y3233D03*
X541927D03*
X528541D03*
X541927Y-14877D03*
X501769Y22923D03*
X498423Y3233D03*
X485037D03*
X501769Y-14877D03*
X541927Y78833D03*
X528541D03*
X515155D03*
X541927Y41033D03*
X528541D03*
X541927Y60723D03*
X515155Y41033D03*
X485037Y78833D03*
X498423D03*
X485037Y41033D03*
X501769Y60723D03*
X498423Y41033D03*
X541927Y523923D03*
X501769D03*
X541927Y579833D03*
X528541D03*
X541927Y561723D03*
X515155Y579833D03*
X528541Y542033D03*
X541927D03*
X515155D03*
X501769Y561723D03*
X498423Y579833D03*
X485037D03*
X498423Y542033D03*
X485037D03*
X515155Y617633D03*
X528541D03*
X541927D03*
X498423D03*
X485037D03*
X541927Y599523D03*
X501769D03*
X575391Y22923D03*
Y-14877D03*
X588777Y3233D03*
X558659D03*
X572045D03*
X545273D03*
X588777Y78833D03*
X575391Y60723D03*
X588777Y41033D03*
X545273Y78833D03*
X572045D03*
X558659D03*
X572045Y41033D03*
X558659D03*
X545273D03*
X575391Y523923D03*
Y561723D03*
X588777Y579833D03*
Y542033D03*
X545273Y579833D03*
X572045D03*
X558659D03*
X545273Y542033D03*
X572045D03*
X558659D03*
X545273Y617633D03*
X572045D03*
X558659D03*
X588777D03*
X575391Y599523D03*
X783267Y3233D03*
X769881D03*
X783267Y78833D03*
X769881D03*
Y41033D03*
X783267D03*
Y579833D03*
Y542033D03*
Y617633D03*
X826771Y22923D03*
X823425D03*
X826771Y3233D03*
X823425Y-14877D03*
X826771D03*
X836811Y3233D03*
X843503D03*
X813385D03*
X793307D03*
X826771Y78833D03*
X843503D03*
X836811D03*
X843503Y41033D03*
X836811D03*
X826771Y60723D03*
X823425D03*
X826771Y41033D03*
X793307Y78833D03*
X813385D03*
Y41033D03*
X793307D03*
X826771Y523923D03*
X823425D03*
X826771Y579833D03*
X823425Y561723D03*
X826771D03*
X843503Y579833D03*
X836811D03*
X826771Y542033D03*
X843503D03*
X836811D03*
X813385Y579833D03*
X793307D03*
X813385Y542033D03*
X793307D03*
Y617633D03*
X813385D03*
X826771D03*
X843503D03*
X836811D03*
X826771Y599523D03*
X823425D03*
X887007Y3233D03*
X900393D03*
X910433D03*
X897047Y-14877D03*
X900393D03*
X897047Y22923D03*
X900393D03*
X866929Y3233D03*
X856889D03*
X910433Y78833D03*
X887007D03*
X900393D03*
X897047Y60723D03*
X887007Y41033D03*
X900393D03*
X910433D03*
X900393Y60723D03*
X856889Y78833D03*
X866929D03*
Y41033D03*
X856889D03*
X900393Y523923D03*
X897047D03*
X910433Y579833D03*
X887007D03*
X900393D03*
Y561723D03*
X897047D03*
X910433Y542033D03*
X900393D03*
X887007D03*
X866929Y579833D03*
X856889D03*
X866929Y542033D03*
X856889D03*
X910433Y617633D03*
X900393D03*
X887007D03*
X866929D03*
X856889D03*
X897047Y599523D03*
X900393D03*
X940551Y3233D03*
X917125D03*
X930511D03*
X940551Y78833D03*
Y41033D03*
X917125Y78833D03*
X930511D03*
Y41033D03*
X917125D03*
X940551Y579833D03*
Y542033D03*
X917125Y579833D03*
X930511D03*
Y542033D03*
X917125D03*
X930511Y617633D03*
X917125D03*
X940551D03*
X1151377Y22923D03*
X1134645Y3233D03*
X1148031D03*
X1151377Y-14877D03*
X1121259Y3233D03*
X1117913Y22923D03*
Y3233D03*
Y-14877D03*
X1104527Y3233D03*
X1134645Y78833D03*
X1121259D03*
X1148031D03*
Y41033D03*
X1151377Y60723D03*
X1134645Y41033D03*
X1121259D03*
X1104527Y78833D03*
X1117913D03*
Y60723D03*
Y41033D03*
X1104527D03*
X1151377Y523923D03*
X1117913D03*
X1134645Y579833D03*
X1121259D03*
X1148031D03*
X1151377Y561723D03*
X1121259Y542033D03*
X1148031D03*
X1134645D03*
X1117913Y579833D03*
X1104527D03*
X1117913Y561723D03*
X1104527Y542033D03*
X1117913D03*
X1121259Y617633D03*
X1148031D03*
X1134645D03*
X1104527D03*
X1117913D03*
X1151377Y599523D03*
X1117913D03*
X1191535Y22923D03*
X1221653Y3233D03*
X1208267D03*
X1191535D03*
Y-14877D03*
X1194881Y3233D03*
X1164763D03*
X1178149D03*
X1208267Y78833D03*
X1221653D03*
X1191535D03*
X1194881D03*
X1191535Y41033D03*
Y60723D03*
X1194881Y41033D03*
X1221653D03*
X1208267D03*
X1164763Y78833D03*
X1178149D03*
X1164763Y41033D03*
X1178149D03*
X1191535Y523923D03*
Y579833D03*
X1194881D03*
X1191535Y561723D03*
X1208267Y579833D03*
X1221653D03*
X1191535Y542033D03*
X1194881D03*
X1208267D03*
X1221653D03*
X1164763Y579833D03*
X1178149D03*
X1164763Y542033D03*
X1178149D03*
X1164763Y617633D03*
X1178149D03*
X1208267D03*
X1221653D03*
X1191535D03*
X1194881D03*
X1191535Y599523D03*
X1238385Y3233D03*
X1224999Y-14877D03*
Y22923D03*
X1238385Y78833D03*
X1224999Y60723D03*
X1238385Y41033D03*
X1224999Y523923D03*
Y561723D03*
X1238385Y579833D03*
Y542033D03*
Y617633D03*
X1224999Y599523D03*
X324407Y617633D03*
X311021D03*
X337793D03*
X354525Y599523D03*
X334447D03*
X321061D03*
X364565Y523923D03*
Y542033D03*
Y617633D03*
X408069Y599523D03*
X424801Y523923D03*
X438187D03*
Y617633D03*
X421455Y599523D03*
X974015Y3233D03*
X960629D03*
X970669Y-14877D03*
X960629Y78833D03*
X957283Y60723D03*
X1004133Y-14877D03*
X987401Y3233D03*
X984055Y-14877D03*
X1014173Y78833D03*
Y60723D03*
X1087795Y3233D03*
X1044291D03*
Y78833D03*
X974015Y617633D03*
X960629D03*
X970669Y599523D03*
X1014173Y542033D03*
X987401Y617633D03*
X1014173D03*
X1004133Y599523D03*
X984055D03*
X1087795Y523923D03*
X1074409D03*
X1087795Y617633D03*
X1071063Y599523D03*
X1057677D03*
G54D62*
X0Y0D03*
G54D83*
X1448686Y41227D03*
X1445186D03*
X1438936D03*
X1435436D03*
X1429786D03*
X1426286D03*
X1454636D03*
X1458136D03*
X1464086D03*
X1467586D03*
X1491836Y41327D03*
X1486486Y41227D03*
X1495336Y41327D03*
X1482986Y41227D03*
X1477036D03*
X1608348Y41229D03*
X1604848D03*
G54D67*
X18228Y178386D03*
X-1969D03*
X44291D03*
G54D52*
X170470Y3233D03*
X157084D03*
X150392D03*
X137006Y22923D03*
X140352D03*
X137006Y-14877D03*
X140352D03*
X126966Y3233D03*
X140352D03*
X170470Y78833D03*
Y41033D03*
X157084Y78833D03*
X150392D03*
Y41033D03*
X157084D03*
X126966Y78833D03*
X140352D03*
X137006Y60723D03*
X140352D03*
X126966Y41033D03*
X140352D03*
Y523923D03*
X137006D03*
X157084Y579833D03*
X170470D03*
X150392D03*
X157084Y542033D03*
X170470D03*
X150392D03*
X140352Y561723D03*
X137006D03*
X126966Y579833D03*
X140352D03*
Y542033D03*
X126966D03*
Y617633D03*
X140352D03*
X150392D03*
X157084D03*
X170470D03*
X137006Y599523D03*
X140352D03*
X213974Y22923D03*
X210628D03*
X213974Y-14877D03*
Y3233D03*
X224014D03*
X230706D03*
X210628Y-14877D03*
X200588Y3233D03*
X180510D03*
X213974Y78833D03*
X224014D03*
X230706D03*
X213974Y60723D03*
Y41033D03*
X224014D03*
X230706D03*
X210628Y60723D03*
X200588Y78833D03*
Y41033D03*
X180510D03*
Y78833D03*
X213974Y523923D03*
X210628D03*
X213974Y579833D03*
Y561723D03*
X210628D03*
X230706Y579833D03*
X224014D03*
X213974Y542033D03*
X230706D03*
X224014D03*
X200588Y579833D03*
X180510D03*
X200588Y542033D03*
X180510D03*
X213974Y617633D03*
X180510D03*
X200588D03*
X230706D03*
X224014D03*
X210628Y599523D03*
X213974D03*
X287596Y22923D03*
X284250D03*
X274210Y3233D03*
X284250Y-14877D03*
X287596D03*
Y3233D03*
X254132D03*
X244092D03*
X274210Y78833D03*
X287596D03*
Y41033D03*
X274210D03*
X287596Y60723D03*
X284250D03*
X254132Y78833D03*
X244092D03*
X254132Y41033D03*
X244092D03*
X284250Y523923D03*
X287596D03*
X274210Y579833D03*
X287596D03*
Y561723D03*
X284250D03*
X274210Y542033D03*
X287596D03*
X244092Y579833D03*
X254132D03*
Y542033D03*
X244092D03*
X287596Y617633D03*
X274210D03*
X254132D03*
X244092D03*
X284250Y599523D03*
X287596D03*
X297636Y3233D03*
Y78833D03*
Y41033D03*
Y579833D03*
Y542033D03*
Y617633D03*
X464958Y22923D03*
X478344Y3233D03*
X461612D03*
X464958Y-14877D03*
X461612Y78833D03*
X478344D03*
X461612Y41033D03*
X464958Y60723D03*
X478344Y41033D03*
X464958Y523923D03*
X478344Y579833D03*
X464958Y561723D03*
X461612Y579833D03*
X478344Y542033D03*
X461612D03*
Y617633D03*
X478344D03*
X464958Y599523D03*
X538580Y22923D03*
X521848Y3233D03*
X535234D03*
X538580Y-14877D03*
X505116Y22923D03*
X508462Y3233D03*
X505116D03*
X491730D03*
X505116Y-14877D03*
X535234Y78833D03*
X521848D03*
Y41033D03*
X535234D03*
X538580Y60723D03*
X508462Y78833D03*
X505116D03*
X491730D03*
X505116Y60723D03*
Y41033D03*
X491730D03*
X508462D03*
X538580Y523923D03*
X505116D03*
X535234Y579833D03*
X538580Y561723D03*
X521848Y579833D03*
Y542033D03*
X535234D03*
X505116Y561723D03*
X491730Y579833D03*
X505116D03*
X508462D03*
X491730Y542033D03*
X505116D03*
X508462D03*
X521848Y617633D03*
X535234D03*
X505116D03*
X508462D03*
X491730D03*
X538580Y599523D03*
X505116D03*
X578738Y22923D03*
Y-14877D03*
Y3233D03*
X582084D03*
X595470D03*
X565352D03*
X551966D03*
X578738Y78833D03*
X582084D03*
X595470D03*
X578738Y60723D03*
X582084Y41033D03*
X578738D03*
X595470D03*
X565352Y78833D03*
X551966D03*
Y41033D03*
X565352D03*
X578738Y523923D03*
X595470Y579833D03*
X578738D03*
X582084D03*
X578738Y561723D03*
X595470Y542033D03*
X578738D03*
X582084D03*
X565352Y579833D03*
X551966D03*
Y542033D03*
X565352D03*
X551966Y617633D03*
X565352D03*
X595470D03*
X578738D03*
X582084D03*
X578738Y599523D03*
X776574Y3233D03*
X789960Y-14877D03*
X786614D03*
X789960Y3233D03*
Y22923D03*
X786614D03*
X776574Y78833D03*
X789960D03*
Y41033D03*
Y60723D03*
X786614D03*
X776574Y41033D03*
X789960Y523923D03*
X786614D03*
X789960Y579833D03*
Y561723D03*
X786614D03*
X776574Y579833D03*
Y542033D03*
X789960D03*
Y617633D03*
X776574D03*
X786614Y599523D03*
X789960D03*
X820078Y3233D03*
X830118D03*
X850196D03*
X800000D03*
X806692D03*
X850196Y78833D03*
X830118D03*
X820078D03*
X850196Y41033D03*
X830118D03*
X820078D03*
X800000Y78833D03*
X806692D03*
Y41033D03*
X800000D03*
X820078Y579833D03*
X850196D03*
X830118D03*
X820078Y542033D03*
X850196D03*
X830118D03*
X806692Y579833D03*
X800000D03*
X806692Y542033D03*
X800000D03*
X806692Y617633D03*
X800000D03*
X820078D03*
X850196D03*
X830118D03*
X880314Y3233D03*
X893700D03*
X903740D03*
X863582Y22923D03*
X860236D03*
X873622Y3233D03*
X863582D03*
Y-14877D03*
X860236D03*
X903740Y78833D03*
X880314D03*
X893700D03*
X880314Y41033D03*
X903740D03*
X893700D03*
X863582Y78833D03*
X873622D03*
X863582Y41033D03*
Y60723D03*
X860236D03*
X873622Y41033D03*
X860236Y523923D03*
X863582D03*
X903740Y579833D03*
X880314D03*
X893700D03*
X903740Y542033D03*
X893700D03*
X880314D03*
X873622Y579833D03*
X863582D03*
X860236Y561723D03*
X863582D03*
X873622Y542033D03*
X863582D03*
X903740Y617633D03*
X893700D03*
X880314D03*
X873622D03*
X863582D03*
Y599523D03*
X860236D03*
X947244Y3233D03*
X937204Y22923D03*
X923818Y3233D03*
X937204D03*
X933858Y-14877D03*
X937204D03*
X933858Y22923D03*
X947244Y78833D03*
Y41033D03*
X923818Y78833D03*
X937204D03*
X933858Y60723D03*
X937204Y41033D03*
Y60723D03*
X923818Y41033D03*
X937204Y523923D03*
X933858D03*
X947244Y579833D03*
Y542033D03*
X923818Y579833D03*
X933858Y561723D03*
X937204Y579833D03*
Y561723D03*
Y542033D03*
X923818D03*
Y617633D03*
X937204D03*
X947244D03*
X937204Y599523D03*
X933858D03*
X1154724Y22923D03*
X1127952Y3233D03*
X1141338D03*
X1154724D03*
X1158070D03*
X1154724Y-14877D03*
X1114566Y22923D03*
Y-14877D03*
X1111220Y3233D03*
X1154724Y78833D03*
X1158070D03*
X1141338D03*
X1127952D03*
Y41033D03*
X1154724Y60723D03*
X1141338Y41033D03*
X1154724D03*
X1158070D03*
X1111220Y78833D03*
X1114566Y60723D03*
X1111220Y41033D03*
X1154724Y523923D03*
X1114566D03*
X1127952Y579833D03*
X1154724D03*
X1158070D03*
X1154724Y561723D03*
X1141338Y579833D03*
X1158070Y542033D03*
X1154724D03*
X1141338D03*
X1127952D03*
X1111220Y579833D03*
X1114566Y561723D03*
X1111220Y542033D03*
X1154724Y617633D03*
X1158070D03*
X1141338D03*
X1127952D03*
X1111220D03*
X1154724Y599523D03*
X1114566D03*
X1188188Y22923D03*
X1214960Y3233D03*
X1188188Y-14877D03*
X1201574Y3233D03*
X1184842D03*
X1171456D03*
X1214960Y78833D03*
X1201574D03*
X1184842D03*
X1188188Y60723D03*
X1201574Y41033D03*
X1184842D03*
X1214960D03*
X1171456Y78833D03*
Y41033D03*
X1188188Y523923D03*
X1184842Y579833D03*
X1201574D03*
X1188188Y561723D03*
X1214960Y579833D03*
X1184842Y542033D03*
X1201574D03*
X1214960D03*
X1171456Y579833D03*
Y542033D03*
Y617633D03*
X1214960D03*
X1184842D03*
X1201574D03*
X1188188Y599523D03*
X1245078Y3233D03*
X1228346D03*
X1231692D03*
X1228346Y-14877D03*
Y22923D03*
X1245078Y78833D03*
Y41033D03*
X1231692Y78833D03*
X1228346D03*
Y60723D03*
Y41033D03*
X1231692D03*
X1228346Y523923D03*
X1245078Y579833D03*
Y542033D03*
X1228346Y561723D03*
Y579833D03*
X1231692D03*
Y542033D03*
X1228346D03*
Y617633D03*
X1231692D03*
X1245078D03*
X1228346Y599523D03*
X314368Y523923D03*
X344486Y617633D03*
X341140Y599523D03*
X314368D03*
X414762Y523923D03*
X361218D03*
Y542033D03*
Y617633D03*
X404722D03*
X414762Y599523D03*
X431494Y523923D03*
X444880D03*
Y617633D03*
X963976Y-14877D03*
X994094Y3233D03*
X990748Y-14877D03*
X1010826Y78833D03*
Y60723D03*
X1064370Y-14877D03*
X1094488Y3233D03*
X1054330D03*
X1094488Y78833D03*
X963976Y523923D03*
Y599523D03*
X1010826Y523923D03*
Y542033D03*
X994094Y617633D03*
X1010826D03*
X990748Y599523D03*
X1094488Y523923D03*
X1064370D03*
X1081102D03*
X1054330Y617633D03*
X1064370Y599523D03*
G54D51*
X1866923Y235400D03*
G54D47*
X-3937Y-43307D03*
X1956693D03*
X-13780Y598560D03*
X-3937Y646063D03*
X1956693D03*
G54D55*
X1271750Y466204D03*
Y461504D03*
X1264430Y469540D03*
X1310630Y466600D03*
X1310586Y462030D03*
X1492692Y132750D03*
X1489800Y120588D03*
X1492692Y127250D03*
G54D89*
X1560898Y41434D03*
X1557398D03*
X1551748Y41234D03*
X1589448D03*
X1585948D03*
X1579998D03*
X1576498D03*
X1570548D03*
X1567048D03*
X1598898D03*
X1595398D03*
X1911400Y199600D03*
G54D74*
X56450Y95000D03*
Y91500D03*
Y137000D03*
Y133500D03*
Y123000D03*
Y119500D03*
Y109000D03*
Y105500D03*
G54D60*
X1611283Y615236D03*
G54D85*
X1507076Y88665D03*
Y112287D03*
G54D50*
X1955506Y454297D03*
X1699600D03*
Y235400D03*
G54D54*
X133563Y183126D03*
Y419626D03*
X783171Y183126D03*
Y419626D03*
G54D86*
X1507076Y94570D03*
Y100476D03*
Y106382D03*
Y118192D03*
Y124098D03*
Y130004D03*
G54D57*
X1454685Y338189D03*
X1600355Y527165D03*
G54D92*
X1613069Y302692D03*
G54D56*
X1427894Y30669D03*
X1462540Y17283D03*
X1443642D03*
X1434194D03*
X1424744D03*
X1446792Y30669D03*
X1456240D03*
X1465690D03*
X1490886Y17283D03*
X1494036Y30669D03*
X1481438Y17283D03*
X1471988D03*
X1475138Y30669D03*
G54D101*
X1739374Y460603D03*
X1751972D03*
X1764570D03*
X1789768D03*
X1802366D03*
X1814964D03*
X1827562D03*
G54D88*
X1546734Y17268D03*
X1556184D03*
X1565634D03*
X1559334Y30668D03*
X1549884D03*
X1587684D03*
X1578234D03*
X1575084Y17268D03*
X1584534D03*
X1593984D03*
X1568784Y30668D03*
X1612884Y17268D03*
X1622334D03*
X1631784D03*
X1634934Y30668D03*
X1625484D03*
X1616034D03*
X1606584D03*
X1603434Y17268D03*
X1597134Y30668D03*
X1653834D03*
X1650684Y17268D03*
X1641234D03*
X1644384Y30668D03*
X1663284D03*
X1672734D03*
X1682184D03*
X1691634D03*
X1701084D03*
X1710534D03*
X1716834Y17268D03*
X1707384D03*
X1697934D03*
X1688484D03*
X1679034D03*
X1669584D03*
X1660134D03*
X1719984Y30668D03*
X1726284Y17268D03*
X1729434Y30668D03*
X1738884D03*
X1748334D03*
X1776682D03*
X1773532Y17268D03*
X1745184D03*
X1735734D03*
X1786132Y30668D03*
X1782982Y17268D03*
G54D82*
X1453091Y17283D03*
X1437343Y30669D03*
X1484587D03*
G54D77*
X224410Y301378D03*
X326772Y439173D03*
X500000Y163582D03*
Y439173D03*
X602362Y214764D03*
Y387992D03*
X874016Y301378D03*
X1149606Y163582D03*
Y439173D03*
X1251969Y214764D03*
Y387992D03*
G54D59*
X1647050Y363100D03*
G54D103*
X1770870Y441754D03*
X1783468D03*
X1833862D03*
X1821264D03*
X1796066D03*
G54D102*
X1777169Y460603D03*
G54D100*
X1742288Y186937D03*
X1754886D03*
X1767484D03*
X1776968Y244105D03*
X1805280Y186937D03*
X1817878D03*
X1814764Y244105D03*
X1795866D03*
G54D104*
X1758271Y441754D03*
X1745673D03*
X1808665D03*
G54D99*
X1729689Y186937D03*
X1758071Y244105D03*
X1792681Y186937D03*
X1780083D03*
G54D97*
X1773784Y204236D03*
X1748586D03*
X1735988D03*
X1786382D03*
X1798980D03*
G54D98*
X1761185D03*
X1824177D03*
X1811579D03*
%LPD*%
G75*
G36*
G01X39600Y265275D02*
Y199342D01*
X37261Y197003D01*
X13233D01*
X12100Y198136D01*
Y232100D01*
X12098Y232102D01*
Y232723D01*
X9032Y235790D01*
Y264669D01*
X13796Y269435D01*
Y270427D01*
X13900Y270531D01*
Y336948D01*
X16052Y339100D01*
X38700D01*
X39600Y338200D01*
Y274717D01*
G03Y274577I1400J-70D01*
G01Y265420D01*
G03Y265280I1400J-70D01*
G01Y265275D01*
G37*
G36*
G01X44734Y271114D02*
Y286873D01*
G02X45416Y287155I400J-1D01*
G01X46989Y285582D01*
X49224D01*
X49448Y285359D01*
Y282803D01*
X50552Y281698D01*
X58178D01*
X58211Y281686D01*
G03X59189I489J1314D01*
G01X59222Y281698D01*
X66889D01*
X66901Y281511D01*
G03X69311Y280629I1399J89D01*
G02X69889I289J-277D01*
G03X70557Y280241I1011J971D01*
G01X70626Y280172D01*
Y274785D01*
X73614Y271797D01*
G02X73331Y271114I-283J-283D01*
G01X44734D01*
G37*
G36*
G01X77383Y269444D02*
X71627Y275200D01*
Y280401D01*
G03X69907Y282590I-727J1199D01*
G01X69766Y282448D01*
X69514Y282700D01*
X69172D01*
X69119Y282738D01*
G03X67431Y282700I-819J-1138D01*
G01X63424D01*
G02X63025Y283122I0J400D01*
G03X62499Y284297I-1400J79D01*
G02X62560Y284963I249J313D01*
G03X61026Y285104I-660J1237D01*
G02X60965Y284438I-249J-313D01*
G03X60431Y283936I660J-1237D01*
G02X59782Y283892I-340J210D01*
G03X57300Y283078I-1082J-892D01*
G02X56901Y282700I-399J22D01*
G01X50967D01*
X50449Y283218D01*
Y285774D01*
X49639Y286584D01*
X47404D01*
X46071Y287917D01*
Y304471D01*
X50500Y308900D01*
Y334374D01*
X52360Y336234D01*
X52483Y336182D01*
G03X54318Y338017I542J1293D01*
G01X54266Y338140D01*
X54710Y338584D01*
X54900Y338394D01*
X54909Y338326D01*
G03X57590Y337950I1391J174D01*
G02X58289Y338017I368J-157D01*
G03X60840Y338601I1163J783D01*
G01X60864Y338773D01*
X61508D01*
X61549Y338626D01*
G03X64000Y338130I1351J374D01*
G02X64643Y338108I313J-248D01*
G03X67172Y338614I1157J792D01*
G01X67206Y338773D01*
X67588D01*
X67612Y338601D01*
G03X67872Y337967I1388J199D01*
G02X67743Y337379I-322J-238D01*
G03X69546Y336983I675J-1229D01*
G02X69675Y337571I322J238D01*
G03X70167Y338023I-675J1229D01*
G02X70833I333J-222D01*
G03X73105Y337937I1167J777D01*
G02X73727Y337948I315J-246D01*
G03X76181Y338608I1073J902D01*
G01X76210Y338773D01*
X86032D01*
G02X86336Y338113I0J-400D01*
G03X86021Y337451I1064J-912D01*
G02X85554Y337129I-394J71D01*
G03X84085Y336450I-254J-1379D01*
G02X83386Y336461I-346J200D01*
G03X80937Y336504I-1236J-661D01*
G02X80371Y336371I-346J201D01*
G03X80813Y334496I-771J-1171D01*
G02X81379Y334629I346J-201D01*
G03X83365Y335100I771J1171D01*
G02X84064Y335089I346J-200D01*
G03X86679Y335499I1236J661D01*
G02X87146Y335821I394J-71D01*
G03X88464Y338113I254J1379D01*
G02X88768Y338773I304J260D01*
G01X92927D01*
X94419Y337281D01*
G02X94186Y336601I-283J-283D01*
G03X95751Y335036I174J-1391D01*
G02X96431Y335269I397J-50D01*
G01X97500Y334200D01*
Y274263D01*
X92681Y269444D01*
X77383D01*
G37*
G36*
G01X53000Y223300D02*
X51800Y224500D01*
Y258900D01*
X59984Y267084D01*
X72912D01*
X74529Y265467D01*
Y265408D01*
X74988Y264949D01*
Y224634D01*
X73654Y223300D01*
X53000D01*
G37*
G36*
G01X308308Y-19342D02*
X308077Y-19111D01*
G02X308340Y-18428I283J283D01*
G01X308776D01*
Y-11326D01*
X306574D01*
Y-16662D01*
G02X305891Y-16925I-400J20D01*
G01X305758Y-16792D01*
Y-8309D01*
X305766Y-8281D01*
G03Y-7421I-1438J430D01*
G01X305758Y-7393D01*
Y-4158D01*
X305766Y-4130D01*
G03Y-3270I-1438J430D01*
G01X305758Y-3242D01*
Y11625D01*
X305768Y11686D01*
G03X305790Y11769I-1440J426D01*
G01X305805Y11834D01*
X306000Y11997D01*
X306195Y11835D01*
X306210Y11768D01*
G03X306719Y10943I1464J334D01*
G02X306743Y10347I-255J-309D01*
G03X308607I932J-1047D01*
G02X308631Y10943I279J287D01*
G03X309146Y12404I-956J1158D01*
G03X308173Y14590I-1154J796D01*
G03X306591Y13141I-181J-1390D01*
G03X306213Y12445I1084J-1039D01*
G01Y12444D01*
X306197Y12378D01*
X306003Y12217D01*
X305808Y12379D01*
X305793Y12445D01*
G03X305767Y12544I-1465J-332D01*
G01X305758Y12573D01*
Y14356D01*
X305766Y14384D01*
G03Y15244I-1438J430D01*
G01X305758Y15272D01*
Y29491D01*
X305766Y29519D01*
G03Y30379I-1438J430D01*
G01X305758Y30407D01*
Y33642D01*
X305766Y33670D01*
G03Y34530I-1438J430D01*
G01X305758Y34558D01*
Y49456D01*
X305766Y49484D01*
G03Y50344I-1438J430D01*
G01X305758Y50372D01*
Y52156D01*
X305766Y52184D01*
G03Y53044I-1438J430D01*
G01X305758Y53072D01*
Y67291D01*
X305766Y67319D01*
G03Y68179I-1438J430D01*
G01X305758Y68207D01*
Y71442D01*
X305766Y71470D01*
G03Y72330I-1438J430D01*
G01X305758Y72358D01*
Y87256D01*
X305766Y87284D01*
G03Y88144I-1438J430D01*
G01X305758Y88172D01*
Y90138D01*
X305762Y90176D01*
X305763Y90181D01*
G03X305761Y90657I-1485J232D01*
G01X305758Y90673D01*
Y97666D01*
X305817Y97725D01*
Y100825D01*
X320542Y115550D01*
Y123100D01*
X330442Y133000D01*
Y136050D01*
X335792Y141400D01*
Y181650D01*
X337292Y183150D01*
Y190150D01*
X339342Y192200D01*
Y201404D01*
G02X339460Y202002I313J249D01*
G03X340147Y203761I-622J1257D01*
G03X338685Y204652I-1309J-503D01*
G02X338242Y205049I-43J398D01*
G01Y205367D01*
G02X338685Y205764I400J-1D01*
G03Y208552I153J1394D01*
G02X338242Y208949I-43J398D01*
G01Y209267D01*
G02X338685Y209664I400J-1D01*
G03Y212452I153J1394D01*
G02X338242Y212849I-43J398D01*
G01Y213169D01*
G02X338685Y213566I400J-1D01*
G03Y216354I153J1394D01*
G02X338242Y216751I-43J398D01*
G01Y220969D01*
G02X338685Y221366I400J-1D01*
G03Y224154I153J1394D01*
G02X338242Y224551I-43J398D01*
G01Y227900D01*
X340092Y229750D01*
Y229931D01*
X340110Y229971D01*
G03Y231149I-1272J589D01*
G01X340092Y231189D01*
Y233831D01*
X340110Y233871D01*
G03Y235049I-1272J589D01*
G01X340092Y235089D01*
Y237731D01*
X340110Y237771D01*
G03Y238949I-1272J589D01*
G01X340092Y238989D01*
Y241631D01*
X340110Y241671D01*
G03Y242849I-1272J589D01*
G01X340092Y242889D01*
Y245350D01*
X341590Y246848D01*
X341712Y246801D01*
G03X342742Y246808I506J1308D01*
G03X343285Y247200I-525J1300D01*
G01X343914D01*
G02X344287Y246658I-1J-400D01*
G03X346909I1311J-498D01*
G02X347282Y247200I374J142D01*
G01X347911D01*
G03X350045I1067J909D01*
G01X350673D01*
G02X351046Y246658I-1J-400D01*
G03X353668I1311J-498D01*
G02X354041Y247200I374J142D01*
G01X354670D01*
G03X356804I1067J909D01*
G01X357433D01*
G02X357806Y246658I-1J-400D01*
G03X360428I1311J-498D01*
G02X360801Y247200I374J142D01*
G01X361430D01*
G03X363300Y246960I1067J909D01*
G01X363410Y247032D01*
X364489Y245953D01*
X364501Y245893D01*
G03X367055Y245400I1376J267D01*
G01X370942D01*
X372164Y244178D01*
G02X372049Y243533I-283J-282D01*
G03X374014Y242525I588J-1273D01*
G02X374407Y243000I393J75D01*
G01X375305D01*
X375350Y242976D01*
G03X376684I667J1233D01*
G01X376729Y243000D01*
X376892D01*
X378062Y241830D01*
X378077Y241788D01*
G03X378925Y240940I1320J472D01*
G01X378967Y240925D01*
X379461Y240431D01*
G02X379226Y239752I-283J-282D01*
G03X380795Y238469I171J-1392D01*
G02X381193Y238900I399J31D01*
G01X384361D01*
G02X384759Y238469I-1J-400D01*
G03X387555I1398J-109D01*
G02X387953Y238900I399J31D01*
G01X391120D01*
G02X391518Y238469I-1J-400D01*
G03X394314I1398J-109D01*
G02X394712Y238900I399J31D01*
G01X397880D01*
G02X398278Y238469I-1J-400D01*
G03X400495Y237222I1398J-109D01*
G03X399973Y239730I-819J1138D01*
G02X399792Y240400I102J387D01*
G01X400582Y241190D01*
X400588Y241195D01*
G03X400741Y241348I-912J1065D01*
G01X400746Y241354D01*
X401242Y241850D01*
X408242D01*
X412658Y237434D01*
Y197266D01*
X414008Y195916D01*
Y161500D01*
X413292Y160784D01*
Y142100D01*
X414190Y141202D01*
Y132998D01*
X447964Y99224D01*
Y91098D01*
G03Y88702I728J-1198D01*
G01Y86540D01*
G03Y84052I646J-1244D01*
G01Y75689D01*
X448139Y75514D01*
G02X448033Y74872I-283J-283D01*
G03X447199Y73664I566J-1283D01*
G03X447688Y72523I1400J-75D01*
G02X447699Y71926I-260J-303D01*
G03X447562Y70013I952J-1030D01*
G03X447768Y69807I1089J883D01*
G02Y69198I-260J-305D01*
G03X447608Y67128I859J-1108D01*
G03X448519Y66692I1020J961D01*
G02X448888Y66294I-31J-399D01*
G01Y62823D01*
X448525Y62460D01*
X447964D01*
Y55996D01*
G03Y53770I1009J-1113D01*
G01Y52305D01*
X447855Y52249D01*
G03X447329Y51783I637J-1249D01*
G03Y50217I1163J-783D01*
G03X447855Y49751I1163J783D01*
G01X447964Y49695D01*
Y48377D01*
X447852Y48322D01*
G03Y45628I665J-1347D01*
G01X447964Y45573D01*
Y37506D01*
X447803Y37474D01*
G03X446748Y36670I289J-1474D01*
G02X446167Y36517I-358J179D01*
G03X445671Y37116I-1285J-560D01*
G01X445583Y37176D01*
Y37482D01*
X445982D01*
Y44584D01*
X443778D01*
Y37482D01*
X444181D01*
Y37176D01*
X444093Y37116D01*
G03X446182Y35432I789J-1159D01*
G02X446766Y35294I231J-326D01*
G03X447714Y34546I1326J706D01*
G03X447767Y34517I699J1215D01*
G03X447845Y34480I640J1248D01*
G01X447964Y34427D01*
Y33271D01*
X447830Y33224D01*
G03X446906Y31686I462J-1324D01*
G03X447024Y31302I1386J216D01*
G03X447154Y29347I1202J-902D01*
G01X447180Y29320D01*
X447241Y29177D01*
X447190Y29045D01*
X447167Y29019D01*
G03X447856Y26748I1059J-919D01*
G01X447964Y26715D01*
Y18181D01*
G03Y15819I928J-1181D01*
G01Y15071D01*
X447830Y15024D01*
G03X446924Y13395I462J-1324D01*
G03X447248Y12764I1369J304D01*
G02X447213Y12210I-305J-259D01*
G03X447818Y9654I1013J-1110D01*
G01X447964Y9613D01*
Y-356D01*
X447970Y-362D01*
Y-5110D01*
X448375Y-5515D01*
Y-5837D01*
X448147D01*
X448121Y-5830D01*
G03X447329Y-5841I-377J-1350D01*
G03X447048Y-8397I414J-1339D01*
G03X447939Y-8568I696J1217D01*
G02X448375Y-8967I36J-399D01*
G01Y-16530D01*
X446664Y-18241D01*
G02X445982Y-17958I-282J283D01*
G01Y-11326D01*
X445559D01*
Y-11018D01*
X445635Y-10968D01*
G03X444125I-755J1182D01*
G01X444201Y-11018D01*
Y-11326D01*
X443778D01*
Y-18428D01*
X445531D01*
G02X445794Y-19111I-20J-400D01*
G01X445563Y-19342D01*
X436762D01*
X436716Y-19337D01*
X436706Y-19334D01*
G03X436066Y-19337I-314J-1366D01*
G01X436043Y-19342D01*
X423262D01*
X423216Y-19337D01*
X423206Y-19334D01*
G03X422566Y-19337I-314J-1366D01*
G01X422543Y-19342D01*
X409262D01*
X409216Y-19337D01*
X409206Y-19334D01*
G03X408566Y-19337I-314J-1366D01*
G01X408543Y-19342D01*
X394262D01*
X394216Y-19337D01*
X394206Y-19334D01*
G03X393566Y-19337I-314J-1366D01*
G01X393543Y-19342D01*
X327036D01*
X326997Y-19325D01*
G03X325787I-605J-1375D01*
G01X325748Y-19342D01*
X308308D01*
G37*
G36*
G01X690514Y25200D02*
X688314Y27400D01*
X681314D01*
X678100Y30614D01*
Y35286D01*
X679500Y36686D01*
Y40885D01*
G02X679510Y40975I400J1D01*
G01Y41488D01*
X680033Y42011D01*
X684106D01*
G03X686094I994J989D01*
G01X701070D01*
X701500Y41581D01*
Y38586D01*
X702500Y37586D01*
Y32549D01*
X701400Y31849D01*
Y25707D01*
X700896Y25203D01*
X700583D01*
X700580Y25200D01*
X690514D01*
G37*
G36*
G01X675845Y509900D02*
X675300Y510445D01*
Y517914D01*
X674114Y519100D01*
X672414D01*
X672000Y519514D01*
Y521586D01*
X672004Y521590D01*
Y522053D01*
X672915Y522964D01*
X673825D01*
G02X674197Y522417I0J-400D01*
G03X676803I1303J-517D01*
G02X677175Y522964I372J147D01*
G01X681378D01*
X682500Y524086D01*
Y527586D01*
X683414Y528500D01*
X686060D01*
X686064Y528496D01*
X699595D01*
X702000Y526091D01*
Y520414D01*
X701400Y519814D01*
Y511014D01*
X701186Y510800D01*
X678986D01*
X678086Y509900D01*
X675845D01*
G37*
G36*
G01X1347199Y102000D02*
X1359086D01*
X1362500Y98586D01*
Y93414D01*
X1362000Y92914D01*
Y86414D01*
X1361086Y85500D01*
X1360000D01*
Y87914D01*
X1358914Y89000D01*
X1351086D01*
X1348586Y86500D01*
X1343586D01*
X1342086Y85000D01*
X1339914D01*
X1339500Y85414D01*
Y87086D01*
X1339914Y87500D01*
X1340914D01*
X1342500Y89086D01*
Y91914D01*
X1341414Y93000D01*
X1332149D01*
X1329649Y91000D01*
X1329236D01*
Y91302D01*
X1329319Y91362D01*
G03X1328818Y93866I-819J1138D01*
G03X1327398Y91634I-318J-1366D01*
G02X1327073Y91000I-325J-234D01*
G01X1325000D01*
Y95086D01*
X1326914Y97000D01*
X1338914D01*
X1341000Y99086D01*
Y101086D01*
X1341914Y102000D01*
X1343801D01*
G02X1344178Y101467I0J-400D01*
G03X1344111Y100808I1322J-467D01*
G03X1346646Y100192I1146J-808D01*
G03X1346822Y101467I-1146J808D01*
G02X1347199Y102000I377J133D01*
G37*
G36*
G01X1331000Y498300D02*
X1330000Y499300D01*
Y509909D01*
X1332991Y512900D01*
X1342640D01*
X1344552Y510988D01*
X1355598D01*
X1358000Y508586D01*
Y505914D01*
X1356500Y504414D01*
Y499086D01*
X1355714Y498300D01*
X1347600D01*
X1345600Y500300D01*
X1341000D01*
X1339000Y498300D01*
X1331000D01*
G37*
%LPC*%
G75*
G36*
G01X60473Y279010D02*
G03X61027I277J288D01*
G02Y276990I973J-1010D01*
G03X60473I-277J-288D01*
G02Y279010I-973J1010D01*
G37*
G36*
G01X64971Y315489D02*
G03Y314911I277J-289D01*
G02X63029I-971J-1011D01*
G03Y315489I-277J289D01*
G02X64971I971J1011D01*
G37*
G36*
G01X76830Y321972D02*
G02X76259Y320391I770J-1172D01*
G03X75657Y320608I-382J-117D01*
G02X73796Y320899I-770J1172D01*
G03X73178Y320903I-311J-252D01*
G02X71014Y320913I-1078J897D01*
G03X70437Y320957I-309J-253D01*
G02X68489Y321029I-937J1043D01*
G03X67911I-289J-277D01*
G02Y322971I-1011J971D01*
G03X68489I289J277D01*
G02X70586Y322887I1011J-971D01*
G03X71163Y322843I309J253D01*
G02X73191Y322681I937J-1043D01*
G03X73809Y322677I311J252D01*
G02X76228Y322189I1078J-897D01*
G03X76830Y321972I382J117D01*
G37*
G36*
G01X77011Y310638D02*
G02X74355Y309826I-1385J-221D01*
G03X73684Y309910I-362J-170D01*
G02X73871Y311392I-1084J890D01*
G03X74542Y311308I362J170D01*
G02X75699Y311818I1083J-890D01*
G03X76115Y312280I21J399D01*
G02X77427Y311100I1385J220D01*
G03X77011Y310638I-21J-399D01*
G37*
G36*
G01X59608Y298174D02*
G02X57670Y298249I-1008J-974D01*
G03X57692Y298826I-266J299D01*
G02X57830Y300900I1008J975D01*
G03X57808Y301543I-248J313D01*
G02X59470Y301600I792J1157D01*
G03X59492Y300957I248J-313D01*
G02X59630Y298751I-792J-1157D01*
G03X59608Y298174I266J-299D01*
G37*
G36*
G01X58175Y255329D02*
G02X56785Y255306I-675J-1229D01*
G03X56753Y256011I-204J344D01*
G02X58183Y256034I692J1445D01*
G03X58175Y255329I184J-355D01*
G37*
G36*
G01X325676Y104251D02*
G03X326253Y104144I338J214D01*
G02X325908Y102270I839J-1123D01*
G03X325331Y102377I-338J-214D01*
G02X325676Y104251I-839J1123D01*
G37*
G36*
G01X364145Y86617D02*
G03X363524I-311J-252D01*
G02Y88383I-1089J883D01*
G03X364145I310J252D01*
G02Y86617I1089J-883D01*
G37*
G36*
G01X376347Y85404D02*
G03Y84850I288J-277D01*
G02X374327I-1010J-973D01*
G03Y85404I-288J277D01*
G02X376347I1010J973D01*
G37*
G36*
G01X358743Y69924D02*
G03Y69346I277J-289D01*
G02X356801I-971J-1011D01*
G03Y69924I-277J289D01*
G02X358743I971J1011D01*
G37*
G36*
G01X308938Y69365D02*
G03X308924Y68789I270J-295D01*
G02X306982Y68837I-996J-987D01*
G03X306996Y69413I-270J295D01*
G02X308938Y69365I996J987D01*
G37*
G36*
G01X358702Y51293D02*
G03Y50699I268J-297D01*
G02X356822I-940J-1040D01*
G03Y51293I-268J297D01*
G02X358702I940J1040D01*
G37*
G36*
G01X363196Y46006D02*
G03X362587I-305J-258D01*
G02Y47822I-1069J908D01*
G03X363196I305J258D01*
G02Y46006I1069J-908D01*
G37*
G36*
G01X359577Y32318D02*
G03X359571Y31740I273J-292D01*
G02X357634Y31760I-979J-1004D01*
G03X357640Y32338I-273J292D01*
G02X359577Y32318I979J1004D01*
G37*
G36*
G01X373192Y18898D02*
G03X373437Y19395I-136J376D01*
G02X375251Y18501I1336J424D01*
G03X375006Y18004I136J-376D01*
G02X373192Y18898I-1336J-424D01*
G37*
G36*
G01X364291Y16081D02*
G03X363703Y16074I-291J-275D01*
G02X363682Y17975I-1041J939D01*
G03X364270Y17982I291J275D01*
G02X364291Y16081I1041J-939D01*
G37*
G36*
G01X358463Y13303D02*
G03Y12725I277J-289D01*
G02X356521I-971J-1011D01*
G03Y13303I-277J289D01*
G02X358463I971J1011D01*
G37*
G36*
G01X378626Y-9933D02*
G03X379212Y-9938I295J270D01*
G02X379198Y-11847I1020J-962D01*
G03X378612Y-11842I-295J-270D01*
G02X378626Y-9933I-1020J962D01*
G37*
G36*
G01X363887Y91625D02*
G02Y93375I-1095J875D01*
G03X364512I313J250D01*
G02Y91625I1095J-875D01*
G03X363887I-312J-250D01*
G37*
G36*
G01X375007Y75306D02*
G02X373577I-715J-1206D01*
G03Y75994I-204J344D01*
G02X375007I715J1206D01*
G03Y75306I204J-344D01*
G37*
G36*
G01X438890Y75282D02*
Y74976D01*
X438978Y74916D01*
G02X437400I-789J-1159D01*
G01X437488Y74976D01*
Y75282D01*
X437086D01*
Y82384D01*
X439288D01*
Y75282D01*
X438890D01*
G37*
G36*
G01X435543D02*
Y74976D01*
X435631Y74916D01*
G02X434053I-789J-1159D01*
G01X434141Y74976D01*
Y75282D01*
X433738D01*
Y82384D01*
X435942D01*
Y75282D01*
X435543D01*
G37*
G36*
G01X428850D02*
Y74976D01*
X428938Y74916D01*
G02X427360I-789J-1159D01*
G01X427448Y74976D01*
Y75282D01*
X427046D01*
Y82384D01*
X429248D01*
Y75282D01*
X428850D01*
G37*
G36*
G01X415464D02*
Y74976D01*
X415552Y74916D01*
G02X413974I-789J-1159D01*
G01X414062Y74976D01*
Y75282D01*
X413660D01*
Y82384D01*
X415864D01*
Y75282D01*
X415464D01*
G37*
G36*
G01X405424D02*
Y74976D01*
X405512Y74916D01*
G02X403934I-789J-1159D01*
G01X404022Y74976D01*
Y75282D01*
X403620D01*
Y82384D01*
X405824D01*
Y75282D01*
X405424D01*
G37*
G36*
G01X402078D02*
Y74976D01*
X402166Y74916D01*
G02X400588I-789J-1159D01*
G01X400676Y74976D01*
Y75282D01*
X400274D01*
Y82384D01*
X402478D01*
Y75282D01*
X402078D01*
G37*
G36*
G01X355227D02*
Y74976D01*
X355315Y74916D01*
G02X353737I-789J-1159D01*
G01X353825Y74976D01*
Y75282D01*
X353424D01*
Y82384D01*
X355626D01*
Y75282D01*
X355227D01*
G37*
G36*
G01X348534D02*
Y74976D01*
X348622Y74916D01*
G02X347044I-789J-1159D01*
G01X347132Y74976D01*
Y75282D01*
X346732D01*
Y82384D01*
X348934D01*
Y75282D01*
X348534D01*
G37*
G36*
G01X345187D02*
Y74976D01*
X345275Y74916D01*
G02X343697I-789J-1159D01*
G01X343785Y74976D01*
Y75282D01*
X343384D01*
Y82384D01*
X345588D01*
Y75282D01*
X345187D01*
G37*
G36*
G01X338494D02*
Y74976D01*
X338582Y74916D01*
G02X337004I-789J-1159D01*
G01X337092Y74976D01*
Y75282D01*
X336692D01*
Y82384D01*
X338894D01*
Y75282D01*
X338494D01*
G37*
G36*
G01X335148D02*
Y74976D01*
X335236Y74916D01*
G02X333658I-789J-1159D01*
G01X333746Y74976D01*
Y75282D01*
X333346D01*
Y82384D01*
X335548D01*
Y75282D01*
X335148D01*
G37*
G36*
G01X328455D02*
Y74976D01*
X328543Y74916D01*
G02X326965I-789J-1159D01*
G01X327053Y74976D01*
Y75282D01*
X326652D01*
Y82384D01*
X328856D01*
Y75282D01*
X328455D01*
G37*
G36*
G01X325108D02*
Y74976D01*
X325196Y74916D01*
G02X323618I-789J-1159D01*
G01X323706Y74976D01*
Y75282D01*
X323306D01*
Y82384D01*
X325508D01*
Y75282D01*
X325108D01*
G37*
G36*
G01X381727Y61396D02*
G02X380164Y61350I-747J-1186D01*
G03X380145Y62014I-233J326D01*
G02X381708Y62060I747J1186D01*
G03X381727Y61396I233J-326D01*
G37*
G36*
G01X445982Y57172D02*
X443778D01*
Y64274D01*
X444214D01*
Y64584D01*
X444122Y64643D01*
G02X445638I758J1179D01*
G01X445546Y64584D01*
Y64274D01*
X445982D01*
Y57172D01*
G37*
G36*
G01X439288D02*
X437086D01*
Y64274D01*
X437523D01*
Y64584D01*
X437431Y64643D01*
G02X438947I758J1179D01*
G01X438855Y64584D01*
Y64274D01*
X439288D01*
Y57172D01*
G37*
G36*
G01X432596D02*
X430392D01*
Y64274D01*
X430805D01*
Y64581D01*
X430716Y64641D01*
G02X432272I778J1166D01*
G01X432183Y64581D01*
Y64274D01*
X432596D01*
Y57172D01*
G37*
G36*
G01X425902D02*
X423700D01*
Y64274D01*
X424112D01*
Y64581D01*
X424023Y64641D01*
G02X425579I778J1166D01*
G01X425490Y64581D01*
Y64274D01*
X425902D01*
Y57172D01*
G37*
G36*
G01X422556D02*
X420354D01*
Y64274D01*
X420790D01*
Y64584D01*
X420698Y64643D01*
G02X422214I758J1179D01*
G01X422122Y64584D01*
Y64274D01*
X422556D01*
Y57172D01*
G37*
G36*
G01X415864D02*
X413660D01*
Y64274D01*
X414097D01*
Y64584D01*
X414005Y64643D01*
G02X415521I758J1179D01*
G01X415429Y64584D01*
Y64274D01*
X415864D01*
Y57172D01*
G37*
G36*
G01X409170D02*
X406968D01*
Y64274D01*
X407380D01*
Y64581D01*
X407291Y64641D01*
G02X408847I778J1166D01*
G01X408758Y64581D01*
Y64274D01*
X409170D01*
Y57172D01*
G37*
G36*
G01X405824D02*
X403620D01*
Y64274D01*
X404057D01*
Y64584D01*
X403965Y64643D01*
G02X405481I758J1179D01*
G01X405389Y64584D01*
Y64274D01*
X405824D01*
Y57172D01*
G37*
G36*
G01X399130D02*
X396928D01*
Y64274D01*
X397340D01*
Y64581D01*
X397251Y64641D01*
G02X398807I778J1166D01*
G01X398718Y64581D01*
Y64274D01*
X399130D01*
Y57172D01*
G37*
G36*
G01X355626D02*
X353424D01*
Y64274D01*
X353859D01*
Y64584D01*
X353767Y64643D01*
G02X355283I758J1179D01*
G01X355191Y64584D01*
Y64274D01*
X355626D01*
Y57172D01*
G37*
G36*
G01X352280D02*
X350078D01*
Y64274D01*
X350513D01*
Y64584D01*
X350421Y64643D01*
G02X351937I758J1179D01*
G01X351845Y64584D01*
Y64274D01*
X352280D01*
Y57172D01*
G37*
G36*
G01X345588D02*
X343384D01*
Y64274D01*
X343820D01*
Y64584D01*
X343728Y64643D01*
G02X345244I758J1179D01*
G01X345152Y64584D01*
Y64274D01*
X345588D01*
Y57172D01*
G37*
G36*
G01X342242D02*
X340038D01*
Y64274D01*
X340474D01*
Y64584D01*
X340382Y64643D01*
G02X341898I758J1179D01*
G01X341806Y64584D01*
Y64274D01*
X342242D01*
Y57172D01*
G37*
G36*
G01X335548D02*
X333346D01*
Y64274D01*
X333767D01*
Y64582D01*
X333677Y64642D01*
G02X335215I769J1172D01*
G01X335125Y64582D01*
Y64274D01*
X335548D01*
Y57172D01*
G37*
G36*
G01X332202D02*
X329998D01*
Y64274D01*
X330421D01*
Y64582D01*
X330331Y64642D01*
G02X331869I769J1172D01*
G01X331779Y64582D01*
Y64274D01*
X332202D01*
Y57172D01*
G37*
G36*
G01X325508D02*
X323306D01*
Y64274D01*
X323728D01*
Y64582D01*
X323638Y64642D01*
G02X325176I769J1172D01*
G01X325086Y64582D01*
Y64274D01*
X325508D01*
Y57172D01*
G37*
G36*
G01X322162D02*
X319960D01*
Y64274D01*
X320382D01*
Y64582D01*
X320292Y64642D01*
G02X321830I769J1172D01*
G01X321740Y64582D01*
Y64274D01*
X322162D01*
Y57172D01*
G37*
G36*
G01X315470D02*
X313266D01*
Y64274D01*
X313689D01*
Y64582D01*
X313599Y64642D01*
G02X315137I769J1172D01*
G01X315047Y64582D01*
Y64274D01*
X315470D01*
Y57172D01*
G37*
G36*
G01X438890Y37482D02*
Y37176D01*
X438978Y37116D01*
G02X437400I-789J-1159D01*
G01X437488Y37176D01*
Y37482D01*
X437086D01*
Y44584D01*
X439288D01*
Y37482D01*
X438890D01*
G37*
G36*
G01X435543D02*
Y37176D01*
X435631Y37116D01*
G02X434053I-789J-1159D01*
G01X434141Y37176D01*
Y37482D01*
X433738D01*
Y44584D01*
X435942D01*
Y37482D01*
X435543D01*
G37*
G36*
G01X428850D02*
Y37176D01*
X428938Y37116D01*
G02X427360I-789J-1159D01*
G01X427448Y37176D01*
Y37482D01*
X427046D01*
Y44584D01*
X429248D01*
Y37482D01*
X428850D01*
G37*
G36*
G01X415464D02*
Y37176D01*
X415552Y37116D01*
G02X413974I-789J-1159D01*
G01X414062Y37176D01*
Y37482D01*
X413660D01*
Y44584D01*
X415864D01*
Y37482D01*
X415464D01*
G37*
G36*
G01X405424D02*
Y37176D01*
X405512Y37116D01*
G02X403934I-789J-1159D01*
G01X404022Y37176D01*
Y37482D01*
X403620D01*
Y44584D01*
X405824D01*
Y37482D01*
X405424D01*
G37*
G36*
G01X402078D02*
Y37176D01*
X402166Y37116D01*
G02X400588I-789J-1159D01*
G01X400676Y37176D01*
Y37482D01*
X400274D01*
Y44584D01*
X402478D01*
Y37482D01*
X402078D01*
G37*
G36*
G01X395385D02*
Y37176D01*
X395473Y37116D01*
G02X393895I-789J-1159D01*
G01X393983Y37176D01*
Y37482D01*
X393582D01*
Y44584D01*
X395784D01*
Y37482D01*
X395385D01*
G37*
G36*
G01X355227D02*
Y37176D01*
X355315Y37116D01*
G02X353737I-789J-1159D01*
G01X353825Y37176D01*
Y37482D01*
X353424D01*
Y44584D01*
X355626D01*
Y37482D01*
X355227D01*
G37*
G36*
G01X348534D02*
Y37176D01*
X348622Y37116D01*
G02X347044I-789J-1159D01*
G01X347132Y37176D01*
Y37482D01*
X346732D01*
Y44584D01*
X348934D01*
Y37482D01*
X348534D01*
G37*
G36*
G01X345187D02*
Y37176D01*
X345275Y37116D01*
G02X343697I-789J-1159D01*
G01X343785Y37176D01*
Y37482D01*
X343384D01*
Y44584D01*
X345588D01*
Y37482D01*
X345187D01*
G37*
G36*
G01X338494D02*
Y37176D01*
X338582Y37116D01*
G02X337004I-789J-1159D01*
G01X337092Y37176D01*
Y37482D01*
X336692D01*
Y44584D01*
X338894D01*
Y37482D01*
X338494D01*
G37*
G36*
G01X335148D02*
Y37176D01*
X335236Y37116D01*
G02X333658I-789J-1159D01*
G01X333746Y37176D01*
Y37482D01*
X333346D01*
Y44584D01*
X335548D01*
Y37482D01*
X335148D01*
G37*
G36*
G01X328455D02*
Y37176D01*
X328543Y37116D01*
G02X326965I-789J-1159D01*
G01X327053Y37176D01*
Y37482D01*
X326652D01*
Y44584D01*
X328856D01*
Y37482D01*
X328455D01*
G37*
G36*
G01X325108D02*
Y37176D01*
X325196Y37116D01*
G02X323618I-789J-1159D01*
G01X323706Y37176D01*
Y37482D01*
X323306D01*
Y44584D01*
X325508D01*
Y37482D01*
X325108D01*
G37*
G36*
G01X311722D02*
Y37176D01*
X311810Y37116D01*
G02X310232I-789J-1159D01*
G01X310320Y37176D01*
Y37482D01*
X309920D01*
Y44584D01*
X312122D01*
Y37482D01*
X311722D01*
G37*
G36*
G01X365244D02*
Y37174D01*
X365334Y37114D01*
G02X363796I-769J-1172D01*
G01X363886Y37174D01*
Y37482D01*
X363464D01*
Y44584D01*
X365666D01*
Y37482D01*
X365244D01*
G37*
G36*
G01X361897D02*
Y37174D01*
X361987Y37114D01*
G02X360449I-769J-1172D01*
G01X360539Y37174D01*
Y37482D01*
X360116D01*
Y44584D01*
X362320D01*
Y37482D01*
X361897D01*
G37*
G36*
G01X381635Y26053D02*
G02X379949I-843J-1120D01*
G03Y26692I-241J320D01*
G02X381635I843J1120D01*
G03Y26053I241J-320D01*
G37*
G36*
G01X445982Y19372D02*
X443778D01*
Y26474D01*
X444214D01*
Y26784D01*
X444122Y26843D01*
G02X445638I758J1179D01*
G01X445546Y26784D01*
Y26474D01*
X445982D01*
Y19372D01*
G37*
G36*
G01X439288D02*
X437086D01*
Y26474D01*
X437523D01*
Y26784D01*
X437431Y26843D01*
G02X438947I758J1179D01*
G01X438855Y26784D01*
Y26474D01*
X439288D01*
Y19372D01*
G37*
G36*
G01X432596D02*
X430392D01*
Y26474D01*
X430805D01*
Y26781D01*
X430716Y26841D01*
G02X432272I778J1166D01*
G01X432183Y26781D01*
Y26474D01*
X432596D01*
Y19372D01*
G37*
G36*
G01X425902D02*
X423700D01*
Y26474D01*
X424112D01*
Y26781D01*
X424023Y26841D01*
G02X425579I778J1166D01*
G01X425490Y26781D01*
Y26474D01*
X425902D01*
Y19372D01*
G37*
G36*
G01X422556D02*
X420354D01*
Y26474D01*
X420790D01*
Y26784D01*
X420698Y26843D01*
G02X422214I758J1179D01*
G01X422122Y26784D01*
Y26474D01*
X422556D01*
Y19372D01*
G37*
G36*
G01X415864D02*
X413660D01*
Y26474D01*
X414094D01*
Y26784D01*
X414002Y26843D01*
G02X415522I760J1178D01*
G01X415430Y26784D01*
Y26474D01*
X415864D01*
Y19372D01*
G37*
G36*
G01X409170D02*
X406968D01*
Y26474D01*
X407380D01*
Y26781D01*
X407291Y26841D01*
G02X408847I778J1166D01*
G01X408758Y26781D01*
Y26474D01*
X409170D01*
Y19372D01*
G37*
G36*
G01X405824D02*
X403620D01*
Y26474D01*
X404057D01*
Y26784D01*
X403965Y26843D01*
G02X405481I758J1179D01*
G01X405389Y26784D01*
Y26474D01*
X405824D01*
Y19372D01*
G37*
G36*
G01X399130D02*
X396928D01*
Y26474D01*
X397340D01*
Y26781D01*
X397251Y26841D01*
G02X398807I778J1166D01*
G01X398718Y26781D01*
Y26474D01*
X399130D01*
Y19372D01*
G37*
G36*
G01X365666D02*
X363464D01*
Y26474D01*
X363886D01*
Y26782D01*
X363796Y26842D01*
G02X365334I769J1172D01*
G01X365244Y26782D01*
Y26474D01*
X365666D01*
Y19372D01*
G37*
G36*
G01X362320D02*
X360116D01*
Y26474D01*
X360539D01*
Y26782D01*
X360449Y26842D01*
G02X361987I769J1172D01*
G01X361897Y26782D01*
Y26474D01*
X362320D01*
Y19372D01*
G37*
G36*
G01X355626D02*
X353424D01*
Y26474D01*
X353859D01*
Y26784D01*
X353767Y26843D01*
G02X355283I758J1179D01*
G01X355191Y26784D01*
Y26474D01*
X355626D01*
Y19372D01*
G37*
G36*
G01X352280D02*
X350078D01*
Y26474D01*
X350513D01*
Y26784D01*
X350421Y26843D01*
G02X351937I758J1179D01*
G01X351845Y26784D01*
Y26474D01*
X352280D01*
Y19372D01*
G37*
G36*
G01X345588D02*
X343384D01*
Y26474D01*
X343820D01*
Y26784D01*
X343728Y26843D01*
G02X345244I758J1179D01*
G01X345152Y26784D01*
Y26474D01*
X345588D01*
Y19372D01*
G37*
G36*
G01X342242D02*
X340038D01*
Y26474D01*
X340474D01*
Y26784D01*
X340382Y26843D01*
G02X341898I758J1179D01*
G01X341806Y26784D01*
Y26474D01*
X342242D01*
Y19372D01*
G37*
G36*
G01X335548D02*
X333346D01*
Y26474D01*
X333767D01*
Y26782D01*
X333677Y26842D01*
G02X335215I769J1172D01*
G01X335125Y26782D01*
Y26474D01*
X335548D01*
Y19372D01*
G37*
G36*
G01X332202D02*
X329998D01*
Y26474D01*
X330421D01*
Y26782D01*
X330331Y26842D01*
G02X331869I769J1172D01*
G01X331779Y26782D01*
Y26474D01*
X332202D01*
Y19372D01*
G37*
G36*
G01X325508D02*
X323306D01*
Y26474D01*
X323728D01*
Y26782D01*
X323638Y26842D01*
G02X325176I769J1172D01*
G01X325086Y26782D01*
Y26474D01*
X325508D01*
Y19372D01*
G37*
G36*
G01X322162D02*
X319960D01*
Y26474D01*
X320382D01*
Y26782D01*
X320292Y26842D01*
G02X321830I769J1172D01*
G01X321740Y26782D01*
Y26474D01*
X322162D01*
Y19372D01*
G37*
G36*
G01X315470D02*
X313266D01*
Y26474D01*
X313689D01*
Y26782D01*
X313599Y26842D01*
G02X315137I769J1172D01*
G01X315047Y26782D01*
Y26474D01*
X315470D01*
Y19372D01*
G37*
G36*
G01X308776D02*
X306574D01*
Y26474D01*
X306996D01*
Y26782D01*
X306906Y26842D01*
G02X308444I769J1172D01*
G01X308354Y26782D01*
Y26474D01*
X308776D01*
Y19372D01*
G37*
G36*
G01X376959Y5723D02*
G02Y7277I-1167J777D01*
G03X377625I333J222D01*
G02Y5723I1167J-777D01*
G03X376959I-333J-222D01*
G37*
G36*
G01X355359Y-318D02*
Y-611D01*
X355430Y-671D01*
G02X353620I-905J-1071D01*
G01X353691Y-611D01*
Y-318D01*
X353424D01*
Y6784D01*
X355626D01*
Y-318D01*
X355359D01*
G37*
G36*
G01X435673D02*
Y-611D01*
X435744Y-671D01*
G02X433936I-904J-1072D01*
G01X434007Y-611D01*
Y-318D01*
X433738D01*
Y6784D01*
X435942D01*
Y-318D01*
X435673D01*
G37*
G36*
G01X428980D02*
Y-611D01*
X429051Y-671D01*
G02X427243I-904J-1072D01*
G01X427314Y-611D01*
Y-318D01*
X427046D01*
Y6784D01*
X429248D01*
Y-318D01*
X428980D01*
G37*
G36*
G01X415594D02*
Y-611D01*
X415665Y-671D01*
G02X413857I-904J-1072D01*
G01X413928Y-611D01*
Y-318D01*
X413660D01*
Y6784D01*
X415864D01*
Y-318D01*
X415594D01*
G37*
G36*
G01X402208D02*
Y-611D01*
X402279Y-671D01*
G02X400471I-904J-1072D01*
G01X400542Y-611D01*
Y-318D01*
X400274D01*
Y6784D01*
X402478D01*
Y-318D01*
X402208D01*
G37*
G36*
G01X348666D02*
Y-611D01*
X348737Y-671D01*
G02X346929I-904J-1072D01*
G01X347000Y-611D01*
Y-318D01*
X346732D01*
Y6784D01*
X348934D01*
Y-318D01*
X348666D01*
G37*
G36*
G01X335280D02*
Y-611D01*
X335351Y-671D01*
G02X333543I-904J-1072D01*
G01X333614Y-611D01*
Y-318D01*
X333346D01*
Y6784D01*
X335548D01*
Y-318D01*
X335280D01*
G37*
G36*
G01X328587D02*
Y-611D01*
X328658Y-671D01*
G02X326850I-904J-1072D01*
G01X326921Y-611D01*
Y-318D01*
X326652D01*
Y6784D01*
X328856D01*
Y-318D01*
X328587D01*
G37*
G36*
G01X365244D02*
Y-626D01*
X365334Y-686D01*
G02X363796I-769J-1172D01*
G01X363886Y-626D01*
Y-318D01*
X363464D01*
Y6784D01*
X365666D01*
Y-318D01*
X365244D01*
G37*
G36*
G01X361897D02*
Y-626D01*
X361987Y-686D01*
G02X360449I-769J-1172D01*
G01X360539Y-626D01*
Y-318D01*
X360116D01*
Y6784D01*
X362320D01*
Y-318D01*
X361897D01*
G37*
G36*
G01X439288Y-18428D02*
X437086D01*
Y-11326D01*
X437508D01*
Y-11018D01*
X437418Y-10958D01*
G02X438956I769J1172D01*
G01X438866Y-11018D01*
Y-11326D01*
X439288D01*
Y-18428D01*
G37*
G36*
G01X432596D02*
X430392D01*
Y-11326D01*
X430661D01*
Y-11033D01*
X430590Y-10973D01*
G02X432398I904J1072D01*
G01X432327Y-11033D01*
Y-11326D01*
X432596D01*
Y-18428D01*
G37*
G36*
G01X425902D02*
X423700D01*
Y-11326D01*
X424122D01*
Y-11018D01*
X424032Y-10958D01*
G02X425570I769J1172D01*
G01X425480Y-11018D01*
Y-11326D01*
X425902D01*
Y-18428D01*
G37*
G36*
G01X405824D02*
X403620D01*
Y-11326D01*
X403889D01*
Y-11033D01*
X403818Y-10973D01*
G02X405626I904J1072D01*
G01X405555Y-11033D01*
Y-11326D01*
X405824D01*
Y-18428D01*
G37*
G36*
G01X399130D02*
X396928D01*
Y-11326D01*
X397196D01*
Y-11033D01*
X397125Y-10973D01*
G02X398933I904J1072D01*
G01X398862Y-11033D01*
Y-11326D01*
X399130D01*
Y-18428D01*
G37*
G36*
G01X365666D02*
X363464D01*
Y-11326D01*
X363886D01*
Y-11018D01*
X363796Y-10958D01*
G02X365334I769J1172D01*
G01X365244Y-11018D01*
Y-11326D01*
X365666D01*
Y-18428D01*
G37*
G36*
G01X362320D02*
X360116D01*
Y-11326D01*
X360539D01*
Y-11018D01*
X360449Y-10958D01*
G02X361987I769J1172D01*
G01X361897Y-11018D01*
Y-11326D01*
X362320D01*
Y-18428D01*
G37*
G36*
G01X352280D02*
X350078D01*
Y-11326D01*
X350346D01*
Y-11033D01*
X350275Y-10973D01*
G02X352083I904J1072D01*
G01X352012Y-11033D01*
Y-11326D01*
X352280D01*
Y-18428D01*
G37*
G36*
G01X345588D02*
X343384D01*
Y-11326D01*
X343807D01*
Y-11018D01*
X343717Y-10958D01*
G02X345255I769J1172D01*
G01X345165Y-11018D01*
Y-11326D01*
X345588D01*
Y-18428D01*
G37*
G36*
G01X332202D02*
X329998D01*
Y-11326D01*
X330421D01*
Y-11018D01*
X330331Y-10958D01*
G02X331869I769J1172D01*
G01X331779Y-11018D01*
Y-11326D01*
X332202D01*
Y-18428D01*
G37*
G36*
G01X325508D02*
X323306D01*
Y-11326D01*
X323574D01*
Y-11033D01*
X323503Y-10973D01*
G02X325311I904J1072D01*
G01X325240Y-11033D01*
Y-11326D01*
X325508D01*
Y-18428D01*
G37*
G36*
G01X1345997Y508808D02*
G02X1345824Y507297I1084J-889D01*
G03X1345157Y507374I-358J-177D01*
G02X1345330Y508885I-1084J889D01*
G03X1345997Y508808I358J177D01*
G37*
G36*
G01X1333988Y506103D02*
G02X1331680Y507358I-1388J197D01*
G03X1331658Y507979I-263J302D01*
G02X1333892Y509263I842J1121D01*
G03X1334470Y508952I398J46D01*
G02X1334543Y506413I630J-1252D01*
G03X1333988Y506103I-159J-367D01*
G37*
G54D112*
X388187Y88678D03*
Y50878D03*
Y69778D03*
Y13078D03*
Y31978D03*
Y-5822D03*
G54D76*
X19800Y257900D03*
G54D49*
X19904Y254162D03*
X37000Y265350D03*
X33490Y267900D03*
X37000Y275000D03*
X48550Y301650D03*
X91600Y278700D03*
X53500Y307300D03*
X53400Y298100D03*
X79410Y331636D03*
X84000Y324542D03*
X53100Y327000D03*
X64700Y310525D03*
X69125Y310625D03*
X84300Y305700D03*
Y310700D03*
X66300Y285850D03*
X72904Y284898D03*
X84300Y289000D03*
X82050Y283951D03*
X77103Y283900D03*
X88600Y302997D03*
X81324Y316119D03*
X84866Y294213D03*
X79400Y325400D03*
X84300Y299000D03*
X88840Y324740D03*
X53100Y315000D03*
X53250Y302800D03*
X92086Y324258D03*
X307675Y-1843D03*
X321192Y13200D03*
X321334Y32100D03*
X308092D03*
X307675Y35957D03*
X334292Y13200D03*
Y32100D03*
X308157Y-7180D03*
X307675Y17057D03*
X321061D03*
Y-7108D03*
X327754Y9114D03*
X324407Y17057D03*
Y-4536D03*
Y9114D03*
X314368Y-7108D03*
X311021Y-4536D03*
X314368Y17057D03*
X311021Y9114D03*
X334446D03*
X331100Y17057D03*
X354526Y-7108D03*
Y17057D03*
X354525Y9122D03*
X351179Y17057D03*
X347833Y9122D03*
X344486D03*
Y-4536D03*
Y17057D03*
X337793Y9114D03*
Y-4536D03*
X341140Y17057D03*
Y-7108D03*
X334447D03*
Y17057D03*
X317714Y35957D03*
Y-4536D03*
Y9114D03*
X307950Y50729D03*
X321192Y51000D03*
X321334Y69900D03*
X307592Y73800D03*
X334292Y51000D03*
Y69900D03*
X308166Y87394D03*
X307675Y54857D03*
Y92657D03*
X321061Y92757D03*
X327754Y87392D03*
X324407Y89964D03*
Y84599D03*
X314368Y92657D03*
X311021Y84714D03*
X334447Y87392D03*
X331100Y89964D03*
X354415Y92757D03*
Y87392D03*
X351179Y89964D03*
X347833Y87392D03*
X344486Y84714D03*
Y89964D03*
X337793Y84599D03*
X341140Y92757D03*
X334447D03*
X321061Y54857D03*
X327754Y46914D03*
X324407Y54857D03*
Y46914D03*
X314368Y54857D03*
X311021Y46914D03*
X334446D03*
X331100Y54857D03*
X354526D03*
X354525Y46922D03*
X351179Y54857D03*
X347833Y46922D03*
X344486D03*
Y54857D03*
X337793Y46914D03*
X341140Y54857D03*
X334447D03*
X317714Y84714D03*
Y73757D03*
Y46914D03*
X348978Y220809D03*
Y209109D03*
X352357Y211060D03*
X342218Y220809D03*
X355737Y209109D03*
Y220809D03*
X342218Y205210D03*
X345598Y207159D03*
X342218Y209109D03*
X348978Y205210D03*
Y216909D03*
X352357Y218860D03*
X345598D03*
X342218Y213009D03*
X359117Y211060D03*
Y218860D03*
X355737Y216909D03*
Y213009D03*
X342218Y216909D03*
X345598Y211060D03*
X348978Y213009D03*
X352357Y238360D03*
X345598D03*
X342218Y224709D03*
X345598Y230559D03*
X352357Y222760D03*
X348978Y224709D03*
X355737D03*
X348978Y228610D03*
X352357Y230559D03*
X348978Y236409D03*
Y240309D03*
X352357Y234460D03*
X345598Y242260D03*
Y234460D03*
X342218Y240309D03*
Y228610D03*
Y236409D03*
X359117Y230559D03*
X355737Y228610D03*
Y236409D03*
X352357Y242260D03*
X355737Y240309D03*
X345598Y222760D03*
X380200Y-1200D03*
X394192Y-9700D03*
X408184Y32100D03*
Y13200D03*
X404723Y17057D03*
X401376Y9121D03*
X364565Y9114D03*
X361218D03*
X414761Y-7108D03*
X414762Y17058D03*
X398029Y17042D03*
X404722Y9121D03*
Y-4536D03*
X414763Y9122D03*
X408069Y17042D03*
X408068Y-7108D03*
X394682Y11792D03*
X394683Y-2200D03*
X376700Y-1300D03*
X371258Y-1858D03*
Y-9800D03*
X411415Y36058D03*
Y-4536D03*
X411416Y9122D03*
X374401Y-11346D03*
X394682Y17157D03*
X371042Y46900D03*
X380792Y56500D03*
X408184Y51000D03*
Y69900D03*
X394492Y54700D03*
X404722Y89964D03*
X401375Y87392D03*
X414761Y92757D03*
X398029Y89964D03*
X404722Y84599D03*
X414761Y87392D03*
X408068Y92757D03*
X394682Y87392D03*
X404723Y54857D03*
X401377Y46922D03*
X364565Y54842D03*
X361218D03*
X414763Y54857D03*
X398029Y54842D03*
X404723Y46922D03*
X414763D03*
X408069Y54842D03*
X394682Y49592D03*
X380600Y37400D03*
X384992Y81600D03*
X411415Y84714D03*
X411416Y73757D03*
Y46922D03*
X394682Y68492D03*
X386292Y98800D03*
X401375Y103116D03*
X414819D03*
X408126D03*
X362497Y209109D03*
Y220809D03*
X369257D03*
X382777D03*
Y209109D03*
X376017Y220809D03*
Y209109D03*
X389537D03*
Y220809D03*
X396296Y209109D03*
Y220809D03*
X407706Y209109D03*
Y220809D03*
X372637Y207159D03*
X399676D03*
X372637Y211060D03*
X392916D03*
X389537Y213009D03*
X396296D03*
X369257D03*
X396296Y216909D03*
X376017D03*
X365877Y218860D03*
X372637D03*
X362497Y216909D03*
X382777Y213009D03*
X399676Y218860D03*
X386157Y211060D03*
X407706Y216909D03*
X379397Y207159D03*
X369257Y216909D03*
X382777D03*
X379397Y218860D03*
X392916D03*
X362497Y213009D03*
X386157Y218860D03*
X389537Y216909D03*
X376017Y213009D03*
X399676Y211060D03*
X359117Y238360D03*
X365877D03*
X372637D03*
X376017Y224709D03*
X372637Y222760D03*
X365877D03*
X369257Y224709D03*
X362497D03*
X386157Y222760D03*
X396296Y228610D03*
X389537Y224709D03*
X399676Y222760D03*
X382777Y224709D03*
X379397Y222760D03*
X359117D03*
X392916D03*
X396296Y224709D03*
X379397Y230559D03*
X365877Y242260D03*
X407706Y236409D03*
X372637Y234460D03*
X365877D03*
X372637Y230559D03*
X365877D03*
X369257Y236409D03*
X362497D03*
X369257Y228610D03*
X362497D03*
X382777D03*
X389537Y236409D03*
X399676Y230559D03*
Y234460D03*
X382777Y236409D03*
X392916Y230559D03*
X407706Y224709D03*
Y228610D03*
X376017Y236409D03*
X369257Y240309D03*
X376017D03*
X386157Y230559D03*
X379397Y234460D03*
X359117Y242260D03*
X362497Y240309D03*
X359117Y234460D03*
X386157D03*
X392916D03*
X389537Y228610D03*
X396296Y236409D03*
X376017Y228610D03*
X433508Y32100D03*
X421368D03*
X433508Y13200D03*
X421368D03*
X421455Y9121D03*
X421454Y-1817D03*
X438187Y-4536D03*
Y9120D03*
X444880Y-4536D03*
X431494Y17042D03*
X444880Y17059D03*
Y9122D03*
X428147Y9120D03*
X421454Y-7108D03*
X421456Y17057D03*
X434840Y9120D03*
X424801Y17042D03*
X438187Y17059D03*
X421368Y51000D03*
X433508D03*
Y69900D03*
X421368D03*
X421455Y46921D03*
X421456Y73757D03*
X438187Y84714D03*
X431494Y89964D03*
X444880D03*
Y84714D03*
X428147Y87392D03*
X421454Y92757D03*
X434840Y87392D03*
X424801Y89964D03*
X438187D03*
X438189Y46922D03*
X431494Y54842D03*
X444880Y54859D03*
Y46922D03*
X428149D03*
X421456Y54857D03*
X434842Y46922D03*
X424801Y54842D03*
X438187Y54859D03*
X427696Y103100D03*
X421512Y103116D03*
X689500Y37900D03*
X690500Y523300D03*
X1353500Y96959D03*
X1348615Y96239D03*
G54D53*
X334447Y-14877D03*
X337793Y3233D03*
X354525Y-14877D03*
X321061D03*
X324407Y3233D03*
X311021D03*
Y78833D03*
X307675Y60723D03*
X394683Y3233D03*
X408069Y-14877D03*
X394683Y78833D03*
X364565D03*
Y60723D03*
X438187Y3233D03*
X421455Y-14877D03*
G54D52*
X344486Y3233D03*
X341140Y-14877D03*
X314368D03*
X404722Y3233D03*
X414762Y-14877D03*
X361218Y78833D03*
Y60723D03*
X444880Y3233D03*
Y78833D03*
%LPD*%
G75*
G54D10*
X-17936Y-49379D03*
Y-53779D03*
Y-44979D03*
Y-40579D03*
X-18079Y-35764D03*
Y-58764D03*
X-14186Y196989D03*
Y199989D03*
X-14839Y445588D03*
X-14753Y448601D03*
X-17179Y643156D03*
X-17194Y638753D03*
X-17179Y647556D03*
Y660756D03*
Y651956D03*
Y656356D03*
X-13636Y-40479D03*
Y-44879D03*
Y-53679D03*
X-9079Y-50164D03*
X-4679D03*
X-279D03*
X-9079Y-54264D03*
X-4679D03*
X-279D03*
X22964Y-40379D03*
Y-44779D03*
Y-53579D03*
Y-49179D03*
X18964Y-53579D03*
Y-49179D03*
X13964Y-53579D03*
Y-49179D03*
X8964Y-40379D03*
Y-44779D03*
Y-53579D03*
Y-49179D03*
X3964Y-40379D03*
Y-44779D03*
Y-53579D03*
Y-49179D03*
X25921Y-35764D03*
X30321D03*
X43521D03*
X39121D03*
X34721D03*
X8321D03*
X12721D03*
X21521D03*
X17121D03*
X-13679D03*
X-9279D03*
X3921D03*
X-4879D03*
X-479D03*
X17121Y-58764D03*
X21521D03*
X12721D03*
X8321D03*
X34721D03*
X39121D03*
X43521D03*
X30321D03*
X25921D03*
X-479D03*
X-13679D03*
X-4879D03*
X3921D03*
X-13636Y-49279D03*
X-9279Y-58764D03*
X875Y211336D03*
X6074Y211293D03*
X3474Y211263D03*
X875Y208352D03*
X36200Y208600D03*
X33200D03*
X20700D03*
X17700Y211600D03*
X20700D03*
X17700Y208600D03*
X23700Y211600D03*
Y208600D03*
X33200Y211600D03*
X30200D03*
Y208600D03*
X36200Y211600D03*
X6074Y208321D03*
X3474Y208263D03*
X5500Y218500D03*
X-5300Y200191D03*
X-7900D03*
X-2700Y200202D03*
X-11586Y196989D03*
Y199989D03*
X-2600Y232300D03*
X-5246Y232351D03*
X-7846D03*
X20500Y221000D03*
Y224000D03*
X17500Y221000D03*
Y224000D03*
X23500D03*
Y221000D03*
X33300Y224000D03*
Y221000D03*
X30300D03*
Y224000D03*
X36300D03*
Y221000D03*
X-14129Y235221D03*
X-11484Y235215D03*
Y232215D03*
X-14084D03*
X2678Y221018D03*
X5277Y221110D03*
X5173Y224042D03*
X2574Y223963D03*
X-26Y223982D03*
X-11652Y445530D03*
Y448530D03*
X22421Y647556D03*
X26821D03*
X31221D03*
X18021D03*
Y643156D03*
X31221D03*
X26821D03*
X22421D03*
X18006Y638753D03*
X9221Y647556D03*
X13621D03*
Y643156D03*
X9221D03*
X4821D03*
Y647556D03*
X22406Y638753D03*
X26806D03*
X31206D03*
X-12794D03*
X-12779Y647556D03*
Y643156D03*
X40006Y638753D03*
X44406D03*
X35606D03*
X35621Y647556D03*
Y643156D03*
X-9599Y610630D03*
X-3301Y619643D03*
Y601615D03*
X4549Y620682D03*
X4548Y600577D03*
X13801Y624130D03*
Y597130D03*
X23360Y620172D03*
X23352Y601079D03*
X27301Y610630D03*
X18021Y660756D03*
X35621Y656356D03*
X26821Y660756D03*
X18021Y651956D03*
X31221D03*
X22421Y660756D03*
X26821Y651956D03*
X22421D03*
X4821D03*
X13621D03*
X9221D03*
X-8379Y660756D03*
X4821Y656356D03*
X9221D03*
X13621D03*
X-3979D03*
X421D03*
X13621Y660756D03*
X-3979D03*
X421D03*
X4821D03*
X-12779Y651956D03*
X22421Y656356D03*
X26821D03*
X31221D03*
X18021D03*
X-8379D03*
X-12779D03*
X31221Y660756D03*
X35621Y651956D03*
Y660756D03*
X44421D03*
X40021D03*
X-12779D03*
X9221D03*
X107921Y-58764D03*
X102921D03*
X97921D03*
X92921D03*
X87921D03*
X82921D03*
X77921D03*
X72921D03*
X67921D03*
X62921D03*
X57921D03*
X52921D03*
X47921Y-35764D03*
Y-58764D03*
X107921Y-35764D03*
X102921D03*
X97921D03*
X92921D03*
X87921D03*
X82921D03*
X77921D03*
X72921D03*
X67921D03*
X62921D03*
X57921D03*
X52921D03*
X96249Y204722D03*
X64700Y210100D03*
Y212800D03*
X64778Y218062D03*
X58000Y206500D03*
X56900Y197800D03*
X93870Y199131D03*
X97730Y188584D03*
X58200Y230400D03*
Y233400D03*
X55600Y230400D03*
X53000Y230300D03*
Y233300D03*
X55600Y233400D03*
X58200Y227400D03*
X53000Y227300D03*
X55600Y227400D03*
X58200Y239400D03*
X53000Y239300D03*
X55600Y239400D03*
X58200Y236400D03*
X55600D03*
X53000Y236300D03*
X71500Y263300D03*
X68800D03*
X53004Y244632D03*
X55275Y245900D03*
X57875D03*
X57457Y248537D03*
Y251237D03*
X57600Y262800D03*
X57500Y260200D03*
X62800Y265500D03*
X71500Y266000D03*
X65500Y265500D03*
X68800Y266000D03*
X60000Y265500D03*
X76540Y397355D03*
X81900Y398300D03*
X79140Y397355D03*
X98149Y399769D03*
X102456Y393756D03*
X76052Y420935D03*
X78000Y423100D03*
X80100Y425000D03*
X81500Y427400D03*
X79700Y409700D03*
X77400Y407800D03*
X81500Y412100D03*
X84913Y434471D03*
X87013Y436371D03*
X107571Y406291D03*
X48806Y638753D03*
X75206D03*
X106006D03*
X70806D03*
X53206D03*
X66406D03*
X92806D03*
X97206D03*
X101606D03*
X57606D03*
X62006D03*
X79606D03*
X84006D03*
X88406D03*
X53221Y660756D03*
X101621D03*
X97221D03*
X92821D03*
X106021D03*
X48821D03*
X70821D03*
X66421D03*
X62021D03*
X57621D03*
X75221D03*
X88421D03*
X84021D03*
X79621D03*
X167921Y-58764D03*
X162921D03*
X157921D03*
X152921D03*
X147921D03*
X142921D03*
X137921D03*
X132921D03*
X127921D03*
X122921D03*
X117921D03*
X112921D03*
X162921Y-35764D03*
X157921D03*
X152921D03*
X147921D03*
X142921D03*
X137921D03*
X132921D03*
X127921D03*
X122921D03*
X117921D03*
X112921D03*
X167921D03*
X166000Y212900D03*
X168600D03*
X164300Y207870D03*
X160800Y212900D03*
X163400D03*
X157800Y207300D03*
X161216Y209533D03*
Y206933D03*
X154500Y205500D03*
X150600Y212900D03*
X151000Y205500D03*
X140889Y211972D03*
X137615Y212039D03*
X143900Y204600D03*
X147500Y205500D03*
X137300Y204500D03*
X140200Y204400D03*
X153200Y212900D03*
X122044Y162340D03*
X139815Y268974D03*
X137900Y272800D03*
X139800Y237000D03*
X165825Y239543D03*
X168425Y236943D03*
Y239543D03*
X165825Y236943D03*
X163225D03*
X152825D03*
X145025D03*
X147625D03*
X150225D03*
X142425D03*
X163225Y239543D03*
X158025Y236943D03*
X155425D03*
X160625D03*
X142371Y244384D03*
X142466Y268982D03*
X142700Y276200D03*
X136729Y276386D03*
X139683Y276174D03*
X163225Y242143D03*
X168425Y244743D03*
X165825D03*
X163225D03*
X168425Y242143D03*
X165825D03*
X150700Y276800D03*
X169150Y259470D03*
Y255470D03*
X157633Y268727D03*
X162833D03*
X160233D03*
X165433D03*
X168033Y271327D03*
X162833Y276527D03*
Y273927D03*
Y271327D03*
X165433Y276527D03*
Y273927D03*
Y271327D03*
X159983Y276507D03*
X168033Y276527D03*
Y273927D03*
Y268727D03*
X153300Y276800D03*
X139866Y333016D03*
X160233Y306257D03*
Y308857D03*
Y303657D03*
X157518Y335391D03*
X157745Y332800D03*
X139900Y302400D03*
X142433Y301057D03*
X147633D03*
X150233D03*
X145033D03*
X145200Y341300D03*
X148200D03*
X142465Y332940D03*
X152833Y301057D03*
X163233Y306257D03*
Y308857D03*
X168433Y306257D03*
Y308857D03*
Y301057D03*
X165833D03*
X163233D03*
X160633D03*
X158033D03*
X155433D03*
X169150Y287600D03*
Y291600D03*
X165833Y306257D03*
X163233Y303657D03*
X168433D03*
X165833D03*
Y308857D03*
X151000Y341300D03*
X169150Y323600D03*
Y319600D03*
X160501Y332965D03*
X160274Y335556D03*
X165701Y338165D03*
Y335565D03*
X163101Y332965D03*
X168301D03*
X165701D03*
X163101Y335565D03*
X168301Y340765D03*
Y338165D03*
Y335565D03*
X163101Y338165D03*
Y340765D03*
X165701D03*
X154200Y341100D03*
X139767Y364883D03*
X147833Y364457D03*
X142421Y364908D03*
X145033Y364457D03*
X142863Y402829D03*
X140219Y402894D03*
X137619Y402900D03*
X134992D03*
X142818Y400163D03*
X143073Y397194D03*
X140475Y397310D03*
X140218Y400163D03*
X137529Y400296D03*
X134929D03*
X114084Y399937D03*
X122840Y400827D03*
X150633Y364457D03*
X167433Y369657D03*
X169150Y355600D03*
Y351600D03*
X167700Y363900D03*
X161833Y364457D03*
X164633D03*
X159033D03*
X156233D03*
X153433D03*
X164633Y369657D03*
X161833D03*
X161933Y372357D03*
X164733D03*
X167533D03*
X166340Y374785D03*
X167670Y383993D03*
Y387993D03*
X130613Y429647D03*
X123648Y425041D03*
X125328Y427269D03*
X127932Y428571D03*
X110519Y410307D03*
X110199Y413852D03*
X110406Y638753D03*
X145606D03*
X141206D03*
X136806D03*
X132406D03*
X158806D03*
X119206D03*
X123606D03*
X114806D03*
X128006D03*
X163206D03*
X154406D03*
X167606D03*
X150006D03*
X132421Y660756D03*
X145621D03*
X141221D03*
X136821D03*
X123621D03*
X114821D03*
X128021D03*
X110421D03*
X119221D03*
X150021D03*
X167621D03*
X163221D03*
X158821D03*
X154421D03*
X182921Y-58764D03*
X177921D03*
X172921D03*
X227921Y-35764D03*
X222921D03*
X217921D03*
X212921D03*
X207921D03*
X202921D03*
X197921D03*
X192921D03*
X187921D03*
X182921D03*
X177921D03*
X227921Y-58764D03*
X222921D03*
X217921D03*
X212921D03*
X207921D03*
X202921D03*
X197921D03*
X192921D03*
X187921D03*
X172921Y-35764D03*
X211606Y638753D03*
X224806D03*
X220406D03*
X216006D03*
X189606D03*
X198406D03*
X202806D03*
X207206D03*
X176406D03*
X172006D03*
X185206D03*
X180806D03*
X194006D03*
X226500Y649900D03*
X229206Y638753D03*
X224821Y660756D03*
X220421D03*
X198421D03*
X211621D03*
X189621D03*
X202821D03*
X207221D03*
X194021D03*
X185221D03*
X172021D03*
X176421D03*
X180821D03*
X229221D03*
X216021D03*
X292921Y-35764D03*
X287921D03*
X282921D03*
X277921D03*
X272921D03*
X267921D03*
X262921D03*
X257921D03*
X252921D03*
X247921D03*
X242921D03*
X237921D03*
X232921D03*
X292921Y-58764D03*
X287921D03*
X282921D03*
X277921D03*
X272921D03*
X267921D03*
X262921D03*
X257921D03*
X252921D03*
X247921D03*
X242921D03*
X237921D03*
X232921D03*
X290806Y638753D03*
X268806D03*
X273206D03*
X277606D03*
X282006D03*
X260006D03*
X264406D03*
X255606D03*
X251206D03*
X286406D03*
X242406D03*
X246806D03*
X233606D03*
X238006D03*
X286421Y660756D03*
X268821D03*
X282021D03*
X273221D03*
X277621D03*
X264421D03*
X251221D03*
X255621D03*
X260021D03*
X246821D03*
X242421D03*
X238021D03*
X233621D03*
X290821D03*
X352921Y-58764D03*
Y-35764D03*
X347921Y-58764D03*
Y-35764D03*
X342921Y-58764D03*
Y-35764D03*
X337921Y-58764D03*
Y-35764D03*
X332921Y-58764D03*
Y-35764D03*
X327921Y-58764D03*
Y-35764D03*
X322921Y-58764D03*
Y-35764D03*
X317921Y-58764D03*
Y-35764D03*
X312921Y-58764D03*
X307921D03*
Y-35764D03*
X302921Y-58764D03*
Y-35764D03*
X297921D03*
Y-58764D03*
X312921Y-35764D03*
X330406Y638753D03*
X348006D03*
X326006D03*
X312806D03*
X317206D03*
X321606D03*
X352406D03*
X295206D03*
X299606D03*
X308406D03*
X304006D03*
X334806D03*
X339206D03*
X343606D03*
X312821Y660756D03*
X317221D03*
X308421D03*
X304021D03*
X352421D03*
X295221D03*
X326021D03*
X321621D03*
X339221D03*
X299621D03*
X334821D03*
X330421D03*
X343621D03*
X348021D03*
X392921Y-35764D03*
X387921Y-58764D03*
Y-35764D03*
X382921Y-58764D03*
Y-35764D03*
X377921Y-58764D03*
Y-35764D03*
X372921Y-58764D03*
Y-35764D03*
X367921Y-58764D03*
Y-35764D03*
X362921Y-58764D03*
Y-35764D03*
X357921Y-58764D03*
Y-35764D03*
X392921Y-58764D03*
X402921Y-35764D03*
X397921Y-58764D03*
Y-35764D03*
X412921Y-58764D03*
Y-35764D03*
X407921Y-58764D03*
Y-35764D03*
X402921Y-58764D03*
X380885Y273876D03*
Y270876D03*
X382494Y278904D03*
X371094D03*
X378294D03*
X375294D03*
X368094D03*
X389694D03*
X392694D03*
X385945Y278480D03*
X407094Y278910D03*
X414207D03*
X411288D03*
X404094D03*
X400842Y278914D03*
X368094Y295904D03*
X371094D03*
X385494D03*
X375294D03*
X378294D03*
X382494D03*
X389694D03*
X392694D03*
X365693Y311893D03*
X391144Y324173D03*
X388394D03*
X385494D03*
X411294Y295904D03*
X414294D03*
X407094D03*
X404094D03*
X399894D03*
X396894D03*
Y324173D03*
X408894D03*
X411894D03*
X405894D03*
X414894D03*
X393894D03*
X402894D03*
X399894D03*
X383206Y638753D03*
X387606D03*
X392006D03*
X396406D03*
X400806D03*
X405206D03*
X409606D03*
X414006D03*
X370006D03*
X365606D03*
X374406D03*
X378806D03*
X356806D03*
X361206D03*
X374421Y660756D03*
X387621D03*
X383221D03*
X400821D03*
X396421D03*
X392021D03*
X405221D03*
X409621D03*
X414021D03*
X361221D03*
X365621D03*
X356821D03*
X370021D03*
X378821D03*
X477921Y-58764D03*
Y-35764D03*
X472921Y-58764D03*
Y-35764D03*
X467921Y-58764D03*
Y-35764D03*
X462921Y-58764D03*
Y-35764D03*
X457921Y-58764D03*
Y-35764D03*
X452921Y-58764D03*
Y-35764D03*
X447921Y-58764D03*
Y-35764D03*
X442921Y-58764D03*
Y-35764D03*
X437921Y-58764D03*
Y-35764D03*
X432921Y-58764D03*
X422921Y-35764D03*
X417921Y-58764D03*
Y-35764D03*
X432921D03*
X427921Y-58764D03*
Y-35764D03*
X422921Y-58764D03*
X432643Y264508D03*
X418523Y278910D03*
X428694D03*
X432894D03*
X425694D03*
X435894Y278938D03*
X443094Y278904D03*
X440094D03*
X421523Y278944D03*
X451675Y291739D03*
X449148Y292841D03*
X446209Y292842D03*
X451816Y295904D03*
X435894D03*
X418494D03*
X443094D03*
X440094D03*
X446383Y295841D03*
X428694Y295904D03*
X432894D03*
X425694D03*
X421494D03*
X418494Y324173D03*
X451267Y324476D03*
X448694Y323949D03*
X421494Y324173D03*
X446094Y323904D03*
X425694Y324173D03*
X428694D03*
X432894D03*
X435894D03*
X455226Y291686D03*
X454922Y295841D03*
X466806Y638753D03*
X462406D03*
X475606D03*
X471206D03*
X418406D03*
X422806D03*
X427206D03*
X440406D03*
X436006D03*
X431606D03*
X449206D03*
X458006D03*
X453606D03*
X444806D03*
X458021Y660756D03*
X449221D03*
X462421D03*
X466821D03*
X471221D03*
X418421D03*
X475621D03*
X453621D03*
X422821D03*
X427221D03*
X440421D03*
X431621D03*
X436021D03*
X444821D03*
X537921Y-58764D03*
Y-35764D03*
X532921Y-58764D03*
Y-35764D03*
X527921Y-58764D03*
Y-35764D03*
X522921Y-58764D03*
Y-35764D03*
X517921Y-58764D03*
Y-35764D03*
X512921Y-58764D03*
Y-35764D03*
X507921Y-58764D03*
Y-35764D03*
X502921Y-58764D03*
Y-35764D03*
X497921Y-58764D03*
Y-35764D03*
X492921Y-58764D03*
Y-35764D03*
X487921Y-58764D03*
Y-35764D03*
X482921Y-58764D03*
Y-35764D03*
X480006Y638753D03*
X484406D03*
X488806D03*
X493206D03*
X497606D03*
X510806D03*
X537206D03*
X519606D03*
X524006D03*
X532806D03*
X528406D03*
X515206D03*
X502006D03*
X506406D03*
X524021Y660756D03*
X480021D03*
X484421D03*
X497621D03*
X493221D03*
X488821D03*
X519621D03*
X532821D03*
X537221D03*
X528421D03*
X515221D03*
X510821D03*
X506421D03*
X502021D03*
X597921Y-35764D03*
Y-58764D03*
X592921Y-35764D03*
Y-58764D03*
X587921Y-35764D03*
Y-58764D03*
X582921Y-35764D03*
Y-58764D03*
X577921Y-35764D03*
Y-58764D03*
X572921Y-35764D03*
Y-58764D03*
X567921Y-35764D03*
Y-58764D03*
X562921Y-35764D03*
Y-58764D03*
X557921Y-35764D03*
Y-58764D03*
X552921Y-35764D03*
Y-58764D03*
X547921D03*
Y-35764D03*
X542921Y-58764D03*
Y-35764D03*
X590006Y638753D03*
X572406D03*
X559206D03*
X568006D03*
X563606D03*
X550406D03*
X581206D03*
X585606D03*
X576806D03*
X598806D03*
X594406D03*
X601500Y649500D03*
X554806Y638753D03*
X541606D03*
X546006D03*
X559221Y660756D03*
X546021D03*
X554821D03*
X598821D03*
X572421D03*
X568021D03*
X563621D03*
X585621D03*
X541621D03*
X594421D03*
X576821D03*
X590021D03*
X581221D03*
X550421D03*
X637921Y-58764D03*
X632921Y-35764D03*
Y-58764D03*
X627921Y-35764D03*
Y-58764D03*
X622921Y-35764D03*
Y-58764D03*
X617921Y-35764D03*
Y-58764D03*
X612921Y-35764D03*
Y-58764D03*
X607921Y-35764D03*
Y-58764D03*
X602921Y-35764D03*
Y-58764D03*
X652921Y-35764D03*
Y-58764D03*
X647921Y-35764D03*
Y-58764D03*
X642921Y-35764D03*
Y-58764D03*
X637921Y-35764D03*
X662921D03*
Y-58764D03*
X657921Y-35764D03*
Y-58764D03*
X638406Y638753D03*
X634006D03*
X642806D03*
X629606D03*
X616406D03*
X612006D03*
X603206D03*
X625206D03*
X651606D03*
X647206D03*
X660406D03*
X620806D03*
X656006D03*
X607606D03*
X607621Y660756D03*
X638421D03*
X647221D03*
X616421D03*
X634021D03*
X612021D03*
X620821D03*
X625221D03*
X629621D03*
X642821D03*
X603221D03*
X656021D03*
X660421D03*
X651621D03*
X692921Y-58764D03*
X687921Y-35764D03*
Y-58764D03*
X682921Y-35764D03*
Y-58764D03*
X677921Y-35764D03*
Y-58764D03*
X672921Y-35764D03*
Y-58764D03*
X667921Y-35764D03*
Y-58764D03*
X697921Y-35764D03*
Y-58764D03*
X692921Y-35764D03*
X722921D03*
Y-58764D03*
X717921Y-35764D03*
Y-58764D03*
X712921Y-35764D03*
Y-58764D03*
X707921Y-35764D03*
Y-58764D03*
X702921Y-35764D03*
Y-58764D03*
X704466Y-7874D03*
X690966Y-21374D03*
X700525Y1668D03*
X700517Y-17425D03*
X681713Y-17927D03*
X690966Y5626D03*
X681714Y2178D03*
X673864Y-16889D03*
X667566Y-7874D03*
X673864Y1139D03*
X695606Y638753D03*
X673606D03*
X708806D03*
X704406D03*
X700006D03*
X722006D03*
X717606D03*
X713206D03*
X664806D03*
X669206D03*
X686806D03*
X682406D03*
X678006D03*
X691206D03*
X690966Y624130D03*
Y597130D03*
X700525Y620172D03*
X700517Y601079D03*
X704466Y610630D03*
X667566D03*
X673864Y619643D03*
Y601615D03*
X681714Y620682D03*
X681713Y600577D03*
X664821Y660756D03*
X695621D03*
X708821D03*
X700021D03*
X704421D03*
X669221D03*
X686821D03*
X691221D03*
X678021D03*
X673621D03*
X682421D03*
X722021D03*
X717621D03*
X713221D03*
X777921Y-58764D03*
X772921Y-35764D03*
Y-58764D03*
X767921Y-35764D03*
Y-58764D03*
X762921Y-35764D03*
Y-58764D03*
X757921Y-35764D03*
Y-58764D03*
X752921Y-35764D03*
Y-58764D03*
X787921Y-35764D03*
Y-58764D03*
X782921Y-35764D03*
Y-58764D03*
X777921Y-35764D03*
X747921D03*
Y-58764D03*
X742921Y-35764D03*
Y-58764D03*
X737921Y-35764D03*
Y-58764D03*
X732921Y-35764D03*
Y-58764D03*
X727921Y-35764D03*
Y-58764D03*
X786674Y211463D03*
X785920Y204763D03*
X786300Y207400D03*
X787200Y244200D03*
Y271900D03*
X787100Y241100D03*
X773419Y270414D03*
X787200Y276400D03*
X787100Y303900D03*
X753098Y338316D03*
X744698Y332816D03*
X787000Y308300D03*
X787400Y340400D03*
X741774Y376463D03*
X785400Y372400D03*
X757500Y374000D03*
X770406Y638753D03*
X779206D03*
X774806D03*
X730806D03*
X726406D03*
X739606D03*
X735206D03*
X748406D03*
X744006D03*
X766006D03*
X761606D03*
X757206D03*
X752806D03*
X783606D03*
X744021Y660756D03*
X735221D03*
X779221D03*
X770421D03*
X774821D03*
X726421D03*
X730821D03*
X739621D03*
X748421D03*
X783621D03*
X757221D03*
X761621D03*
X752821D03*
X766021D03*
X842921Y-35764D03*
X837921Y-58764D03*
Y-35764D03*
X832921Y-58764D03*
X847921D03*
Y-35764D03*
X842921Y-58764D03*
X832921Y-35764D03*
X827921Y-58764D03*
Y-35764D03*
X822921Y-58764D03*
Y-35764D03*
X817921Y-58764D03*
Y-35764D03*
X812921Y-58764D03*
Y-35764D03*
X807921Y-58764D03*
Y-35764D03*
X802921Y-58764D03*
Y-35764D03*
X797921D03*
Y-58764D03*
X792921Y-35764D03*
Y-58764D03*
X816900Y216300D03*
X816874Y212863D03*
X814274D03*
X811674D03*
X808818Y211179D03*
X808618Y208579D03*
X803200Y213100D03*
X800600D03*
X794474Y211463D03*
X791874D03*
X789274D03*
X788522Y204343D03*
X791122Y204339D03*
X789432Y236947D03*
X789400Y273700D03*
X811983Y244843D03*
Y242243D03*
X814583Y239643D03*
X815432Y237000D03*
X814583Y244843D03*
Y242243D03*
X812832Y237000D03*
X811983Y239643D03*
X802432Y237000D03*
X799832D03*
X792032D03*
X794632D03*
X810232D03*
X797232D03*
X805032D03*
X807632D03*
X791000Y244400D03*
X793600D03*
X816800Y234300D03*
X816900Y230900D03*
X817000Y252500D03*
X789800Y276400D03*
X792400D03*
X801991Y276557D03*
X804591D03*
X792191Y269101D03*
X789591D03*
X814891Y271657D03*
Y274257D03*
Y276857D03*
Y269057D03*
X812291D03*
Y274257D03*
Y276857D03*
Y271657D03*
X817000Y255100D03*
Y257700D03*
X817491Y276857D03*
Y274257D03*
Y271657D03*
Y269057D03*
X817183Y242243D03*
Y239643D03*
Y244843D03*
X818032Y237000D03*
X788600Y306100D03*
X789500Y301200D03*
X797300D03*
X799900D03*
X810300D03*
X802500D03*
X812900D03*
X807700D03*
X805100D03*
X815500D03*
X811991Y308957D03*
Y306357D03*
Y303757D03*
X814591Y306357D03*
Y308957D03*
Y303757D03*
X792900Y308400D03*
X789900D03*
X794700Y301200D03*
X792100D03*
X793000Y340400D03*
X790300Y340300D03*
X816991Y337357D03*
Y334757D03*
Y339957D03*
X814391D03*
Y337357D03*
Y334757D03*
X811791Y337357D03*
Y339957D03*
Y334757D03*
X791879Y332798D03*
X794600Y332600D03*
X816938Y319888D03*
Y323888D03*
X817100Y317000D03*
X818100Y301200D03*
X817191Y303757D03*
Y306357D03*
Y308957D03*
X789860Y364947D03*
X816591Y369857D03*
Y372457D03*
X811391Y369857D03*
X813991D03*
Y372457D03*
X811391D03*
X790900Y372300D03*
X788300Y372400D03*
X802759Y364575D03*
X816672Y358809D03*
X795310Y364721D03*
X816593Y356210D03*
X807959Y364575D03*
X805359D03*
X810559D03*
X815759D03*
X813159D03*
X816900Y361400D03*
X792610Y364821D03*
X816591Y375057D03*
X792238Y396753D03*
X789600Y396809D03*
X811515Y397289D03*
X808915D03*
X813648Y395557D03*
X815472Y390442D03*
X814877Y393138D03*
X792000Y399409D03*
X789400D03*
X849606Y638753D03*
X836406D03*
X832006D03*
X796806D03*
X801206D03*
X792406D03*
X827606D03*
X818806D03*
X823206D03*
X810006D03*
X788006D03*
X845206D03*
X814406D03*
X805606D03*
X840806D03*
X849621Y660756D03*
X832021D03*
X810021D03*
X818821D03*
X836421D03*
X788021D03*
X814421D03*
X801221D03*
X805621D03*
X823221D03*
X827621D03*
X840821D03*
X796821D03*
X792421D03*
X845221D03*
X907921Y-58764D03*
Y-35764D03*
X902921Y-58764D03*
Y-35764D03*
X897921Y-58764D03*
Y-35764D03*
X892921Y-58764D03*
Y-35764D03*
X887921Y-58764D03*
Y-35764D03*
X882921Y-58764D03*
Y-35764D03*
X877921Y-58764D03*
Y-35764D03*
X872921Y-58764D03*
Y-35764D03*
X867921Y-58764D03*
Y-35764D03*
X862921Y-58764D03*
Y-35764D03*
X857921Y-58764D03*
Y-35764D03*
X852921Y-58764D03*
Y-35764D03*
X858406Y638753D03*
X854006D03*
X884806D03*
X880406D03*
X876006D03*
X871606D03*
X867206D03*
X911206D03*
X906806D03*
X889206D03*
X898006D03*
X902406D03*
X893606D03*
X862806D03*
X854021Y660756D03*
X858421D03*
X862821D03*
X898021D03*
X902421D03*
X871621D03*
X884821D03*
X893621D03*
X867221D03*
X889221D03*
X911221D03*
X906821D03*
X880421D03*
X876021D03*
X937921Y-35764D03*
X932921Y-58764D03*
Y-35764D03*
X927921Y-58764D03*
Y-35764D03*
X922921Y-58764D03*
Y-35764D03*
X917921Y-58764D03*
Y-35764D03*
X912921Y-58764D03*
Y-35764D03*
X942921D03*
X967921D03*
X962921Y-58764D03*
Y-35764D03*
X957921Y-58764D03*
Y-35764D03*
X952921Y-58764D03*
Y-35764D03*
X947921Y-58764D03*
Y-35764D03*
X942921Y-58764D03*
X972921D03*
Y-35764D03*
X967921Y-58764D03*
X937921D03*
X924406Y638753D03*
X920006D03*
X915606D03*
X972806D03*
X968406D03*
X964006D03*
X917100Y649300D03*
X942006Y638753D03*
X937606D03*
X933206D03*
X928806D03*
X959606D03*
X955206D03*
X950806D03*
X946406D03*
X959621Y660756D03*
X964021D03*
X968421D03*
X972821D03*
X920021D03*
X915621D03*
X924421D03*
X946421D03*
X942021D03*
X937621D03*
X933221D03*
X928821D03*
X955221D03*
X950821D03*
X1002921Y-58764D03*
Y-35764D03*
X997921Y-58764D03*
Y-35764D03*
X992921Y-58764D03*
Y-35764D03*
X987921Y-58764D03*
Y-35764D03*
X982921Y-58764D03*
Y-35764D03*
X977921Y-58764D03*
Y-35764D03*
X1032921Y-58764D03*
Y-35764D03*
X1027921Y-58764D03*
Y-35764D03*
X1022921Y-58764D03*
Y-35764D03*
X1017921Y-58764D03*
Y-35764D03*
X1012921Y-58764D03*
Y-35764D03*
X1007921Y-58764D03*
Y-35764D03*
X1030489Y270889D03*
Y273889D03*
X1027902Y278904D03*
X1020702D03*
X1017702D03*
X1024902D03*
X1032102D03*
X1017567Y295859D03*
X1024767D03*
X1020567D03*
X1031967D03*
X1027767D03*
X1015293Y311955D03*
X1003606Y638753D03*
X1012406D03*
X977206D03*
X990406D03*
X986006D03*
X994806D03*
X1016806D03*
X1021206D03*
X981606D03*
X999206D03*
X1025606D03*
X1008006D03*
X1030006D03*
X1034406D03*
X999221Y660756D03*
X1034421D03*
X1030021D03*
X1008021D03*
X1012421D03*
X1003621D03*
X1016821D03*
X977221D03*
X981621D03*
X1021221D03*
X1025621D03*
X994821D03*
X986021D03*
X990421D03*
X1067921Y-58764D03*
Y-35764D03*
X1062921Y-58764D03*
Y-35764D03*
X1057921Y-58764D03*
Y-35764D03*
X1052921Y-58764D03*
Y-35764D03*
X1047921Y-58764D03*
Y-35764D03*
X1042921Y-58764D03*
Y-35764D03*
X1037921Y-58764D03*
Y-35764D03*
X1092921Y-58764D03*
Y-35764D03*
X1087921Y-58764D03*
Y-35764D03*
X1082921Y-58764D03*
Y-35764D03*
X1077921Y-58764D03*
Y-35764D03*
X1072921Y-58764D03*
Y-35764D03*
X1042302Y278904D03*
X1039302D03*
X1056602Y278910D03*
X1035814Y278775D03*
X1049867Y278999D03*
X1053459Y278910D03*
X1060958D03*
X1075302D03*
X1078302D03*
X1082330D03*
X1070926D03*
X1063652D03*
X1067783D03*
X1082432Y264620D03*
X1085518Y278910D03*
X1089702Y278904D03*
X1039167Y295859D03*
X1042167D03*
X1034967D03*
X1046367D03*
X1056567D03*
X1049367D03*
X1053567D03*
X1038720Y324174D03*
X1044220D03*
X1035820D03*
X1050220D03*
X1047220D03*
X1053220D03*
X1056220D03*
X1041470D03*
X1059220D03*
X1060767Y295859D03*
X1095756Y292841D03*
X1082367Y295859D03*
X1085367D03*
X1075167D03*
X1078167D03*
X1089567D03*
X1092567D03*
X1095567Y295841D03*
X1070967Y295859D03*
X1063767D03*
X1067967D03*
X1062220Y324174D03*
X1095402Y323904D03*
X1083220Y324174D03*
X1076020D03*
X1079020D03*
X1071820D03*
X1065220D03*
X1068820D03*
X1096006Y638753D03*
X1078406D03*
X1082806D03*
X1074006D03*
X1069606D03*
X1091606D03*
X1052006D03*
X1038806D03*
X1087206D03*
X1060806D03*
X1056406D03*
X1065206D03*
X1043206D03*
X1047606D03*
X1078421Y660756D03*
X1060821D03*
X1087221D03*
X1038821D03*
X1091621D03*
X1052021D03*
X1074021D03*
X1065221D03*
X1096021D03*
X1056421D03*
X1043221D03*
X1047621D03*
X1082821D03*
X1069621D03*
X1157921Y-58764D03*
Y-35764D03*
X1152921Y-58764D03*
Y-35764D03*
X1147921Y-58764D03*
Y-35764D03*
X1142921Y-58764D03*
Y-35764D03*
X1137921Y-58764D03*
Y-35764D03*
X1132921Y-58764D03*
Y-35764D03*
X1127921Y-58764D03*
Y-35764D03*
X1122921Y-58764D03*
Y-35764D03*
X1117921Y-58764D03*
Y-35764D03*
X1112921Y-58764D03*
Y-35764D03*
X1107921Y-58764D03*
Y-35764D03*
X1102921Y-58764D03*
Y-35764D03*
X1097921Y-58764D03*
Y-35764D03*
X1104256Y291841D03*
X1101615Y292447D03*
X1098756Y292841D03*
X1101567Y295859D03*
X1104221Y295696D03*
X1098567Y295841D03*
X1112490Y312723D03*
X1112515Y315369D03*
X1101200Y324013D03*
X1098402Y324017D03*
X1135606Y638753D03*
X1126806D03*
X1144406D03*
X1140006D03*
X1118006D03*
X1122406D03*
X1153206D03*
X1157606D03*
X1104806D03*
X1100406D03*
X1131206D03*
X1148806D03*
X1109206D03*
X1113606D03*
X1157621Y660756D03*
X1148821D03*
X1122421D03*
X1126821D03*
X1100421D03*
X1118021D03*
X1140021D03*
X1113621D03*
X1109221D03*
X1153221D03*
X1144421D03*
X1104821D03*
X1131221D03*
X1135621D03*
X1217921Y-58764D03*
Y-35764D03*
X1212921Y-58764D03*
Y-35764D03*
X1207921Y-58764D03*
Y-35764D03*
X1202921Y-58764D03*
Y-35764D03*
X1197921Y-58764D03*
Y-35764D03*
X1192921Y-58764D03*
Y-35764D03*
X1187921Y-58764D03*
Y-35764D03*
X1182921Y-58764D03*
Y-35764D03*
X1177921Y-58764D03*
Y-35764D03*
X1172921Y-58764D03*
Y-35764D03*
X1167921Y-58764D03*
Y-35764D03*
X1162921Y-58764D03*
Y-35764D03*
X1188406Y638753D03*
X1214806D03*
X1197206D03*
X1201606D03*
X1192806D03*
X1170806D03*
X1162006D03*
X1166406D03*
X1206006D03*
X1219206D03*
X1179606D03*
X1175206D03*
X1210406D03*
X1184006D03*
X1184021Y660756D03*
X1219221D03*
X1192821D03*
X1188421D03*
X1201621D03*
X1179621D03*
X1214821D03*
X1206021D03*
X1166421D03*
X1210421D03*
X1170821D03*
X1162021D03*
X1175221D03*
X1197221D03*
X1232921Y-58764D03*
Y-35764D03*
X1227921Y-58764D03*
Y-35764D03*
X1222921Y-58764D03*
Y-35764D03*
X1252921Y-58764D03*
Y-35764D03*
X1247921Y-58764D03*
Y-35764D03*
X1242921Y-58764D03*
Y-35764D03*
X1237921Y-58764D03*
Y-35764D03*
X1257921D03*
X1272921Y-58764D03*
Y-35764D03*
X1267921Y-58764D03*
Y-35764D03*
X1262921Y-58764D03*
Y-35764D03*
X1257921Y-58764D03*
X1277921D03*
Y-35764D03*
X1263206Y638753D03*
X1223606D03*
X1228006D03*
X1258806D03*
X1241206D03*
X1236806D03*
X1250006D03*
X1245606D03*
X1276406D03*
X1254406D03*
X1280806D03*
X1272006D03*
X1267606D03*
X1232406D03*
X1228021Y660756D03*
X1232421D03*
X1280821D03*
X1245621D03*
X1236821D03*
X1223621D03*
X1276421D03*
X1241221D03*
X1272021D03*
X1258821D03*
X1250021D03*
X1254421D03*
X1263221D03*
X1267621D03*
X1342921Y-35764D03*
Y-58764D03*
X1317921D03*
X1312921Y-35764D03*
Y-58764D03*
X1307921Y-35764D03*
Y-58764D03*
X1302921Y-35764D03*
Y-58764D03*
X1297921D03*
Y-35764D03*
X1292921Y-58764D03*
Y-35764D03*
X1287921Y-58764D03*
Y-35764D03*
X1282921Y-58764D03*
Y-35764D03*
X1322921D03*
Y-58764D03*
X1317921Y-35764D03*
X1337921D03*
Y-58764D03*
X1332921Y-35764D03*
Y-58764D03*
X1327921Y-35764D03*
Y-58764D03*
X1324806Y638753D03*
X1298406D03*
X1285206D03*
X1294006D03*
X1302806D03*
X1333606D03*
X1338006D03*
X1320406D03*
X1311606D03*
X1329206D03*
X1307206D03*
X1342406D03*
X1289606D03*
X1316006D03*
X1329221Y660756D03*
X1311621D03*
X1316021D03*
X1333621D03*
X1342421D03*
X1285221D03*
X1324821D03*
X1338021D03*
X1298421D03*
X1289621D03*
X1294021D03*
X1320421D03*
X1302821D03*
X1307221D03*
X1402921Y-58764D03*
X1397921D03*
X1402921Y-35764D03*
X1392921Y-58764D03*
X1397921Y-35764D03*
X1387921Y-58764D03*
X1392921Y-35764D03*
X1382921Y-58764D03*
X1387921Y-35764D03*
X1377921Y-58764D03*
X1382921Y-35764D03*
X1372921Y-58764D03*
X1377921Y-35764D03*
X1367921Y-58764D03*
X1362921Y-35764D03*
Y-58764D03*
X1357921Y-35764D03*
Y-58764D03*
X1352921Y-35764D03*
Y-58764D03*
X1347921Y-35764D03*
Y-58764D03*
X1395913Y-7874D03*
X1402211Y1139D03*
Y-16889D03*
X1351206Y638753D03*
X1360006D03*
X1404506Y638853D03*
X1355606Y638753D03*
X1386906Y638853D03*
X1364406Y638753D03*
X1391306Y638853D03*
X1346806Y638753D03*
X1400106Y638853D03*
X1382006Y638753D03*
X1377606D03*
X1373206D03*
X1395706Y638853D03*
X1368806Y638753D03*
X1402211Y601615D03*
Y619643D03*
X1395913Y610630D03*
X1368821Y660756D03*
X1346821D03*
X1355621D03*
X1360021D03*
X1364421D03*
X1351221D03*
X1404521Y660856D03*
X1400121D03*
X1395721D03*
X1386921D03*
X1377621Y660756D03*
X1382021D03*
X1373221D03*
X1391321Y660856D03*
X1407921Y-58764D03*
X1412921Y-35764D03*
X1407921D03*
X1442921Y-58764D03*
X1447921Y-35764D03*
X1437921Y-58764D03*
X1442921Y-35764D03*
X1432921Y-58764D03*
X1437921Y-35764D03*
X1427921Y-58764D03*
X1432921Y-35764D03*
X1422921Y-58764D03*
X1427921Y-35764D03*
X1417921Y-58764D03*
X1422921Y-35764D03*
X1412921Y-58764D03*
X1417921Y-35764D03*
X1462921Y-58764D03*
X1457921D03*
X1462921Y-35764D03*
X1452921Y-58764D03*
X1457921Y-35764D03*
X1447921Y-58764D03*
X1452921Y-35764D03*
X1410061Y2178D03*
X1410060Y-17927D03*
X1419313Y5626D03*
Y-21374D03*
X1428872Y1668D03*
X1428864Y-17425D03*
X1432813Y-7874D03*
X1422106Y638853D03*
X1466106D03*
X1448506D03*
X1457306D03*
X1417706D03*
X1413306D03*
X1461706D03*
X1452906D03*
X1408906D03*
X1444106D03*
X1435306D03*
X1426506D03*
X1430906D03*
X1439706D03*
X1432813Y610630D03*
X1428864Y601079D03*
X1428872Y620172D03*
X1419313Y597130D03*
Y624130D03*
X1410060Y600577D03*
X1410061Y620682D03*
X1457321Y660856D03*
X1417721D03*
X1413321D03*
X1408921D03*
X1422121D03*
X1426521D03*
X1435321D03*
X1444121D03*
X1439721D03*
X1430921D03*
X1448521D03*
X1452921D03*
X1466121D03*
X1461721D03*
X1502921Y-58764D03*
X1507921Y-35764D03*
X1497921Y-58764D03*
X1502921Y-35764D03*
X1492921Y-58764D03*
X1497921Y-35764D03*
X1487921Y-58764D03*
X1492921Y-35764D03*
X1482921Y-58764D03*
X1487921Y-35764D03*
X1477921Y-58764D03*
X1482921Y-35764D03*
X1472921Y-58764D03*
X1477921Y-35764D03*
X1467921Y-58764D03*
X1472921Y-35764D03*
X1467921D03*
X1527921Y-58764D03*
X1522921D03*
X1527921Y-35764D03*
X1517921Y-58764D03*
X1522921Y-35764D03*
X1512921Y-58764D03*
X1517921Y-35764D03*
X1507921Y-58764D03*
X1512921Y-35764D03*
X1496906Y638853D03*
X1492506D03*
X1501706Y638753D03*
X1506106D03*
X1514906D03*
X1483706Y638853D03*
X1523706Y638753D03*
X1510506D03*
X1488106Y638853D03*
X1474906D03*
X1519306Y638753D03*
X1479306Y638853D03*
X1528106Y638753D03*
X1470506Y638853D03*
X1496921Y660856D03*
X1483721D03*
X1488121D03*
X1492521D03*
X1479321D03*
X1510521Y660756D03*
X1528121D03*
X1523721D03*
X1501721D03*
X1506121D03*
X1514921D03*
X1519321D03*
X1474921Y660856D03*
X1470521D03*
X1587921Y-58764D03*
X1582921D03*
X1587921Y-35764D03*
X1532921D03*
X1542921D03*
X1532921Y-58764D03*
X1537921Y-35764D03*
X1577921Y-58764D03*
X1582921Y-35764D03*
X1572921Y-58764D03*
X1577921Y-35764D03*
X1567921Y-58764D03*
X1572921Y-35764D03*
X1562921Y-58764D03*
X1567921Y-35764D03*
X1557921Y-58764D03*
X1562921Y-35764D03*
X1552921Y-58764D03*
X1557921Y-35764D03*
X1547921Y-58764D03*
X1552921Y-35764D03*
X1542921Y-58764D03*
X1547921Y-35764D03*
X1537921Y-58764D03*
X1580121Y647556D03*
X1555106Y638753D03*
X1555121Y647556D03*
X1590121D03*
X1590106Y638753D03*
X1590121Y643156D03*
X1585121Y647556D03*
X1585106Y638753D03*
X1585121Y643156D03*
X1565121Y647556D03*
X1570121Y643156D03*
X1570106Y638753D03*
X1565106D03*
X1565121Y643156D03*
X1570121Y647556D03*
X1560121D03*
X1560106Y638753D03*
X1560121Y643156D03*
X1575121D03*
X1575106Y638753D03*
X1575121Y647556D03*
X1555121Y643156D03*
X1580106Y638753D03*
X1580121Y643156D03*
X1550121Y647556D03*
X1541306Y638753D03*
X1545706D03*
X1550106D03*
X1550121Y643156D03*
X1536906Y638753D03*
X1532506D03*
X1565121Y651956D03*
X1570121Y660756D03*
Y656356D03*
X1565121Y660756D03*
X1555121Y651956D03*
X1590121Y660756D03*
Y656356D03*
Y651956D03*
X1585121Y660756D03*
Y656356D03*
Y651956D03*
X1580121Y660756D03*
Y656356D03*
Y651956D03*
X1560121Y660756D03*
Y656356D03*
Y651956D03*
X1555121Y660756D03*
Y656356D03*
X1570121Y651956D03*
X1575121D03*
Y656356D03*
Y660756D03*
X1565121Y656356D03*
X1550121Y651956D03*
Y656356D03*
X1541321Y660756D03*
X1550121D03*
X1545721D03*
X1532521D03*
X1536921D03*
X1642921Y-35764D03*
Y-58764D03*
X1637921Y-35764D03*
Y-58764D03*
X1632921Y-35764D03*
Y-58764D03*
X1627921D03*
X1622921D03*
X1627921Y-35764D03*
X1617921Y-58764D03*
X1622921Y-35764D03*
X1612921Y-58764D03*
X1617921Y-35764D03*
X1607921Y-58764D03*
X1612921Y-35764D03*
X1602921Y-58764D03*
X1607921Y-35764D03*
X1597921Y-58764D03*
X1602921Y-35764D03*
X1592921Y-58764D03*
X1597921Y-35764D03*
X1592921D03*
X1647921D03*
Y-58764D03*
X1625106Y638753D03*
X1625121Y647556D03*
X1630121Y643156D03*
X1630106Y638753D03*
X1630121Y647556D03*
X1635121Y643156D03*
X1635106Y638753D03*
X1635121Y647556D03*
X1640121Y643156D03*
Y647556D03*
X1640106Y638753D03*
X1650121Y647556D03*
X1650106Y638753D03*
X1650121Y643156D03*
X1645121Y647556D03*
X1645106Y638753D03*
X1645121Y643156D03*
X1625121D03*
X1620121Y647556D03*
X1620106Y638753D03*
X1620121Y643156D03*
X1615121Y647556D03*
X1615106Y638753D03*
X1615121Y643156D03*
X1610121Y647556D03*
X1610106Y638753D03*
X1610121Y643156D03*
X1605121Y647556D03*
X1605106Y638753D03*
X1605121Y643156D03*
X1600121Y647556D03*
X1600106Y638753D03*
X1600121Y643156D03*
X1595121Y647556D03*
X1595106Y638753D03*
X1595121Y643156D03*
X1625121Y651956D03*
Y660756D03*
X1630121Y651956D03*
Y656356D03*
Y660756D03*
X1635121Y651956D03*
Y656356D03*
Y660756D03*
X1625121Y656356D03*
X1640121D03*
Y651956D03*
X1650121Y660756D03*
Y656356D03*
Y651956D03*
X1645121Y660756D03*
Y656356D03*
Y651956D03*
X1640121Y660756D03*
X1620121D03*
Y656356D03*
Y651956D03*
X1615121Y660756D03*
Y656356D03*
Y651956D03*
X1610121Y660756D03*
Y656356D03*
Y651956D03*
X1605121Y660756D03*
Y656356D03*
Y651956D03*
X1600121Y660756D03*
Y656356D03*
Y651956D03*
X1595121Y660756D03*
Y656356D03*
Y651956D03*
X1692921Y-40764D03*
X1702921Y-54764D03*
X1687921D03*
X1682921D03*
X1677921D03*
X1672921D03*
X1692921D03*
X1697921D03*
X1707921D03*
X1712921D03*
X1697921Y-40764D03*
X1692921Y-50764D03*
X1687921D03*
X1682921D03*
X1677921D03*
X1672921D03*
X1712921D03*
X1707921D03*
X1702921D03*
X1697921Y-45764D03*
X1707921D03*
X1702921D03*
X1712921D03*
X1697921Y-50764D03*
X1667921Y-35764D03*
X1712921D03*
Y-58764D03*
X1707921Y-35764D03*
Y-58764D03*
X1702921Y-35764D03*
Y-58764D03*
X1697921Y-35764D03*
Y-58764D03*
X1687921Y-40764D03*
X1672921Y-45764D03*
X1677921D03*
X1682921D03*
Y-40764D03*
X1687921Y-45764D03*
X1692921D03*
X1667921Y-58764D03*
X1662921Y-35764D03*
Y-58764D03*
X1657921Y-35764D03*
Y-58764D03*
X1652921Y-35764D03*
Y-58764D03*
X1712921Y-40764D03*
X1707921D03*
X1702921D03*
X1677921D03*
X1672921D03*
X1677921Y-35764D03*
Y-58764D03*
X1672921Y-35764D03*
Y-58764D03*
X1682921Y-35764D03*
Y-58764D03*
X1692921Y-35764D03*
Y-58764D03*
X1687921Y-35764D03*
Y-58764D03*
X1690121Y647556D03*
X1710121D03*
X1710106Y638753D03*
X1710121Y643156D03*
X1705121Y647556D03*
X1705106Y638753D03*
X1695121Y643156D03*
X1695106Y638753D03*
X1695121Y647556D03*
X1700121Y643156D03*
X1700106Y638753D03*
X1685121Y647556D03*
X1685106Y638753D03*
X1685121Y643156D03*
X1680121Y647556D03*
X1680106Y638753D03*
X1680121Y643156D03*
X1675121Y647556D03*
X1675106Y638753D03*
X1675121Y643156D03*
X1670121Y647556D03*
X1670106Y638753D03*
X1670121Y643156D03*
X1665121Y647556D03*
X1665106Y638753D03*
X1665121Y643156D03*
X1660121Y647556D03*
X1660106Y638753D03*
X1660121Y643156D03*
X1655121Y647556D03*
X1655106Y638753D03*
X1655121Y643156D03*
X1690121D03*
X1690106Y638753D03*
X1700121Y647556D03*
X1705121Y643156D03*
X1690121Y656356D03*
Y651956D03*
X1710121Y660756D03*
Y656356D03*
Y651956D03*
X1705121Y660756D03*
Y656356D03*
Y651956D03*
X1690121Y660756D03*
X1695121Y651956D03*
Y656356D03*
Y660756D03*
X1685121Y651956D03*
X1680121Y660756D03*
Y656356D03*
Y651956D03*
X1675121Y660756D03*
Y656356D03*
Y651956D03*
X1670121Y660756D03*
Y656356D03*
Y651956D03*
X1665121Y660756D03*
Y656356D03*
Y651956D03*
X1660121Y660756D03*
Y656356D03*
Y651956D03*
X1655121Y660756D03*
Y656356D03*
Y651956D03*
X1685121Y660756D03*
Y656356D03*
X1700121Y651956D03*
Y656356D03*
Y660756D03*
X1737921Y-50764D03*
X1722921Y-45764D03*
X1727921D03*
X1732921D03*
X1747921D03*
X1752921D03*
X1727921Y-54764D03*
X1757921D03*
X1717921D03*
X1722921D03*
X1767921Y-40764D03*
Y-50764D03*
X1762921D03*
X1757921D03*
X1762921Y-54764D03*
X1752921D03*
X1747921D03*
X1742921D03*
X1737921D03*
X1732921D03*
X1772921D03*
X1767921D03*
X1762921Y-40764D03*
X1772921D03*
X1722921Y-50764D03*
X1717921D03*
X1732921D03*
X1757921Y-40764D03*
X1717921Y-45764D03*
Y-58764D03*
X1742921Y-50764D03*
X1747921D03*
X1752921D03*
X1742921Y-58764D03*
X1737921Y-35764D03*
Y-58764D03*
X1732921Y-35764D03*
Y-58764D03*
X1727921Y-35764D03*
Y-58764D03*
X1722921Y-35764D03*
Y-58764D03*
X1717921Y-35764D03*
X1757921Y-45764D03*
X1762921D03*
X1742921D03*
X1752921Y-40764D03*
X1747921D03*
X1742921D03*
X1737921D03*
X1732921D03*
X1727921D03*
X1722921D03*
X1717921D03*
X1727921Y-50764D03*
X1767921Y-45764D03*
X1772921D03*
X1737921D03*
X1772921Y-35764D03*
Y-58764D03*
X1767921Y-35764D03*
Y-58764D03*
X1762921Y-35764D03*
Y-58764D03*
X1757921Y-35764D03*
Y-58764D03*
X1752921Y-35764D03*
Y-58764D03*
X1747921Y-35764D03*
Y-58764D03*
X1742921Y-35764D03*
X1772921Y-50764D03*
X1775121Y643156D03*
Y647556D03*
X1775106Y638753D03*
X1730121Y647556D03*
X1730106Y638753D03*
X1730121Y643156D03*
X1725121Y647556D03*
X1725106Y638753D03*
X1725121Y643156D03*
X1720121Y647556D03*
X1720106Y638753D03*
X1720121Y643156D03*
X1715121Y647556D03*
X1715106Y638753D03*
X1715121Y643156D03*
X1770121Y647556D03*
X1770106Y638753D03*
X1770121Y643156D03*
X1765121Y647556D03*
X1765106Y638753D03*
X1765121Y643156D03*
X1760121Y647556D03*
X1760106Y638753D03*
X1760121Y643156D03*
X1755121Y647556D03*
X1755106Y638753D03*
X1755121Y643156D03*
X1750121Y647556D03*
X1750106Y638753D03*
X1750121Y643156D03*
X1745121Y647556D03*
X1745106Y638753D03*
X1745121Y643156D03*
X1740121Y647556D03*
X1740106Y638753D03*
X1740121Y643156D03*
X1735121Y647556D03*
X1735106Y638753D03*
X1735121Y643156D03*
X1770121Y660756D03*
X1775121D03*
Y656356D03*
Y651956D03*
X1725121Y660756D03*
Y656356D03*
Y651956D03*
X1720121Y660756D03*
Y656356D03*
Y651956D03*
X1715121Y660756D03*
Y656356D03*
Y651956D03*
X1770121D03*
X1765121Y660756D03*
Y656356D03*
Y651956D03*
X1760121Y660756D03*
Y656356D03*
Y651956D03*
X1755121Y660756D03*
Y656356D03*
Y651956D03*
X1750121Y660756D03*
Y656356D03*
Y651956D03*
X1745121Y660756D03*
Y656356D03*
Y651956D03*
X1740121Y660756D03*
Y656356D03*
Y651956D03*
X1735121Y660756D03*
Y656356D03*
Y651956D03*
X1730121Y660756D03*
Y656356D03*
X1770121D03*
X1730121Y651956D03*
X1817921Y-40764D03*
X1832921Y-45764D03*
Y-54764D03*
X1827921D03*
X1822921D03*
X1817921D03*
X1812921D03*
X1807921D03*
X1802921D03*
X1797921D03*
X1792921D03*
X1787921D03*
X1782921D03*
X1777921D03*
X1832921Y-50764D03*
X1827921D03*
X1822921D03*
X1817921D03*
X1812921D03*
X1807921D03*
X1802921D03*
X1797921D03*
X1792921D03*
X1787921D03*
X1782921Y-40764D03*
X1792921D03*
X1802921D03*
X1807921D03*
X1822921D03*
X1827921D03*
X1832921D03*
X1812921D03*
X1797921D03*
X1777921Y-45764D03*
X1782921D03*
X1787921D03*
X1792921D03*
X1797921D03*
X1802921D03*
X1807921D03*
X1812921D03*
X1817921D03*
X1822921D03*
X1787921Y-40764D03*
X1832921Y-35764D03*
Y-58764D03*
X1827921Y-35764D03*
Y-58764D03*
X1822921Y-35764D03*
Y-58764D03*
X1817921Y-35764D03*
Y-58764D03*
X1812921Y-35764D03*
Y-58764D03*
X1807921Y-35764D03*
Y-58764D03*
X1802921Y-35764D03*
Y-58764D03*
X1797921Y-35764D03*
Y-58764D03*
X1792921Y-35764D03*
Y-58764D03*
X1787921Y-35764D03*
Y-58764D03*
X1782921Y-35764D03*
Y-58764D03*
X1777921Y-35764D03*
Y-58764D03*
X1782921Y-50764D03*
X1777921D03*
Y-40764D03*
X1827921Y-45764D03*
X1794992Y61342D03*
X1797664Y61334D03*
X1797645Y64153D03*
X1792382Y61363D03*
X1792363Y64182D03*
X1794973Y64161D03*
X1807891Y62180D03*
X1810563Y62172D03*
X1810693Y59493D03*
X1808021Y59501D03*
X1805411Y59522D03*
X1813393Y59493D03*
X1813363Y62172D03*
X1810578Y56866D03*
X1805282Y56880D03*
X1807916Y56895D03*
X1813278Y56866D03*
X1805281Y62201D03*
X1831148Y144592D03*
X1836200Y153424D03*
X1833000D03*
X1833600Y145900D03*
X1793205Y165531D03*
X1793268Y162774D03*
X1780121Y643156D03*
X1780106Y638753D03*
X1780121Y647556D03*
X1785121Y643156D03*
X1790121D03*
X1835121Y647556D03*
X1835106Y638753D03*
X1835121Y643156D03*
X1830121Y647556D03*
X1830106Y638753D03*
X1830121Y643156D03*
X1825121Y647556D03*
X1825106Y638753D03*
X1825121Y643156D03*
X1820121Y647556D03*
X1820106Y638753D03*
X1820121Y643156D03*
X1815121Y647556D03*
X1815106Y638753D03*
X1815121Y643156D03*
X1810121Y647556D03*
X1810106Y638753D03*
X1810121Y643156D03*
X1805121Y647556D03*
X1805106Y638753D03*
X1805121Y643156D03*
X1800121Y647556D03*
X1800106Y638753D03*
X1800121Y643156D03*
X1795121Y647556D03*
X1795106Y638753D03*
X1795121Y643156D03*
X1790121Y647556D03*
X1790106Y638753D03*
X1785121Y647556D03*
X1785106Y638753D03*
X1800121Y656356D03*
X1780121Y651956D03*
Y656356D03*
Y660756D03*
X1835121D03*
Y656356D03*
Y651956D03*
X1830121Y660756D03*
Y656356D03*
Y651956D03*
X1825121Y660756D03*
Y656356D03*
Y651956D03*
X1820121Y660756D03*
Y656356D03*
Y651956D03*
X1815121Y660756D03*
Y656356D03*
Y651956D03*
X1810121Y660756D03*
Y656356D03*
Y651956D03*
X1805121Y660756D03*
Y656356D03*
Y651956D03*
X1800121Y660756D03*
Y651956D03*
X1795121Y660756D03*
Y656356D03*
Y651956D03*
X1790121Y660756D03*
Y656356D03*
Y651956D03*
X1785121Y660756D03*
Y656356D03*
Y651956D03*
X1857921Y-45764D03*
X1837921D03*
X1897921D03*
X1892921D03*
X1887921D03*
X1882921D03*
X1877921D03*
X1872921D03*
X1867921D03*
X1862921D03*
X1842921Y-54764D03*
X1852921Y-45764D03*
X1847921D03*
X1842921D03*
X1897921Y-54764D03*
X1892921D03*
X1887921D03*
X1882921D03*
X1877921D03*
X1872921D03*
X1867921D03*
X1862921D03*
X1857921D03*
X1852921D03*
X1847921D03*
X1837921D03*
X1897921Y-50764D03*
X1892921D03*
X1887921D03*
X1882921D03*
X1877921D03*
X1872921D03*
X1867921D03*
X1862921D03*
X1857921D03*
X1852921D03*
X1847921D03*
X1842921D03*
X1837921D03*
X1892921Y-40764D03*
X1897921D03*
X1877921D03*
X1882921D03*
X1887921D03*
X1857921D03*
X1862921D03*
X1867921D03*
X1872921D03*
X1837921D03*
X1842921D03*
X1847921D03*
X1852921D03*
Y-35764D03*
Y-58764D03*
X1847921Y-35764D03*
Y-58764D03*
X1842921Y-35764D03*
Y-58764D03*
X1837921Y-35764D03*
Y-58764D03*
X1862921D03*
X1857921Y-35764D03*
Y-58764D03*
X1882921D03*
X1877921Y-35764D03*
Y-58764D03*
X1872921Y-35764D03*
Y-58764D03*
X1867921Y-35764D03*
Y-58764D03*
X1862921Y-35764D03*
X1897921D03*
Y-58764D03*
X1892921Y-35764D03*
Y-58764D03*
X1887921Y-35764D03*
Y-58764D03*
X1882921Y-35764D03*
X1847797Y26331D03*
X1847564Y21636D03*
X1844732Y-7874D03*
X1851030Y1139D03*
Y-16889D03*
X1858880Y2178D03*
X1858879Y-17927D03*
X1868132Y5626D03*
Y-21374D03*
X1877691Y1668D03*
X1877683Y-17425D03*
X1881632Y-7874D03*
X1895121Y647556D03*
X1895106Y638753D03*
X1895121Y643156D03*
X1890121Y647556D03*
X1890106Y638753D03*
X1890121Y643156D03*
X1885121Y647556D03*
X1885106Y638753D03*
X1885121Y643156D03*
X1880121Y647556D03*
X1880106Y638753D03*
X1880121Y643156D03*
X1875121Y647556D03*
X1875106Y638753D03*
X1875121Y643156D03*
X1870121Y647556D03*
X1870106Y638753D03*
X1870121Y643156D03*
X1865121Y647556D03*
X1865106Y638753D03*
X1865121Y643156D03*
X1860121Y647556D03*
X1860106Y638753D03*
X1860121Y643156D03*
X1855121Y647556D03*
X1855106Y638753D03*
X1855121Y643156D03*
X1850121Y647556D03*
X1850106Y638753D03*
X1850121Y643156D03*
X1845121Y647556D03*
X1845106Y638753D03*
X1845121Y643156D03*
X1840121Y647556D03*
X1840106Y638753D03*
X1840121Y643156D03*
X1844732Y610630D03*
X1851030Y619643D03*
Y601615D03*
X1858880Y620682D03*
X1858879Y600577D03*
X1868132Y624130D03*
Y597130D03*
X1877691Y620172D03*
X1877683Y601079D03*
X1881632Y610630D03*
X1895121Y660756D03*
Y656356D03*
Y651956D03*
X1890121Y660756D03*
Y656356D03*
Y651956D03*
X1885121Y660756D03*
Y656356D03*
Y651956D03*
X1880121Y660756D03*
Y656356D03*
Y651956D03*
X1875121Y660756D03*
Y656356D03*
Y651956D03*
X1870121Y660756D03*
Y656356D03*
Y651956D03*
X1865121Y660756D03*
Y656356D03*
Y651956D03*
X1860121Y660756D03*
Y656356D03*
Y651956D03*
X1855121Y660756D03*
Y656356D03*
Y651956D03*
X1850121Y660756D03*
Y656356D03*
Y651956D03*
X1845121Y660756D03*
Y656356D03*
Y651956D03*
X1840121Y660756D03*
Y656356D03*
Y651956D03*
X1927921Y-40764D03*
X1947921Y-45764D03*
X1942921D03*
X1937921D03*
X1932921D03*
X1927921D03*
X1922921D03*
X1917921D03*
X1912921D03*
X1907921D03*
X1902921D03*
X1927921Y-50764D03*
X1932921D03*
Y-40764D03*
X1937921D03*
X1942921D03*
X1947921D03*
X1907921Y-50764D03*
X1902921D03*
X1922921Y-40764D03*
X1917921D03*
X1912921D03*
X1907921D03*
X1902921D03*
X1922921Y-54764D03*
X1917921D03*
X1912921D03*
X1907921D03*
X1902921D03*
X1927921D03*
X1932921D03*
X1937921D03*
X1942921D03*
X1947921D03*
X1952921D03*
X1957921D03*
Y-50764D03*
X1952921D03*
X1947921D03*
X1942921D03*
X1937921D03*
X1922921D03*
X1917921D03*
X1912921D03*
X1957921Y-35764D03*
Y-58764D03*
X1952921Y-35764D03*
Y-58764D03*
X1947921Y-35764D03*
Y-58764D03*
X1942921Y-35764D03*
Y-58764D03*
X1937921Y-35764D03*
Y-58764D03*
X1932921Y-35764D03*
Y-58764D03*
X1927921Y-35764D03*
Y-58764D03*
X1922921Y-35764D03*
Y-58764D03*
X1917921Y-35764D03*
Y-58764D03*
X1912921Y-35764D03*
Y-58764D03*
X1907921Y-35764D03*
Y-58764D03*
X1902921Y-35764D03*
Y-58764D03*
X1960106Y638753D03*
X1955106D03*
X1950106D03*
X1945121Y647556D03*
Y643156D03*
X1945106Y638753D03*
X1940121Y647556D03*
Y643156D03*
X1940106Y638753D03*
X1935121Y647556D03*
Y643156D03*
X1935106Y638753D03*
X1930106D03*
X1925106D03*
X1920121Y647556D03*
X1910121Y643156D03*
X1910106Y638753D03*
X1905121Y647556D03*
Y643156D03*
X1905106Y638753D03*
X1900121Y647556D03*
X1900106Y638753D03*
X1900121Y643156D03*
X1920106Y638753D03*
X1915121Y647556D03*
X1920121Y643156D03*
X1910121Y647556D03*
X1915106Y638753D03*
X1915121Y643156D03*
X1960121Y656356D03*
Y660756D03*
X1955121Y656356D03*
Y660756D03*
X1950121Y651956D03*
Y656356D03*
Y660756D03*
X1945121Y651956D03*
Y656356D03*
Y660756D03*
X1940121Y651956D03*
Y656356D03*
Y660756D03*
X1935121Y651956D03*
Y656356D03*
Y660756D03*
X1930121Y651956D03*
Y656356D03*
Y660756D03*
X1925121Y651956D03*
Y656356D03*
Y660756D03*
X1920121Y651956D03*
Y656356D03*
X1905121Y651956D03*
Y656356D03*
Y660756D03*
X1900121D03*
Y656356D03*
Y651956D03*
X1915121D03*
Y656356D03*
Y660756D03*
X1920121D03*
X1910121D03*
Y656356D03*
Y651956D03*
X1967921Y-45764D03*
X1962921D03*
Y-40764D03*
X1967921D03*
Y-54764D03*
X1962921D03*
X1967921Y-50764D03*
X1962921D03*
X1967921Y-35764D03*
Y-58764D03*
X1962921Y-35764D03*
Y-58764D03*
X1970121Y647556D03*
Y643156D03*
X1970106Y638753D03*
X1965121Y647556D03*
Y643156D03*
X1965106Y638753D03*
X1970121Y651956D03*
Y656356D03*
Y660756D03*
X1965121Y651956D03*
Y656356D03*
Y660756D03*
G54D11*
X0Y0D03*
G54D20*
X72074Y243282D03*
X65180Y243368D03*
X61800Y243400D03*
X68498Y243368D03*
X49560Y649770D03*
Y644670D03*
X54360D03*
X49560Y649570D03*
Y644670D03*
X54360D03*
X49560Y654670D03*
X54360D03*
X49560D03*
X54360D03*
X214820Y649570D03*
Y644670D03*
X210020D03*
X214820Y649770D03*
Y644670D03*
X210020D03*
X214820Y654670D03*
X210020D03*
X214820D03*
X210020D03*
X238282Y649670D03*
Y644770D03*
X243082D03*
X238282Y649870D03*
Y644770D03*
X243082D03*
X238282Y654770D03*
X243082D03*
X238282D03*
X243082D03*
X402404Y649650D03*
Y644550D03*
X397604D03*
X402404Y649450D03*
Y644550D03*
X397604D03*
X402404Y654550D03*
X397604D03*
X402404D03*
X397604D03*
X425750Y649400D03*
Y644500D03*
X430550D03*
X425750Y649600D03*
Y644500D03*
X430550D03*
X425750Y654500D03*
X430550D03*
X425750D03*
X430550D03*
X589871Y649379D03*
Y644279D03*
X585071D03*
X589872Y649180D03*
Y644280D03*
X585072D03*
X589871Y654279D03*
X585071D03*
X589872Y654280D03*
X585072D03*
X613298Y649331D03*
Y644231D03*
X618098D03*
X613298Y649131D03*
Y644231D03*
X618098D03*
X613298Y654231D03*
X618098D03*
X613298D03*
X618098D03*
X905515Y649159D03*
Y644259D03*
X900715D03*
X905515Y649359D03*
Y644259D03*
X900715D03*
X905515Y654259D03*
X900715D03*
X905515D03*
X900715D03*
X928952Y649120D03*
Y644220D03*
X933752D03*
X928952Y649320D03*
Y644220D03*
X933752D03*
X928952Y654220D03*
X933752D03*
X928952D03*
X933752D03*
X1219041Y649348D03*
Y644248D03*
X1214241D03*
X1219041Y649148D03*
Y644248D03*
X1214241D03*
X1219041Y654248D03*
X1214241D03*
X1219041D03*
X1214241D03*
X1242450Y649150D03*
Y644250D03*
X1247250D03*
X1242450Y649350D03*
Y644250D03*
X1247250D03*
X1242450Y654250D03*
X1247250D03*
X1242450D03*
X1247250D03*
X1527739Y644278D03*
D03*
Y654278D03*
D03*
X1532539Y649378D03*
Y644278D03*
Y649178D03*
Y644278D03*
Y654278D03*
D03*
G54D30*
X1887327Y511202D03*
X1929453Y532541D03*
G54D21*
X60512Y467244D03*
X1894100Y493000D03*
X1891086Y602105D03*
G54D12*
G01X38645Y172740D02*
X44291Y178386D01*
G01D02*
X49937Y184032D01*
G01X38645D02*
X44291Y178386D01*
G01D02*
X49937Y172740D01*
G01X-7615D02*
X-1969Y178386D01*
G01D02*
X3677Y184032D01*
G01X-7615D02*
X-1969Y178386D01*
G01D02*
X3677Y172740D01*
G01X12582D02*
X18228Y178386D01*
G01D02*
X23874Y184032D01*
G01X12582D02*
X18228Y178386D01*
G01D02*
X23874Y172740D01*
G01X12129Y430711D02*
X15512Y434094D01*
G01D02*
X18895Y437477D01*
G01X12129D02*
X15512Y434094D01*
G01D02*
X18895Y430711D01*
G01X116597Y142148D02*
X119980Y145531D01*
G01D02*
X123363Y148914D01*
G01X116597D02*
X119980Y145531D01*
G01D02*
X123363Y142148D01*
G01X430749Y-124922D02*
G02I-12000J0D01*
G01X425599D02*
G02I-6850J0D01*
G01X434749D02*
X402749D01*
G01X434749Y-140922D02*
Y-220922D01*
G01D02*
X1729349D01*
G01X434749Y-176422D02*
X1729349D01*
G01X418749Y-140922D02*
Y-108922D01*
G01X434749Y-140922D02*
X1729349D01*
G01X941849D02*
Y-220922D01*
G01X1079349Y-140922D02*
Y-220922D01*
G01X1194349Y-140922D02*
Y-220922D01*
G01X1361849Y-140922D02*
Y-220922D01*
G01X1389729Y21441D02*
X1392264Y23976D01*
G01D02*
X1394799Y26511D01*
G01X1389729D02*
X1392264Y23976D01*
G01D02*
X1394799Y21441D01*
G01X1511383D02*
X1513918Y23976D01*
G01D02*
X1516453Y26511D01*
G01X1511383D02*
X1513918Y23976D01*
G01D02*
X1516453Y21441D01*
G01X1531849Y-140922D02*
Y-220922D01*
G01X1644721Y-2921D02*
X1647327Y-315D01*
G01D02*
X1649933Y2291D01*
G01X1644721D02*
X1647327Y-315D01*
G01D02*
X1649933Y-2921D01*
G01X1729349Y-140922D02*
Y-220922D01*
G01X1757349Y-124922D02*
G02I-12000J0D01*
G01X1752199D02*
G02I-6850J0D01*
G01X1745349Y-140922D02*
Y-108922D01*
G01X1761349Y-124922D02*
X1729349D01*
G01X1947447Y214597D02*
X1950000Y207893D01*
G01X1947447Y203241D02*
X1950000Y207893D01*
G01X1959921Y209074D02*
X1961890Y211043D01*
G01X1950000Y220787D02*
X1953630Y217612D01*
G01X1946370D02*
X1950000Y220787D01*
G01X1947447Y234851D02*
X1950000Y241555D01*
G01Y234851D02*
Y241555D01*
G01X1959921Y240374D02*
X1961890Y238405D01*
G01X1946370Y231836D02*
X1950000Y228661D01*
G01D02*
X1953630Y225486D01*
G01X1950000Y228661D02*
X1953630Y231836D01*
G01X1946370Y223962D02*
X1950000Y220787D01*
G01D02*
X1953630Y223962D01*
G01X1929453Y529639D02*
Y532541D01*
G01D02*
Y535443D01*
G01X1925351Y532541D02*
X1929453D01*
G01D02*
X1933555D01*
G01X1967468Y212037D02*
X1970670Y207007D01*
G01X1967468Y201977D02*
X1970670Y207007D01*
G01X1961890Y211043D02*
X1963859Y213012D01*
G01X1961890Y211043D02*
X1963859Y209074D01*
G01X1967468Y237411D02*
X1970670Y242441D01*
G01Y237411D02*
Y242441D01*
G01X1961890Y238405D02*
X1963859Y240374D01*
G01X1961890Y238405D02*
X1963859Y236436D01*
X-20700Y31400D03*
Y25200D03*
Y22300D03*
Y28100D03*
X-20600Y41200D03*
X-20526Y44263D03*
X-20500Y60300D03*
Y57300D03*
X-20700Y48800D03*
X-20726Y37463D03*
X-20800Y34400D03*
X-20500Y54300D03*
Y51300D03*
X-18000Y247400D03*
X-15000D03*
X-18000Y262700D03*
X-15000D03*
X-14690Y471140D03*
X-16726Y503651D03*
X-17084Y467626D03*
X-17300Y530800D03*
X-17397Y564242D03*
X30600Y-12000D03*
X25838Y-20458D03*
X10600Y25100D03*
X1068Y24831D03*
X27102Y25383D03*
X39530Y5205D03*
X45670Y5185D03*
X33370D03*
X45429Y-4669D03*
X33628Y131D03*
X40994Y-7148D03*
X45700Y40D03*
X11539Y31427D03*
X27200Y30600D03*
X27239Y28027D03*
X25600Y32500D03*
X11600Y33944D03*
X26760Y49595D03*
X27800Y86900D03*
X22100Y56400D03*
X27800Y89900D03*
Y83900D03*
X30400Y89800D03*
Y86800D03*
Y83800D03*
X10925Y56167D03*
X27904Y56294D03*
X30686Y79943D03*
X23530Y94840D03*
X11030D03*
X13530D03*
X16030D03*
X18530D03*
X22380Y92670D03*
X21030Y94840D03*
X2380Y92670D03*
X4880D03*
X7380D03*
X9880D03*
X12380D03*
X14880D03*
X17380D03*
X19880D03*
X3530Y94840D03*
X6030D03*
X8530D03*
X-1000Y81500D03*
X24880Y92670D03*
X25870Y80880D03*
X28294Y80889D03*
X32500Y81791D03*
X25100Y56300D03*
X-1190Y53240D03*
X25886Y71467D03*
X25925Y75867D03*
X26185Y67017D03*
X27488Y64671D03*
X11925Y65311D03*
X27625Y73967D03*
X27525Y69367D03*
X11925Y67811D03*
X11864Y62794D03*
X24064Y61894D03*
X15111Y62553D03*
X27564Y61894D03*
X11600Y36444D03*
X25900Y40300D03*
X27564Y59394D03*
X24064D03*
X25700Y36200D03*
X27300Y34300D03*
Y38300D03*
X27208Y42313D03*
X27239Y47027D03*
X25700Y44400D03*
X27525Y77867D03*
X44200Y139400D03*
X44300Y144800D03*
X44200Y130700D03*
Y116800D03*
X44100Y97800D03*
X44200Y111500D03*
X44300Y102700D03*
Y125600D03*
X44600Y154100D03*
X7995Y285385D03*
X32450Y454050D03*
X35100Y453900D03*
X35900Y423500D03*
X43550Y431300D03*
X20075Y424850D03*
X12025Y427900D03*
X7025D03*
X2025D03*
X21397Y439354D03*
Y444354D03*
X18836Y441785D03*
X7736D03*
X-6104Y461190D03*
X5000Y469000D03*
X10443Y490649D03*
X40132Y499800D03*
X24400Y519500D03*
X280Y524350D03*
X40185Y482918D03*
X37568Y482836D03*
X26780Y488910D03*
X21000Y495800D03*
X13300Y509600D03*
X13600Y504300D03*
X4000Y509500D03*
X2485Y498185D03*
X13700Y498500D03*
X24591Y479139D03*
X35896Y557668D03*
X33396D03*
X38696D03*
X-10200Y558200D03*
X21700Y532300D03*
X19100D03*
X27000D03*
X1040Y531218D03*
X21948Y566700D03*
X19448D03*
X27114Y557563D03*
X24748Y566700D03*
X0Y566800D03*
X29400Y532300D03*
X46400Y536290D03*
Y539790D03*
X43505Y538714D03*
X43241Y535965D03*
X41500Y533800D03*
X29914Y557563D03*
X45880Y554710D03*
Y557820D03*
X46560Y581000D03*
Y577500D03*
X1500Y540600D03*
X15787Y551700D03*
X17100Y545400D03*
X13639Y534683D03*
Y537183D03*
X15800Y543300D03*
X15600Y539100D03*
X17139Y534683D03*
Y537183D03*
X17100Y541200D03*
X17035Y549558D03*
X15800Y547500D03*
X17139Y553683D03*
X1500Y543100D03*
X1439Y538083D03*
X15800Y579500D03*
Y575300D03*
X17108Y585513D03*
X17156Y581481D03*
X17100Y577400D03*
X17139Y573183D03*
X1500Y576600D03*
X17139Y570683D03*
X1500Y579100D03*
X1439Y574083D03*
X15770Y587700D03*
X15800Y583500D03*
X27495Y591409D03*
X-12450Y590965D03*
X30212Y591417D03*
X35085Y591621D03*
X32609Y591538D03*
X46500Y595190D03*
X43190Y598410D03*
X43210Y595180D03*
X43190Y601910D03*
X17139Y589683D03*
X65800Y14200D03*
X59061Y476D03*
X61152Y-12752D03*
X59281Y-20641D03*
X99102Y-12010D03*
X105892Y8700D03*
X62076Y5575D03*
X76247Y1189D03*
X84202Y-11395D03*
X81702D03*
X79202D03*
X73611Y1158D03*
X71111D03*
X68611D03*
X73574Y-1437D03*
X71074D03*
X68574D03*
X79500Y-16600D03*
X55713Y-5095D03*
X76165Y-1415D03*
X106200Y26500D03*
X102100Y73800D03*
X105892Y45290D03*
X52500Y67200D03*
Y63700D03*
Y60700D03*
Y37700D03*
Y34700D03*
Y43700D03*
Y40700D03*
Y57700D03*
X71050Y89600D03*
X48700Y90700D03*
Y95500D03*
X61300Y89800D03*
X81861Y93392D03*
X108385Y84291D03*
X63737Y130602D03*
X48900Y132600D03*
X68592D03*
X85250Y127680D03*
X77730Y126860D03*
X63858Y97620D03*
X66600Y102360D03*
X62422Y109413D03*
X68000Y111000D03*
X48900Y123500D03*
X62524Y123395D03*
X68584Y123900D03*
X68654Y118680D03*
X48800Y118900D03*
X48700Y109600D03*
X48600Y104900D03*
X63582Y116409D03*
X62502Y105100D03*
X52500Y152000D03*
X60300Y151500D03*
X70800Y151400D03*
X48800Y137600D03*
X63878Y144800D03*
X68632Y137800D03*
X63888Y140064D03*
X107254Y128041D03*
X106698Y215610D03*
X100500Y188600D03*
X97500Y185700D03*
X104800D03*
X102400D03*
X99900D03*
X77650Y178150D03*
X73500Y191500D03*
X107750Y238730D03*
X83300Y267400D03*
X84000Y272500D03*
X79300Y272300D03*
X108000Y249330D03*
X53400Y277582D03*
Y274500D03*
X94938Y323467D03*
X48800Y282600D03*
Y285100D03*
Y292400D03*
Y289600D03*
X58400Y314600D03*
X77300Y315600D03*
X53000Y323500D03*
X52804Y333247D03*
X61300Y328600D03*
X84000Y316083D03*
X70700Y330349D03*
X103500Y302100D03*
X93500Y289000D03*
X93400Y296000D03*
X99770Y325249D03*
X71500Y298000D03*
X66000Y292700D03*
X76800Y298000D03*
X76900Y292600D03*
X66500Y303400D03*
X76800D03*
X93500Y285000D03*
X67400Y391690D03*
X67230Y397380D03*
X67710Y402040D03*
X55616Y368998D03*
X52000Y354500D03*
X61000Y383000D03*
X57500Y388100D03*
X77300Y390600D03*
X107224Y393848D03*
X76500Y368300D03*
X76300Y358400D03*
X82037Y358542D03*
X70600Y368400D03*
X82100Y368300D03*
X70900Y358300D03*
X51500Y406000D03*
X57471Y410749D03*
X64007Y408276D03*
X63630Y424280D03*
X63600Y429000D03*
X51890Y424470D03*
Y418970D03*
X103100Y411800D03*
X72603Y474072D03*
X60300Y508650D03*
X51607Y511747D03*
X74480Y504480D03*
X79630Y504580D03*
X60000Y526500D03*
X79400Y502150D03*
X74600Y502064D03*
X77000Y502133D03*
X49800Y524300D03*
X76996Y504587D03*
X60700Y521900D03*
X57936Y516012D03*
X60202Y495342D03*
X57302Y495442D03*
X105958Y518550D03*
X106392Y537000D03*
X105392Y574800D03*
X105412Y556580D03*
X105000Y614533D03*
X82459Y618932D03*
X105352Y594770D03*
X101898Y611483D03*
X150391Y14814D03*
X163427Y14714D03*
X157084Y14814D03*
X160431Y-1801D03*
X153738Y9114D03*
X150391Y-7851D03*
X163391D03*
X157084D03*
X153738Y-1751D03*
X160431Y9114D03*
X126616Y14714D03*
X136756Y16900D03*
X120273Y16839D03*
X132959Y14814D03*
X141880Y17114D03*
X147045Y9114D03*
X130163D03*
X141856Y9100D03*
X136780Y9098D03*
X123620Y9114D03*
X126580Y-7851D03*
X132959Y-7700D03*
X120273Y-9901D03*
X141893Y-9864D03*
X136806Y-9650D03*
X136780Y-1801D03*
X123620D03*
X130313Y-1751D03*
X141906Y-2050D03*
X147045Y-1751D03*
X169770Y14814D03*
X167124Y-1751D03*
X169770Y-7700D03*
X166974Y9114D03*
X169770Y30100D03*
X120273Y27899D03*
X141893Y27936D03*
X136806Y28150D03*
X126580Y29949D03*
X132959Y30100D03*
X157084Y29949D03*
X163391D03*
X150391D03*
X169770Y90364D03*
X166974Y84714D03*
Y73849D03*
Y46914D03*
X169770Y52614D03*
X167124Y36049D03*
X169770Y67900D03*
X157084Y67749D03*
X163391D03*
X130313Y73849D03*
X123620Y73799D03*
X141906Y73550D03*
X136780Y73799D03*
X126580Y67749D03*
X132959Y67900D03*
X141880Y54914D03*
X123620Y35983D03*
X141856Y46900D03*
X141906Y35750D03*
X136806Y65950D03*
X141893Y65736D03*
X136756Y54700D03*
X136780Y35999D03*
X130313Y35983D03*
X123620Y46914D03*
X132959Y52614D03*
X126616Y52514D03*
X147045Y46914D03*
Y36049D03*
X120273Y54839D03*
Y92500D03*
X126616Y90314D03*
X132959Y90414D03*
X141880Y92714D03*
X163427Y90314D03*
X157084Y90414D03*
X150391D03*
X160431Y84714D03*
X153738D03*
X136756Y92500D03*
X141856Y84700D03*
X136780Y84698D03*
X123620Y84714D03*
X147045D03*
X130163D03*
Y46914D03*
X136780Y46898D03*
X120273Y66000D03*
X147045Y73849D03*
X153738Y36049D03*
Y73849D03*
X160431Y73799D03*
X157084Y52614D03*
X160431Y35999D03*
X150391Y67749D03*
Y52614D03*
X163427Y52514D03*
X160431Y46914D03*
X153738D03*
X156954Y192872D03*
X154454Y193021D03*
X151810Y192670D03*
X124895Y212033D03*
X153788Y187309D03*
X156928Y190053D03*
X148900Y180400D03*
X148800Y185300D03*
Y182900D03*
X148900Y190100D03*
X148800Y187700D03*
X113800Y180500D03*
X116900D03*
X151359Y187700D03*
X156294Y187625D03*
X151300Y190200D03*
X141263Y215216D03*
X125563Y218616D03*
X137763Y217716D03*
X128500Y218700D03*
X141263Y217716D03*
X137763Y215216D03*
X154130Y190186D03*
X169150Y223600D03*
Y227600D03*
X112904Y237218D03*
X122820Y244133D03*
X123074Y275948D03*
X113100Y269163D03*
X125624Y223633D03*
Y221133D03*
X141263Y234216D03*
X141200Y229600D03*
X141211Y225615D03*
X141300Y221700D03*
X139763Y231700D03*
Y227600D03*
Y223700D03*
X139582Y219800D03*
X128200Y250700D03*
X125563Y250616D03*
X141263Y249716D03*
Y247216D03*
X137763D03*
Y249716D03*
X125624Y255633D03*
X141300Y253700D03*
X139631Y251900D03*
X125624Y253133D03*
X137763Y279216D03*
X141263Y266216D03*
X139763Y255700D03*
Y259600D03*
X139800Y263700D03*
X141313Y257533D03*
X141263Y279216D03*
X141200Y261600D03*
X137300Y337200D03*
X118800Y298400D03*
X123301Y308044D03*
X110180Y280920D03*
X109960Y313190D03*
X119050Y341625D03*
X113000Y304000D03*
X113100Y333106D03*
X125624Y287633D03*
X128200Y282600D03*
X141263Y311216D03*
X137763D03*
X141263Y281716D03*
X139730Y284200D03*
X139763Y288200D03*
Y292000D03*
Y296000D03*
X125624Y285133D03*
X141200Y286100D03*
X141261Y290076D03*
X141300Y294000D03*
X141263Y298216D03*
X137763Y281716D03*
X125563Y282616D03*
X141211Y325515D03*
X128200Y314800D03*
X141263Y330216D03*
X139763Y327800D03*
X141300Y317500D03*
Y321500D03*
X139582Y315800D03*
X139763Y319400D03*
X125563Y314616D03*
X141263Y313716D03*
X137763D03*
X139763Y323600D03*
X125624Y317133D03*
Y319633D03*
X109640Y376070D03*
X113500Y369000D03*
X110670Y344500D03*
X112600Y366300D03*
X122300Y372100D03*
X119300Y400900D03*
X110397Y402603D03*
X109924Y393848D03*
X141289Y349488D03*
X128100Y346700D03*
X141300Y353300D03*
X141200Y357200D03*
X137763Y345716D03*
X141263D03*
Y343216D03*
X125624Y349133D03*
X137763Y343216D03*
X141263Y362216D03*
X139582Y347800D03*
X139763Y351400D03*
Y355200D03*
Y359500D03*
X125624Y351633D03*
X125563Y346616D03*
X141300Y381800D03*
X139763Y384000D03*
X125624Y381133D03*
X141263Y394216D03*
Y390416D03*
X141261Y385876D03*
X139736Y392300D03*
X125563Y378616D03*
X137763Y375216D03*
X141263D03*
Y377716D03*
X137763D03*
X139631Y379900D03*
X128500Y378700D03*
X139900Y388000D03*
X125624Y383633D03*
X117363Y417416D03*
X130163Y510114D03*
X147045D03*
X132959Y515814D03*
X126616Y515714D03*
X120273Y517900D03*
X136780Y510098D03*
X136756Y517900D03*
X141856Y510100D03*
X141880Y518114D03*
X123620Y510114D03*
X150391Y515814D03*
X169770Y515764D03*
X163427Y515714D03*
X166974Y510114D03*
X160431D03*
X157084Y515814D03*
X153738Y510114D03*
X141893Y528936D03*
X136806Y529150D03*
X141906Y536750D03*
X132959Y553614D03*
X126616Y553514D03*
X130163Y547914D03*
X123620D03*
X136780Y547898D03*
X141856Y547900D03*
X147045Y537049D03*
Y547914D03*
X120210Y529200D03*
X130313Y537049D03*
X132959Y531100D03*
X126580Y530949D03*
X123620Y536999D03*
X136780D03*
X123620Y574799D03*
X130313Y574849D03*
X132959Y568900D03*
X126580Y568749D03*
X141856Y585700D03*
X141906Y574550D03*
X136780Y574799D03*
Y585698D03*
X120092Y566900D03*
X136806Y566950D03*
X147045Y585714D03*
Y574849D03*
X141880Y555914D03*
X120273Y555700D03*
X136756D03*
X141893Y566736D03*
X130163Y585714D03*
X123620D03*
X150391Y530949D03*
Y553614D03*
X166974Y537049D03*
X163391Y530949D03*
X160431Y536999D03*
X169770Y553564D03*
X163427Y553514D03*
X166974Y547914D03*
X160431D03*
X157084Y530949D03*
X153738Y537049D03*
X157084Y553614D03*
X153738Y547914D03*
X169770Y531100D03*
X150391Y568749D03*
X163391D03*
X160431Y585714D03*
X166974D03*
Y574849D03*
X160431Y574799D03*
X169770Y568900D03*
X157084Y568749D03*
X153738Y585714D03*
Y574849D03*
X147045Y612649D03*
X123620Y612599D03*
X136780D03*
X130313Y612649D03*
X160431Y612599D03*
X166974Y612649D03*
X153738D03*
X126616Y591314D03*
X116992Y590700D03*
X132959Y591414D03*
X136756Y593500D03*
X141880Y593714D03*
X132959Y606700D03*
X126580Y606549D03*
X120092Y604900D03*
X141906Y612350D03*
X136806Y604750D03*
X141893Y604536D03*
X150391Y591414D03*
Y606549D03*
X163427Y591314D03*
X163391Y606549D03*
X169770Y606700D03*
Y591364D03*
X157084Y591414D03*
Y606549D03*
X173591Y-1801D03*
X178691Y17114D03*
X173567Y16900D03*
X178717Y-2050D03*
X183856Y-1751D03*
X173617Y-9650D03*
X178704Y-9864D03*
X178667Y9100D03*
X173591Y9098D03*
X183856Y9114D03*
X178704Y27936D03*
X173617Y28150D03*
X190549Y9114D03*
X197242D03*
X210402Y9098D03*
X210428Y-9650D03*
X193895Y-7851D03*
X187202D03*
X200202D03*
X210402Y-1801D03*
X190549Y-1751D03*
X197242Y-1801D03*
X203935Y-1751D03*
X206581Y-7700D03*
X203785Y9114D03*
X210378Y16900D03*
X210428Y28150D03*
X200202Y29949D03*
X187202D03*
X193895Y14814D03*
Y29949D03*
X200238Y14714D03*
X187202Y14814D03*
X206581D03*
Y30100D03*
X220667Y-1751D03*
X215528Y-2050D03*
X215515Y-9864D03*
X227360Y-1751D03*
X230706Y-7851D03*
X224013D03*
X215478Y9100D03*
X220667Y9114D03*
X227360D03*
X224013Y29949D03*
X230706D03*
Y14814D03*
X224013D03*
X215502Y17114D03*
X215515Y27936D03*
X178691Y92714D03*
X173591Y84698D03*
X178667Y84700D03*
X183856Y84714D03*
X173567Y92500D03*
X183856Y36049D03*
X173591Y46898D03*
X183856Y73849D03*
X178717Y73550D03*
X173591Y73799D03*
X178691Y54914D03*
X173591Y35999D03*
X183856Y46914D03*
X178717Y35750D03*
X178667Y46900D03*
X173567Y54700D03*
X173617Y65950D03*
X178704Y65736D03*
X206581Y52614D03*
X210378Y54700D03*
X210402Y46898D03*
X193895Y67749D03*
X200202D03*
X187202D03*
X203785Y46914D03*
X190549D03*
X197242D03*
X200238Y52514D03*
X193895Y52614D03*
X187202D03*
X190549Y36049D03*
X203935D03*
X197242Y35999D03*
X206581Y67900D03*
X210428Y65950D03*
X210402Y35999D03*
X197242Y73799D03*
X203935Y73849D03*
X210402Y73799D03*
Y84698D03*
X210378Y92500D03*
X190549Y73849D03*
Y84714D03*
X197242D03*
X203785D03*
X193895Y90414D03*
X206581D03*
X200238Y90314D03*
X187202Y90414D03*
X215478Y46900D03*
X215502Y54914D03*
X215515Y65736D03*
X224013Y52614D03*
X220667Y46914D03*
X230706Y52614D03*
X224013Y67749D03*
X230706D03*
X227360Y46914D03*
Y36049D03*
X220667D03*
X215528Y35750D03*
X215502Y92714D03*
X220667Y73849D03*
Y84714D03*
X227360D03*
X230706Y90414D03*
X215478Y84700D03*
X215528Y73550D03*
X227360Y73849D03*
X224013Y90414D03*
X197617Y243089D03*
X191537Y242989D03*
Y240489D03*
X197617Y240589D03*
X191537Y237989D03*
X197617Y238089D03*
X192037Y270750D03*
X194537D03*
X197037D03*
X194537Y299750D03*
X197037D03*
X192037D03*
X194537Y332480D03*
X197037D03*
X192037D03*
X194500Y360200D03*
X197137Y360350D03*
X191900Y360173D03*
X195200Y377800D03*
Y380300D03*
X172697Y407196D03*
X197242Y510114D03*
X200238Y515714D03*
X203785Y510114D03*
X190549D03*
X187202Y515814D03*
X193895D03*
X183856Y510114D03*
X173591Y510098D03*
X173567Y517900D03*
X178691Y518114D03*
X206581Y515814D03*
X210402Y510098D03*
X210378Y517900D03*
X215502Y518114D03*
X215478Y510100D03*
X224013Y515814D03*
X220667Y510114D03*
X227360D03*
X230706Y515814D03*
X193895Y553614D03*
X200238Y553514D03*
X183856Y547914D03*
X190549D03*
X203785D03*
X197242D03*
X190549Y537049D03*
X183856D03*
X187202Y530949D03*
X193895D03*
X197242Y536999D03*
X203935Y537049D03*
X200202Y530949D03*
X206581Y553614D03*
X210402Y547898D03*
X178717Y536750D03*
X173617Y529150D03*
X173591Y536999D03*
X178704Y528936D03*
X178667Y547900D03*
X173591Y547898D03*
X206581Y531100D03*
X210402Y536999D03*
X210428Y529150D03*
X187202Y553614D03*
X178691Y555914D03*
X173567Y555700D03*
X210378D03*
X203935Y574849D03*
X200202Y568749D03*
X197242Y574799D03*
X190549Y585714D03*
X183856D03*
X187202Y568749D03*
X193895D03*
X190549Y574849D03*
X183856D03*
X210402Y585698D03*
X206581Y568900D03*
X210428Y566950D03*
X210402Y574799D03*
X178667Y585700D03*
X178717Y574550D03*
X173591Y574799D03*
Y585698D03*
X173617Y566950D03*
X178704Y566736D03*
X197242Y585714D03*
X203785D03*
X215515Y528936D03*
X215528Y536750D03*
X215478Y547900D03*
X224013Y530949D03*
X220667Y537049D03*
X230706Y530949D03*
X227360Y537049D03*
X230706Y553614D03*
X220667Y547914D03*
X227360D03*
X224013Y553614D03*
X215502Y555914D03*
X220667Y585714D03*
X215528Y574550D03*
X215478Y585700D03*
X215515Y566736D03*
X224013Y568749D03*
X220667Y574849D03*
X230706Y568749D03*
X227360Y574849D03*
Y585714D03*
Y612649D03*
X220667D03*
X203935D03*
X197242Y612599D03*
X190549Y612649D03*
X183856D03*
X210402Y612599D03*
X173591D03*
X187202Y591414D03*
X193895D03*
X187202Y606549D03*
X193895D03*
X200202D03*
X210428Y604750D03*
X206581Y606700D03*
X210378Y593500D03*
X206581Y591414D03*
X178717Y612350D03*
X173617Y604750D03*
X178704Y604536D03*
X173567Y593500D03*
X178691Y593714D03*
X200238Y591314D03*
X224013Y606549D03*
X230706D03*
Y591414D03*
X215515Y604536D03*
X215528Y612350D03*
X215502Y593714D03*
X224013Y591414D03*
X270864Y-1801D03*
X247213D03*
X240746Y-1751D03*
X264171D03*
X252339Y-2050D03*
X234053Y-1801D03*
X257478Y-1751D03*
X243392Y-7700D03*
X260824Y-7851D03*
X252326Y-9864D03*
X237013Y-7851D03*
X247239Y-9650D03*
X267517Y-7851D03*
X252289Y9100D03*
X264171Y9114D03*
X240596D03*
X247213Y9098D03*
X270864Y9114D03*
X234053D03*
X257478D03*
X267517Y14814D03*
Y29949D03*
X247189Y16900D03*
X252326Y27936D03*
X243392Y30100D03*
X247239Y28150D03*
X260824Y29949D03*
X237013D03*
X252313Y17114D03*
X243392Y14814D03*
X260824D03*
X237049Y14714D03*
X284050Y-9650D03*
X289137Y-9864D03*
X273824Y-7851D03*
X280203Y-7700D03*
X289100Y9100D03*
X284024Y9098D03*
X277407Y9114D03*
X277557Y-1751D03*
X289150Y-2050D03*
X284024Y-1801D03*
X273824Y29949D03*
X273860Y14714D03*
X284000Y16900D03*
X280203Y14814D03*
Y30100D03*
X289124Y17114D03*
X284050Y28150D03*
X289137Y27936D03*
X247213Y46898D03*
X257478Y46914D03*
X240596D03*
X243392Y67900D03*
X267517Y67749D03*
Y52614D03*
X270864Y46914D03*
X252326Y65736D03*
X237013Y67749D03*
X260824D03*
X247239Y65950D03*
X243392Y52614D03*
X264171Y46914D03*
X247213Y35999D03*
X257478Y36049D03*
X252339Y35750D03*
X234053Y35999D03*
X240746Y36049D03*
X264171D03*
X237049Y52514D03*
X252289Y46900D03*
X247189Y54700D03*
X252313Y54914D03*
X260824Y52614D03*
X270864Y35999D03*
X234053Y46914D03*
X247213Y73799D03*
Y84698D03*
X264171Y84714D03*
X252339Y73550D03*
X257478Y84714D03*
X240746Y73849D03*
X257478D03*
X234053Y73799D03*
X264171Y73849D03*
X243392Y90414D03*
X252313Y92714D03*
X237049Y90314D03*
X270864Y84714D03*
X247189Y92500D03*
X240596Y84714D03*
X234053D03*
X252289Y84700D03*
X260824Y90414D03*
X267517D03*
X270864Y73799D03*
X273824Y67749D03*
X280203Y67900D03*
X284024Y35999D03*
X277557Y36049D03*
X277407Y46914D03*
X289137Y65736D03*
X284050Y65950D03*
X284024Y46898D03*
X284000Y54700D03*
X289100Y46900D03*
X289150Y35750D03*
X289124Y54914D03*
X280203Y52614D03*
X273860Y90314D03*
X277407Y84714D03*
X289100Y84700D03*
X284024Y84698D03*
X284000Y92500D03*
X289150Y73550D03*
X284024Y73799D03*
X289124Y92714D03*
X280203Y90414D03*
X277407Y73849D03*
X264171Y104284D03*
X267517Y109984D03*
X270864Y104284D03*
X257478D03*
X260824Y109984D03*
X243392Y109534D03*
X252339Y112865D03*
X247213Y113114D03*
X237049Y109884D03*
X240596Y104284D03*
X247239Y105265D03*
X252326Y105051D03*
X234053Y104284D03*
X273860Y109884D03*
X284050Y105265D03*
X289137Y105051D03*
X289150Y112865D03*
X284024Y113114D03*
X280203Y109534D03*
X277407Y104284D03*
X271239Y211060D03*
X284759Y207159D03*
X291519D03*
X274619Y213009D03*
Y216909D03*
X277999Y211060D03*
Y214960D03*
Y203260D03*
Y207159D03*
X281379Y213009D03*
X288139Y216909D03*
X284759Y214960D03*
X291519D03*
Y218860D03*
X281379Y201309D03*
X284759Y199360D03*
X291519D03*
X267859Y244209D03*
Y240309D03*
X271239Y238360D03*
X264179D03*
Y250060D03*
X264092Y222710D03*
X264179Y226660D03*
X271239Y269560D03*
Y273460D03*
Y265660D03*
X267859Y263709D03*
Y259809D03*
X264179Y265660D03*
X267859Y252009D03*
X264179Y253960D03*
X291519Y238360D03*
X284759Y234460D03*
X288139Y232509D03*
X281379D03*
X277999Y234460D03*
X274619Y232509D03*
Y220809D03*
Y224709D03*
Y228610D03*
X277999Y230559D03*
X274619Y244209D03*
X277999Y250060D03*
X274619Y240309D03*
Y248109D03*
Y236409D03*
X291519Y246160D03*
Y250060D03*
X284759Y246160D03*
X291519Y242260D03*
X281379Y220809D03*
X284759Y226660D03*
X288139Y236409D03*
X291519Y234460D03*
Y222760D03*
Y230559D03*
Y226660D03*
X281379Y240309D03*
Y252009D03*
X274619D03*
X277999Y253960D03*
X284759D03*
X291519D03*
X284759Y265660D03*
X291519D03*
Y277360D03*
X281379Y275409D03*
Y271509D03*
X284759Y277360D03*
Y273460D03*
X288139Y275409D03*
Y271509D03*
X277999Y277360D03*
X274619Y255909D03*
Y259809D03*
X277999Y269560D03*
X274619Y275409D03*
Y267609D03*
Y263709D03*
X288139Y255909D03*
X291519Y269560D03*
Y257860D03*
Y261760D03*
X281379Y259809D03*
X288139Y252009D03*
X271239Y328060D03*
X267859Y333909D03*
Y341709D03*
Y330009D03*
X264179Y328060D03*
Y339760D03*
X291519Y285160D03*
Y292959D03*
X284759Y285160D03*
X277999Y308560D03*
Y300760D03*
Y292959D03*
Y285160D03*
X291519Y308560D03*
X284759D03*
Y300760D03*
X291519D03*
X284759Y292959D03*
X291519Y316360D03*
X281379Y318309D03*
X291519Y328060D03*
X288139Y341709D03*
X274619Y330009D03*
Y326110D03*
Y322209D03*
X277999Y328060D03*
X274619Y341709D03*
X277999Y320260D03*
Y316360D03*
X274619Y333909D03*
Y337809D03*
X284759Y324160D03*
X288139Y318309D03*
X284759Y316360D03*
X281379Y337809D03*
X291519Y339760D03*
Y335860D03*
X284759Y331960D03*
X291519D03*
X281379Y326110D03*
X288139D03*
X267559Y369010D03*
X271239Y355360D03*
X267859Y349509D03*
Y353409D03*
X267559Y361209D03*
X264179Y343660D03*
Y355360D03*
X267492Y380709D03*
X271239Y390460D03*
X267859Y388509D03*
X271239Y382660D03*
X284759Y351460D03*
X281379Y345609D03*
X291519Y359260D03*
Y355360D03*
Y351460D03*
X284759Y343660D03*
X274619Y365109D03*
X277999Y363160D03*
Y367060D03*
X274619Y369010D03*
Y361209D03*
Y345609D03*
X277999Y347560D03*
X274619Y353409D03*
Y357309D03*
Y349509D03*
X277999Y343660D03*
X291519Y347560D03*
Y343660D03*
X288139Y365109D03*
X281379D03*
X284759Y363160D03*
X291519D03*
X284759Y370959D03*
X291519Y367060D03*
Y370959D03*
X288139Y361209D03*
X281379Y357309D03*
X288139Y345609D03*
Y380709D03*
Y400209D03*
X274619Y380709D03*
X277999Y394359D03*
X274619Y392410D03*
X277999Y390460D03*
Y386560D03*
X274619Y376809D03*
Y372909D03*
X291519Y374860D03*
X277999Y382660D03*
X284759Y398260D03*
X281379Y396309D03*
X291519Y398260D03*
X284759Y390460D03*
X291519D03*
X281379Y376809D03*
Y384609D03*
X284759Y382660D03*
X291519D03*
Y378760D03*
X264171Y510114D03*
X257478D03*
X260824Y515814D03*
Y491044D03*
X247177Y490514D03*
X252313D03*
X236892Y493400D03*
X243392Y493094D03*
X267584Y491219D03*
X271092Y495944D03*
X257392Y495800D03*
X264192D03*
X233292Y495900D03*
X239492Y498500D03*
X247177Y498514D03*
X252313D03*
X252289Y510100D03*
X267517Y515814D03*
X270864Y510114D03*
X247189Y517900D03*
X252313Y518114D03*
X247213Y510098D03*
X240596Y510114D03*
X243392Y515814D03*
X234053Y510114D03*
X237049Y515714D03*
X284024Y490644D03*
X289124D03*
X273860Y515714D03*
X277557Y495944D03*
X277407Y510114D03*
X289100Y510100D03*
X289124Y518114D03*
X284024Y510098D03*
X280203Y515814D03*
X273992Y491144D03*
X280203Y490644D03*
X284024Y498644D03*
X289124D03*
X284000Y517900D03*
X257478Y537049D03*
X237013Y530949D03*
X252339Y536750D03*
X243392Y531100D03*
X247213Y536999D03*
X252326Y528936D03*
X240746Y537049D03*
X234053Y536999D03*
X267517Y553614D03*
X270864Y547914D03*
X267517Y530949D03*
X270864Y536999D03*
X260824Y553614D03*
X237049Y553514D03*
X243392Y553614D03*
X264171Y547914D03*
X257478D03*
X252289Y547900D03*
X240596Y547914D03*
X247213Y547898D03*
X234053Y547914D03*
X264171Y537049D03*
X260824Y530949D03*
X247189Y555700D03*
X252313Y555914D03*
X270864Y574799D03*
Y585714D03*
X267517Y568749D03*
X247239Y566950D03*
X252326Y566736D03*
X234053Y574799D03*
X240746Y574849D03*
X247213Y574799D03*
X234053Y585714D03*
X237013Y568749D03*
X264171Y585714D03*
X257478D03*
X264171Y574849D03*
X257478D03*
X260824Y568749D03*
X252339Y574550D03*
X252289Y585700D03*
X240596Y585714D03*
X247213Y585698D03*
X243392Y568900D03*
X277407Y537049D03*
X273824Y530949D03*
X273860Y553514D03*
X284024Y547898D03*
X289100Y547900D03*
X280203Y553614D03*
Y531100D03*
X284024Y536999D03*
X289137Y528936D03*
X284050Y529150D03*
X289150Y536750D03*
X277407Y547914D03*
X273824Y568749D03*
X284000Y555700D03*
X289124Y555914D03*
X280203Y568900D03*
X277407Y574849D03*
Y585714D03*
X289100Y585700D03*
X289150Y574550D03*
X284024Y574799D03*
Y585698D03*
X284050Y566950D03*
X289137Y566736D03*
X284024Y612599D03*
X240746Y612649D03*
X247213Y612599D03*
X234053D03*
X257478Y612649D03*
X247239Y604750D03*
X252326Y604536D03*
X260824Y606549D03*
X237013D03*
X243392Y606700D03*
X264171Y612449D03*
X252339Y612350D03*
X267517Y591414D03*
X260824D03*
X237049Y591314D03*
X247189Y593500D03*
X252313Y593714D03*
X243392Y591414D03*
X267517Y606549D03*
X270864Y612399D03*
X273824Y606549D03*
X273860Y591314D03*
X284050Y604750D03*
X289150Y612350D03*
X280203Y606700D03*
Y591414D03*
X277407Y612449D03*
X289124Y593714D03*
X284000Y593500D03*
X289137Y604536D03*
X297635Y-7851D03*
X304328D03*
X300982Y-1751D03*
X294289D03*
X321061Y-1743D03*
X314368Y-1843D03*
X331100Y-4536D03*
X327754Y-7108D03*
X317714Y-9786D03*
X311021D03*
X314368Y9114D03*
X321061D03*
X331100D03*
X294289D03*
X300982D03*
X311021Y28014D03*
X304328Y29949D03*
X297635Y14814D03*
Y29949D03*
X304328Y14814D03*
X317714Y28014D03*
X311021Y17057D03*
X317714D03*
X327754D03*
Y28014D03*
X347833Y-7108D03*
X351179Y9122D03*
Y-4536D03*
X341140Y-1743D03*
X337793Y-9901D03*
X341140Y9122D03*
X347833Y17057D03*
Y28022D03*
X337793Y17057D03*
Y28014D03*
X311021Y65814D03*
X317714D03*
X321061Y35957D03*
X300982Y36049D03*
X294289Y46914D03*
X304328Y52614D03*
Y67749D03*
X297635D03*
X294289Y36049D03*
X300982Y46914D03*
X297635Y52614D03*
X314368Y35957D03*
Y46914D03*
X311021Y54857D03*
X317714D03*
X321061Y46914D03*
X331100D03*
X327754Y65814D03*
X331100Y35957D03*
X327754Y54857D03*
Y92757D03*
X331100Y84714D03*
Y73757D03*
X314368D03*
Y87392D03*
X311021Y89964D03*
X317714D03*
X321061Y87392D03*
Y73757D03*
X304278Y90414D03*
X300982Y84714D03*
X294289D03*
X300982Y73849D03*
X294289D03*
X297635Y90414D03*
X341140Y35957D03*
X337793Y65814D03*
Y54857D03*
X351179Y46922D03*
X347833Y54857D03*
X341140Y46922D03*
X347833Y65822D03*
X351179Y35957D03*
X347833Y92757D03*
X351179Y84599D03*
Y73757D03*
X337793Y89964D03*
X341140Y87392D03*
Y73757D03*
X326592Y105600D03*
X313637Y105725D03*
X300992Y112300D03*
X297642Y107700D03*
X304192Y105000D03*
X294899Y213009D03*
X308418Y201309D03*
X317428Y193507D03*
X301648Y194841D03*
X332078Y218860D03*
X329818Y214958D03*
X298279Y218860D03*
X311798Y211060D03*
Y218860D03*
Y214960D03*
X308418Y213009D03*
X305039Y211060D03*
Y218860D03*
X324200Y201308D03*
X298279Y199360D03*
X294899Y201309D03*
X312918Y205210D03*
X315178Y209109D03*
X298279Y207159D03*
Y203260D03*
Y211060D03*
X318558Y218860D03*
X315178Y216909D03*
Y213009D03*
X301659Y209109D03*
X325318Y211060D03*
X338838Y218860D03*
X345598Y214960D03*
X352357D03*
X334328Y199108D03*
X345598Y203260D03*
X355737Y205210D03*
X338838Y211058D03*
X335458Y216909D03*
X294899Y224709D03*
X332078Y242260D03*
Y250060D03*
X328698Y232509D03*
Y220809D03*
X332078Y234460D03*
X298279Y246160D03*
X325318Y250060D03*
X321938Y248109D03*
X305039Y246160D03*
X308418Y244209D03*
X294899D03*
Y248109D03*
X325318Y242260D03*
Y226660D03*
X298279Y234460D03*
X308418Y228610D03*
Y224709D03*
X305039Y230559D03*
X311798Y222760D03*
X308418Y232509D03*
X294899Y228610D03*
X325318Y234460D03*
Y230559D03*
Y222760D03*
X305039Y250060D03*
X318558Y246160D03*
X301659Y248109D03*
X308418Y240309D03*
X315178D03*
X301659D03*
X318558Y242260D03*
X298279Y226660D03*
X318558D03*
X315178Y220809D03*
X321938D03*
X315178Y232509D03*
X301659Y228610D03*
X308418Y236409D03*
X321938D03*
X311798Y238360D03*
X318558D03*
X305039Y226660D03*
X308418Y252009D03*
X298279Y253960D03*
X325318D03*
X308418Y275409D03*
X301659D03*
X308418Y255909D03*
X321938Y275409D03*
X315178Y279310D03*
X318558Y277360D03*
X311798Y261760D03*
X321938Y259809D03*
X301659D03*
X308418Y263709D03*
X325318Y269560D03*
X305039D03*
X318558D03*
X328698Y267609D03*
Y259809D03*
X332078Y269560D03*
X321938Y255909D03*
X308418Y259809D03*
X325318Y273460D03*
Y265660D03*
X301659Y267609D03*
X321938Y263709D03*
X294899Y275409D03*
Y263709D03*
X298279Y265660D03*
X305039Y273460D03*
Y277360D03*
X311798D03*
Y269560D03*
X305039Y265660D03*
X298279Y277360D03*
X328698Y252009D03*
X342218Y244209D03*
Y232509D03*
X355737Y244209D03*
X348978D03*
X345598Y226660D03*
X352357D03*
X348978Y232509D03*
X355737D03*
X338838Y246160D03*
X335458Y248109D03*
X338838Y242260D03*
Y234460D03*
X335458Y236409D03*
X338838Y238360D03*
X335458Y224709D03*
X355737Y248109D03*
X348978D03*
X338838Y253960D03*
X335458Y252009D03*
X338838Y265660D03*
X335458Y259809D03*
Y267609D03*
X345598Y265660D03*
X348978Y263709D03*
X355737Y259809D03*
X352357Y261760D03*
X345598Y273460D03*
Y269560D03*
X342218Y263709D03*
Y271509D03*
Y259809D03*
Y255909D03*
Y267609D03*
Y279310D03*
Y275409D03*
X311798Y292959D03*
X305039D03*
X321938Y283209D03*
X315178D03*
X318558Y281260D03*
Y292959D03*
X311798Y285160D03*
X328698Y310509D03*
X332078Y300760D03*
X328698Y283209D03*
X332078Y292959D03*
Y281260D03*
X298279Y308560D03*
X321938Y310509D03*
X315178D03*
X305039Y308560D03*
X311798D03*
X305039Y300760D03*
X325318D03*
X311798D03*
X298279D03*
X318558D03*
X325318Y292959D03*
Y281260D03*
X305039Y285160D03*
X298279D03*
Y292959D03*
X318558Y312460D03*
X325318D03*
X308418Y333909D03*
Y341709D03*
X325318Y339760D03*
Y335860D03*
X301659Y337809D03*
X315178Y330009D03*
X301659D03*
X308418Y337809D03*
X305039Y331960D03*
X298279Y328060D03*
Y331960D03*
X311798Y324160D03*
X308418Y330009D03*
X315178Y322209D03*
X321938D03*
X294899Y333909D03*
X305039Y328060D03*
X321938Y330009D03*
Y337809D03*
X328698Y330009D03*
Y326110D03*
Y333909D03*
X325318Y324160D03*
X318558Y320260D03*
X301659Y318309D03*
X308418D03*
X305039Y316360D03*
X332078Y331960D03*
Y339760D03*
X298279Y316360D03*
X294899Y322209D03*
Y318309D03*
X311798Y316360D03*
X308418Y326110D03*
X315178Y314409D03*
X332078Y312460D03*
X335458Y310509D03*
X338838Y300760D03*
Y292959D03*
Y281260D03*
X335458Y283209D03*
X342218Y310509D03*
Y283209D03*
X345598Y335860D03*
Y331960D03*
X342218Y314409D03*
X338838Y312460D03*
Y316360D03*
X335458Y330009D03*
X338838Y331960D03*
Y339760D03*
X345598Y328060D03*
Y339760D03*
X352357Y335860D03*
X348978Y333909D03*
X342218Y322209D03*
Y318309D03*
Y330009D03*
Y326110D03*
Y333909D03*
X355737Y337809D03*
X345598Y320260D03*
Y324160D03*
X308418Y357309D03*
X311798Y359260D03*
X298279Y351460D03*
X294899Y349509D03*
Y353409D03*
X321938Y349509D03*
X318558Y359260D03*
X321938Y361209D03*
X298279Y343660D03*
X315178Y357309D03*
X301659D03*
Y349509D03*
X308418Y361209D03*
Y353409D03*
Y345609D03*
X305039Y347560D03*
X325318Y343660D03*
Y347560D03*
X328698Y365109D03*
X332078Y363160D03*
X328698Y345609D03*
X325318Y355360D03*
X332078Y347560D03*
Y355360D03*
X294899Y369010D03*
X325318Y367060D03*
Y370959D03*
X318558D03*
X308418Y365109D03*
X315178D03*
X325318Y363160D03*
X298279D03*
X305039Y370959D03*
X308418Y369010D03*
X305039Y367060D03*
X301659Y369010D03*
X298279Y370959D03*
X318558Y351460D03*
Y355360D03*
X305039Y351460D03*
X301659Y388509D03*
X308418D03*
X318558Y394359D03*
X324458Y399911D03*
X332078Y378760D03*
X318558Y386560D03*
X325318D03*
X311798Y374860D03*
X325318D03*
X294899Y372909D03*
X308418D03*
X321938Y376809D03*
X318558Y382660D03*
Y378760D03*
X298279D03*
X305039D03*
X308418Y384609D03*
X311798Y382660D03*
Y378760D03*
X315178Y376809D03*
X328698D03*
X294899Y384609D03*
X318558Y390460D03*
X320808Y401941D03*
X298279Y386560D03*
Y390460D03*
X315178Y392410D03*
Y388509D03*
X311798Y386560D03*
X298279Y398260D03*
Y394359D03*
X294899Y396309D03*
X325318Y378760D03*
X321938Y380709D03*
X305039Y394359D03*
X302608Y402421D03*
X345598Y370959D03*
X355737Y353409D03*
X348978D03*
X342218Y365109D03*
X338838Y347560D03*
X335458Y361209D03*
X338838Y359260D03*
Y355360D03*
Y351460D03*
X335458Y349509D03*
X345598Y343660D03*
X342218Y345609D03*
Y353409D03*
X338838Y367060D03*
X348978Y365109D03*
X355737D03*
X352357Y370959D03*
X345598Y382660D03*
X352357D03*
X348978Y392410D03*
X355737D03*
X335458Y372909D03*
Y384609D03*
Y380709D03*
X294289Y490444D03*
X301092Y490700D03*
X326797Y499767D03*
X317714Y515364D03*
X321061Y512792D03*
X311701Y499136D03*
X331100Y510114D03*
X327754Y518157D03*
X314368Y512792D03*
X311021Y515364D03*
X297835Y497644D03*
X300982Y510114D03*
X304278Y515814D03*
X297635D03*
X294289Y510114D03*
X304392Y497300D03*
X337793Y515364D03*
X350882Y509999D03*
X347833Y518157D03*
X341140Y512792D03*
X321061Y536957D03*
X317714Y529014D03*
X331100Y547914D03*
Y536957D03*
X327754Y529014D03*
X321061Y547914D03*
X314368D03*
Y536957D03*
X311021Y529014D03*
X304278Y553614D03*
X297635D03*
X300982Y547914D03*
X294289D03*
X304328Y530949D03*
X300982Y537049D03*
X297635Y530949D03*
X294289Y537049D03*
Y574849D03*
Y585714D03*
X304328Y568749D03*
X300982Y574849D03*
Y585714D03*
X297635Y568749D03*
X327754Y555857D03*
X317714D03*
X311021D03*
X327754Y566814D03*
X331100Y574757D03*
Y585714D03*
X314368D03*
Y574757D03*
X317714Y566814D03*
X311021D03*
X321061Y585714D03*
Y574757D03*
X337793Y529014D03*
X351179Y547922D03*
Y536957D03*
X347833Y529022D03*
X341140Y547922D03*
Y536957D03*
X337793Y555857D03*
X347833D03*
X337793Y566814D03*
X341140Y574757D03*
Y585722D03*
X351179Y574757D03*
Y585722D03*
X347833Y566822D03*
X304328Y606549D03*
X297635D03*
X294289Y612249D03*
X300982D03*
X304278Y591414D03*
X297635D03*
X327754Y607292D03*
X331100Y609864D03*
X327754Y593657D03*
X317714D03*
X311021D03*
X317714Y604614D03*
X311021D03*
X314368Y612457D03*
X321061D03*
X337793Y593657D03*
Y604499D03*
X352109Y609918D03*
X347833Y607292D03*
X341140Y612457D03*
X347833Y593657D03*
X357872Y-9786D03*
X367911D03*
Y-1858D03*
X357872D03*
X367911Y9114D03*
X357672D03*
X357872Y28014D03*
X367911D03*
Y17042D03*
X357872Y17014D03*
X398029Y-4536D03*
X401375Y-7108D03*
X408068Y-1743D03*
X411415Y-9786D03*
X398029Y9107D03*
X408069D03*
X409522Y-20794D03*
X411416Y17057D03*
X401376Y17042D03*
X367911Y46914D03*
Y54842D03*
Y35942D03*
X358619Y36031D03*
X358618Y54842D03*
X357872Y65736D03*
X366992Y65950D03*
X357872Y46914D03*
X357965Y92500D03*
X367911Y87500D03*
X368311Y92500D03*
X367742Y73450D03*
X357872Y87500D03*
X358491Y73479D03*
X408069Y35942D03*
X401376Y54842D03*
X408069Y46907D03*
X398029Y35942D03*
Y46907D03*
X411416Y54857D03*
X401375Y92757D03*
X398029Y84800D03*
Y73742D03*
X408068Y87392D03*
X411415Y89964D03*
X408069Y73742D03*
X408126Y105750D03*
X414820Y105800D03*
X401375D03*
X357987Y193507D03*
X378267D03*
X386157Y207159D03*
X382777Y201309D03*
X365877Y214960D03*
X372637D03*
X379397D03*
X359117D03*
X365877Y203260D03*
X376017Y205211D03*
X362497Y205210D03*
X386157Y214960D03*
X415634Y204496D03*
Y212296D03*
X404392Y199100D03*
X415634Y208397D03*
X392898Y195041D03*
X392916Y214960D03*
Y203260D03*
X396296Y197359D03*
X399676Y203260D03*
Y214960D03*
X386157Y226660D03*
X389537Y232509D03*
X369257Y244209D03*
X362497D03*
X379397Y250060D03*
X386157Y238360D03*
X372637Y226660D03*
X365877D03*
X369257Y232509D03*
X362497D03*
X379397Y226660D03*
X382777Y232509D03*
X376017D03*
X359117Y226660D03*
X372637Y250060D03*
X389537Y248109D03*
X376017D03*
X382777D03*
X386157Y250060D03*
X365877Y253960D03*
X362497Y255909D03*
X359117Y257860D03*
X369257Y252009D03*
X392916Y250060D03*
Y238360D03*
X396296Y248109D03*
X399676Y250060D03*
X407706Y248109D03*
Y240309D03*
Y232509D03*
X415634Y247396D03*
Y235696D03*
Y223996D03*
X392916Y226660D03*
X396296Y232509D03*
X399676Y226660D03*
X370650Y312441D03*
X378156D03*
X375674D03*
X373162Y312400D03*
X368165Y312504D03*
X359117Y339760D03*
X362497Y341709D03*
X382777Y349509D03*
X379397Y347560D03*
Y370959D03*
X372637D03*
X365877D03*
X359117D03*
X386157D03*
X362497Y353409D03*
X376017D03*
X369257D03*
Y345609D03*
X376017D03*
X386157Y351460D03*
X372637Y347560D03*
X389537Y353409D03*
X365877Y343660D03*
X389537Y365109D03*
X382777D03*
X369257D03*
X362497D03*
X376017D03*
X390657Y394359D03*
X391787Y402800D03*
X357987D03*
X369257Y392410D03*
X362497D03*
X379397Y382660D03*
X372637D03*
X365877D03*
X359117D03*
X379397Y390460D03*
X378267Y402800D03*
X376017Y392410D03*
X386157Y382660D03*
X396296Y353409D03*
X411086Y351460D03*
X405306Y347109D03*
X399676Y351460D03*
X392916Y370959D03*
X399676D03*
X396296Y365109D03*
X403056D03*
Y357309D03*
X392916Y351460D03*
Y382660D03*
Y390460D03*
X399676Y382660D03*
X406568Y402471D03*
X403056Y392410D03*
X411086Y374860D03*
X386630Y521860D03*
X359042Y515200D03*
X358918Y510114D03*
X366865D03*
Y515152D03*
X401375Y518157D03*
X398029Y509999D03*
X411415Y515364D03*
X408068Y512792D03*
X370080Y555700D03*
X366890Y586000D03*
X367692Y547914D03*
X357672D03*
X357872Y528942D03*
X367911Y529057D03*
X367692Y536200D03*
X357910Y536727D03*
X367211Y555842D03*
X357910D03*
X367192Y566814D03*
X357910D03*
X367192Y574742D03*
X357872D03*
X357025Y585714D03*
X398029Y536942D03*
X408069Y547907D03*
Y536942D03*
X398029Y547907D03*
X401376Y555842D03*
X411416Y555857D03*
X398029Y574742D03*
Y585707D03*
X408069D03*
Y574742D03*
X408068Y612657D03*
X413324Y623559D03*
X399824D03*
X357872Y604614D03*
X367170Y611759D03*
X357872Y612242D03*
X367911Y593642D03*
X357026D03*
X367911Y604614D03*
X398029Y609864D03*
X401376Y593642D03*
X401375Y607292D03*
X411416Y593657D03*
X411415Y604614D03*
X418108Y-4536D03*
X431494D03*
X424801D03*
X428147Y-7108D03*
X434840D03*
X431494Y9107D03*
X424801D03*
X418108D03*
Y-9701D03*
X441533Y-1843D03*
Y9107D03*
X447744Y-7180D03*
X451573Y-1801D03*
Y9114D03*
X436392Y-20760D03*
X422892Y-20789D03*
X434842Y17057D03*
X441533Y17042D03*
X418108D03*
X428149Y17057D03*
X448226Y28100D03*
X448292Y31900D03*
Y13700D03*
X448892Y17000D03*
X418108Y28007D03*
X441533D03*
X458266Y-1751D03*
X460912Y-7700D03*
X454533Y-7851D03*
X458116Y9114D03*
X469832Y-2051D03*
X464732Y-1801D03*
X474998Y-1751D03*
X469845Y-9864D03*
X478344Y-7851D03*
X464758Y-9652D03*
X474998Y9114D03*
X464732Y9098D03*
X478344Y29949D03*
X460912Y30100D03*
Y14814D03*
X469832Y17114D03*
X454569Y14714D03*
X454533Y29949D03*
X469792Y9300D03*
X478344Y14814D03*
X469845Y27936D03*
X464792Y28100D03*
X464692Y16900D03*
X434842Y54857D03*
X441533Y54842D03*
X424801Y46907D03*
X431494D03*
X428149Y54857D03*
X441533Y46907D03*
X448414Y35761D03*
X448973Y54883D03*
X451573Y35999D03*
X448627Y68090D03*
X448517Y46975D03*
X448492Y51000D03*
X451573Y46900D03*
X418108Y65807D03*
Y54842D03*
X441533Y65807D03*
X431494Y35942D03*
X441533D03*
X424801D03*
X418108D03*
Y46907D03*
X428147Y92500D03*
X424801Y84800D03*
X431400D03*
X431494Y73742D03*
X441533Y87392D03*
Y92500D03*
Y73742D03*
X418108Y89964D03*
Y84599D03*
Y73742D03*
X424801D03*
X434840Y92500D03*
X448651Y70896D03*
X451573Y84714D03*
Y73799D03*
X448610Y85296D03*
X448599Y73589D03*
X448692Y89900D03*
X474998Y36049D03*
X464732Y46898D03*
X460912Y52614D03*
X458266Y36049D03*
X458116Y46914D03*
X464758Y65950D03*
X474998Y46914D03*
X454533Y67749D03*
X454569Y52514D03*
X469832Y54914D03*
X469792Y47100D03*
Y35800D03*
X464692Y54700D03*
X464732Y35999D03*
X478344Y52614D03*
X460912Y67900D03*
X478344Y67749D03*
X469845Y65736D03*
X458116Y84714D03*
X464708Y92500D03*
X464732Y84698D03*
X469808Y84700D03*
X474998Y73849D03*
X469858Y73550D03*
X474998Y84714D03*
X478344Y90414D03*
X469832Y92714D03*
X460912Y90314D03*
X464732Y73799D03*
X458266Y73849D03*
X454569Y90314D03*
X427696Y105800D03*
X421503D03*
X441743Y199841D03*
X421464Y199583D03*
X446253Y206446D03*
X425974D03*
X453013Y218147D03*
X449633Y212296D03*
Y216196D03*
X422594D03*
X419214Y214247D03*
X436113Y212296D03*
X432733Y214247D03*
X429354Y216196D03*
X432733Y218147D03*
X425974D03*
X429353Y212296D03*
X446253Y218147D03*
X442873Y216196D03*
X439493Y214247D03*
X436113Y216196D03*
X453013Y214247D03*
X439493Y210346D03*
X434983Y198931D03*
X455263Y198050D03*
X473292Y218147D03*
X469913Y216196D03*
X469912Y212296D03*
X475692Y199900D03*
X466533Y218147D03*
X473292Y214247D03*
X476672Y212296D03*
Y216196D03*
X459773Y214247D03*
X466533Y206446D03*
X456393Y216196D03*
X462023Y198327D03*
X456393Y212296D03*
X463153Y216196D03*
X429354Y251296D03*
X453013Y245447D03*
Y229847D03*
Y237647D03*
X449633Y251296D03*
Y247396D03*
Y227896D03*
Y223996D03*
X436113Y243496D03*
X442873D03*
X422594D03*
X425974Y245447D03*
Y249347D03*
X432733D03*
X436113Y251296D03*
X429354Y247396D03*
X422594Y251296D03*
X446253Y245447D03*
X419214Y249347D03*
X432733Y245447D03*
X439493Y237647D03*
X446253D03*
X422594Y223996D03*
Y231797D03*
X419214Y233746D03*
Y237647D03*
X436113Y231797D03*
X439493Y241547D03*
X419214D03*
X436113Y223996D03*
X429354D03*
Y220096D03*
Y227896D03*
X446253Y229847D03*
X432733D03*
X425974D03*
X439493Y233746D03*
X442873Y231797D03*
Y223996D03*
X425974Y237647D03*
X432733D03*
X449633Y220096D03*
X439493Y253247D03*
X449633Y255196D03*
Y259096D03*
X446253Y257147D03*
X442873Y255196D03*
X453013Y257147D03*
Y261047D03*
X448900Y269600D03*
X469913Y251296D03*
X466533Y245447D03*
X473292D03*
X476672Y223996D03*
Y243496D03*
Y251296D03*
X469913Y247396D03*
Y223996D03*
X473292Y229847D03*
X469913Y227896D03*
X466533Y229847D03*
X473292Y237647D03*
X466533D03*
X469913Y220096D03*
X456393Y243496D03*
Y251296D03*
X459773Y233746D03*
Y241547D03*
Y237647D03*
X456393Y223996D03*
Y231797D03*
X476672D03*
X463153Y243496D03*
Y251296D03*
Y231797D03*
Y223996D03*
X476672Y259096D03*
X463153D03*
X458408Y278940D03*
X477792Y272747D03*
X462023Y271097D03*
X458643Y269146D03*
X456393Y262996D03*
Y259096D03*
X459773Y261047D03*
X469913Y255196D03*
X473292Y257147D03*
X466533D03*
X468783Y274997D03*
X469913Y270796D03*
X466533Y264947D03*
X469913Y305896D03*
X477792Y307851D03*
X469913Y286396D03*
X477792Y303947D03*
Y288347D03*
Y315647D03*
Y319547D03*
X458643Y338746D03*
X477792Y327347D03*
X462948Y315251D03*
X455263Y340697D03*
X462848Y312741D03*
X467653Y340996D03*
X474413D03*
Y337096D03*
X469913Y321496D03*
X443993Y358547D03*
X441743Y348497D03*
X440613Y352696D03*
X437233Y358547D03*
X450753Y366347D03*
Y350747D03*
Y358547D03*
X437233Y362447D03*
X423714D03*
X433854Y368296D03*
X427094D03*
X440613Y364396D03*
X427094Y372197D03*
X447373D03*
Y368296D03*
X440613Y372197D03*
Y368296D03*
X443993Y366347D03*
X427094Y356596D03*
X433854Y352696D03*
X437233Y354647D03*
X423714D03*
X430474D03*
X427094Y360496D03*
X433854D03*
X445123Y346546D03*
X427094Y352696D03*
X430474Y385847D03*
X450753Y397547D03*
X440613Y395595D03*
X429354Y399496D03*
X433854Y379996D03*
X423714Y374146D03*
X437233D03*
X430474Y378047D03*
X433854Y376096D03*
X443993Y397546D03*
Y401447D03*
Y393647D03*
X440613Y391696D03*
X443993Y385847D03*
X427094Y376096D03*
X437233Y381947D03*
X447373Y376096D03*
X440613Y379996D03*
X443993Y378047D03*
X423715Y397548D03*
X430474Y393647D03*
X433854Y391696D03*
X423715Y401449D03*
X450753Y385847D03*
Y393647D03*
Y378047D03*
X437233Y389747D03*
Y385847D03*
X423714D03*
X477792Y342947D03*
Y362447D03*
Y354647D03*
Y358547D03*
X457513Y362447D03*
X454133Y372197D03*
Y364396D03*
Y348796D03*
Y352696D03*
X464273Y366347D03*
X474413Y372197D03*
X471033Y366347D03*
X467653Y372197D03*
X474413Y364396D03*
X464273Y350747D03*
X474413Y348796D03*
X471033Y350747D03*
X474413Y352696D03*
X471033Y358547D03*
X464273D03*
X467653Y368296D03*
Y348796D03*
X460893Y372197D03*
Y364396D03*
Y352696D03*
X457513Y354647D03*
Y358547D03*
Y346847D03*
X477792Y389747D03*
X457513D03*
X471033Y393647D03*
X460893Y395595D03*
X464273Y401447D03*
X471033D03*
X460893Y391696D03*
X457513Y385847D03*
Y381947D03*
X460893Y379996D03*
X477792Y381947D03*
X474413Y391696D03*
X464273Y385847D03*
X454133Y391696D03*
Y379996D03*
X471033Y385847D03*
X464273Y393647D03*
X474413Y379996D03*
X471033Y378047D03*
X467653Y376096D03*
X464273Y378047D03*
Y397546D03*
X477792Y385847D03*
X447091Y407782D03*
X428224Y407800D03*
X443993Y405347D03*
X467653Y407296D03*
X464273Y405347D03*
X441533Y512792D03*
Y518057D03*
X433192Y497650D03*
X434840Y518157D03*
X431494Y509999D03*
X424801Y510114D03*
X418108Y515364D03*
Y509999D03*
X428147Y518157D03*
X451573Y510114D03*
X448692Y515300D03*
X474998Y510114D03*
X464732Y510098D03*
X460912Y515714D03*
X458116Y510114D03*
X454569Y515714D03*
X478344Y515814D03*
X464708Y517900D03*
X469832Y518114D03*
X418108Y536942D03*
Y547907D03*
X431494D03*
X424801D03*
X441533D03*
X418108Y529007D03*
X431494Y536942D03*
X424801D03*
X441533Y536957D03*
Y529007D03*
X451573Y547914D03*
Y536999D03*
X448510Y549843D03*
X448410Y531156D03*
X448432Y536723D03*
X448692Y553100D03*
X448557Y534061D03*
X451573Y585714D03*
Y574799D03*
X448226Y569200D03*
X448291Y574773D03*
X418108Y555842D03*
X428149Y555857D03*
X434842D03*
X441533Y555842D03*
Y585707D03*
Y574742D03*
X418108Y566807D03*
X441533D03*
X424801Y574742D03*
X418108Y585599D03*
Y574742D03*
X431494D03*
Y585707D03*
X424801D03*
X464732Y536999D03*
X460912Y553514D03*
X458116Y547914D03*
X454569Y553514D03*
X454533Y530949D03*
X460912Y531100D03*
X458266Y537049D03*
X469845Y528936D03*
X474998Y537049D03*
X464758Y529150D03*
X469858Y536750D03*
X478344Y553614D03*
X464732Y547898D03*
X474998Y547914D03*
X469808Y547900D03*
X478344Y530949D03*
Y568749D03*
X464732Y574799D03*
X469808Y585700D03*
X469858Y574550D03*
X474998Y574849D03*
Y585714D03*
X464732Y585698D03*
X464758Y566950D03*
X469845Y566736D03*
X458266Y574849D03*
X460912Y568900D03*
X458116Y585714D03*
X454533Y568749D03*
X464708Y555700D03*
X469832Y555914D03*
X441533Y612557D03*
X474998Y612649D03*
X464732Y612599D03*
X458266Y612649D03*
X427324Y623541D03*
X451573Y612599D03*
X441533Y607292D03*
X434840D03*
X428147D03*
X418108Y609864D03*
X424801D03*
X447744Y607220D03*
X448692Y590900D03*
X431494Y609864D03*
X418108Y593642D03*
X434842Y593657D03*
X428149D03*
X441533Y593642D03*
X418108Y604499D03*
X478344Y591414D03*
X464708Y593500D03*
X469832Y593714D03*
X464758Y604750D03*
X469845Y604536D03*
X478344Y606549D03*
X469858Y612350D03*
X460912Y591314D03*
Y606700D03*
X454533Y606549D03*
X454569Y591314D03*
X511809Y-1751D03*
Y9114D03*
X495077Y-1751D03*
X501544Y-1801D03*
X506692Y-2000D03*
X488384Y-1801D03*
X481691Y-1751D03*
X485037Y-7851D03*
X491344D03*
X506657Y-9864D03*
X497723Y-7700D03*
X501592Y-9700D03*
X481691Y9114D03*
X494927D03*
X488384D03*
X501544Y9098D03*
X497723Y14814D03*
X506644Y17114D03*
X506657Y27936D03*
X497723Y30100D03*
X491380Y14714D03*
X506604Y9300D03*
X485037Y14814D03*
X501504Y16900D03*
X485037Y29949D03*
X491344D03*
X501603Y28100D03*
X515155Y-7851D03*
X538355Y9098D03*
X518502Y-1751D03*
X521848Y-7851D03*
X538355Y-1801D03*
X531888Y-1751D03*
X525195Y-1801D03*
X538403Y-9700D03*
X528155Y-7851D03*
X534534Y-7700D03*
X518502Y9114D03*
X531738D03*
X525195D03*
X521848Y14814D03*
Y29949D03*
X528191Y14714D03*
X538315Y16900D03*
X534534Y30100D03*
X515155Y29949D03*
Y14814D03*
X534534D03*
X528155Y29949D03*
X538415Y28100D03*
X488384Y35999D03*
X501492Y54700D03*
X497723Y52614D03*
Y67900D03*
X501544Y46898D03*
X511809Y46914D03*
X491344Y67749D03*
X506657Y65736D03*
X501570Y65950D03*
X481691Y36049D03*
X495077D03*
X506644Y54914D03*
X494927Y46914D03*
X485037Y52614D03*
X481691Y46914D03*
X511809Y36049D03*
X485037Y67749D03*
X488384Y46914D03*
X506603Y35800D03*
X506592Y47000D03*
X501544Y35999D03*
X511809Y84714D03*
X501544Y84698D03*
X494927Y84714D03*
X506670Y73550D03*
X481691Y84714D03*
X488384D03*
X501520Y92500D03*
X506620Y84700D03*
X511809Y73849D03*
X488384Y73799D03*
X481691Y73849D03*
X506644Y92714D03*
X491380Y90314D03*
X497723Y90414D03*
X485037D03*
X495077Y73849D03*
X501544Y73799D03*
X518502Y36049D03*
Y46914D03*
X521848Y67749D03*
X531888Y36049D03*
X538355Y35999D03*
X534534Y52614D03*
X531738Y46914D03*
X525195Y35999D03*
X515155Y67749D03*
Y52614D03*
X521848D03*
X534534Y67900D03*
X538381Y65950D03*
X528155Y67749D03*
X538355Y46898D03*
X538304Y54700D03*
X525195Y46914D03*
X515155Y90414D03*
X534534D03*
X528191Y90314D03*
X521848Y90414D03*
X518502Y73849D03*
Y84714D03*
X531738D03*
X525195D03*
X538355Y84698D03*
X538331Y92500D03*
X531888Y73849D03*
X525195Y73799D03*
X538355D03*
X512024Y104314D03*
X497723Y109564D03*
X501544Y113114D03*
X506670Y112865D03*
X501570Y105265D03*
X491430Y109564D03*
X506657Y105051D03*
X488634Y104314D03*
X495077D03*
X514820Y109564D03*
X521113D03*
X528191Y109914D03*
X534534Y109564D03*
X538355Y113114D03*
X531738Y104314D03*
X525134D03*
X538381Y105265D03*
X518467Y104314D03*
X511592Y206447D03*
Y210346D03*
Y218147D03*
X486812Y214247D03*
Y218147D03*
X498350Y209900D03*
X501452Y212296D03*
X480052Y214247D03*
Y206447D03*
X486812Y210346D03*
X508212Y212296D03*
X518352Y218147D03*
Y206445D03*
X538631Y210346D03*
Y214247D03*
Y206447D03*
X528491Y208397D03*
X525111Y218147D03*
X528491Y216196D03*
X535251Y204496D03*
X525111Y206447D03*
X531871D03*
X521731Y208397D03*
X511592Y241547D03*
Y249347D03*
X486812Y245447D03*
X494692Y247396D03*
X483432Y251296D03*
X501452Y247396D03*
X480052Y237647D03*
X508212Y239596D03*
X498072Y233746D03*
X486812D03*
Y229847D03*
X494692Y235696D03*
X504832Y229847D03*
X486812Y225947D03*
X498072Y222047D03*
Y225947D03*
X486812Y222047D03*
Y237647D03*
X480052Y233746D03*
X504832Y241547D03*
X480052D03*
X486812D03*
X494692Y243496D03*
X483432D03*
X504832Y245447D03*
X501452Y223996D03*
X508212Y231797D03*
Y220096D03*
Y223996D03*
X483432Y235696D03*
Y223996D03*
X494692Y251296D03*
X501452Y274696D03*
X508212Y278596D03*
X484552Y268847D03*
X494692Y255196D03*
X486812Y257147D03*
X504832Y253247D03*
X487932Y278596D03*
Y274696D03*
X494692Y278596D03*
X501452Y266896D03*
Y259096D03*
X483432D03*
X481172Y274696D03*
Y278596D03*
X508212Y270796D03*
X494692D03*
X480052Y261047D03*
X518352Y229847D03*
X521731Y231797D03*
Y235696D03*
Y247396D03*
Y220096D03*
X538631Y225947D03*
Y222047D03*
Y237647D03*
X528491Y247396D03*
Y243496D03*
X538631Y249347D03*
X535251Y235696D03*
X528491Y227896D03*
Y235696D03*
Y220096D03*
X535251Y247396D03*
Y251296D03*
Y239596D03*
X531871Y222047D03*
X525111Y237647D03*
X514972Y247396D03*
Y227896D03*
Y235696D03*
Y239596D03*
Y223996D03*
X535251Y259096D03*
X531871Y261047D03*
X514972Y270796D03*
Y278596D03*
X525111Y253247D03*
X518352D03*
X528491Y274696D03*
X531871Y268847D03*
Y276646D03*
X535251Y266896D03*
X525111Y280547D03*
X521731Y266896D03*
Y259096D03*
Y274696D03*
X538631Y257147D03*
X504832Y307847D03*
X525111Y315647D03*
X494692Y294196D03*
X501452Y290296D03*
Y282496D03*
X491312Y292245D03*
Y300047D03*
X508212Y290296D03*
Y294196D03*
X511592Y307847D03*
Y284447D03*
X481172Y309797D03*
X494692D03*
X481172Y301996D03*
X487932Y309797D03*
X498072Y303947D03*
X487932Y282496D03*
X484552Y300047D03*
Y292245D03*
X494692Y286396D03*
X501452Y298096D03*
X481172Y290296D03*
X508212Y329296D03*
X487932Y317596D03*
X504832Y319547D03*
X484552Y323446D03*
X508212Y317596D03*
Y325396D03*
X491312Y339047D03*
X494692Y337096D03*
X511592Y327347D03*
Y339047D03*
Y331247D03*
Y335147D03*
Y315647D03*
Y323446D03*
X508212Y313696D03*
X481172D03*
X494692Y340996D03*
X504832Y331247D03*
X508212Y337096D03*
Y333196D03*
X504832Y335147D03*
X501452Y333196D03*
X504832Y339047D03*
X501452Y340996D03*
X504832Y315647D03*
X498072Y319547D03*
X504832Y323446D03*
X498072Y327347D03*
X491312Y331247D03*
X511592Y319547D03*
X538631Y311747D03*
X535251Y290296D03*
X514972Y301996D03*
Y290296D03*
Y286396D03*
Y294196D03*
X525111Y284447D03*
X531871Y288347D03*
Y292245D03*
X528491Y294196D03*
X525111Y300047D03*
X531871D03*
X521731Y301996D03*
X528491Y286396D03*
Y298096D03*
X535251Y294196D03*
X538631Y292245D03*
Y288347D03*
Y284447D03*
X531871Y303947D03*
X535251Y301996D03*
X531871Y311747D03*
Y307847D03*
X535251Y309797D03*
X514972Y333196D03*
Y321496D03*
Y317596D03*
Y329296D03*
Y325396D03*
Y337096D03*
X518352Y319547D03*
Y323446D03*
Y315647D03*
X521731Y317596D03*
Y325396D03*
X518352Y327347D03*
Y339047D03*
X531871Y335147D03*
X525111D03*
X528491Y337096D03*
X531871Y327347D03*
X535251Y329296D03*
X538631Y335147D03*
Y339047D03*
X528491Y317596D03*
X531871Y319547D03*
X535251Y321496D03*
X538631Y319547D03*
X504832Y342947D03*
X491312Y370247D03*
X498072Y366347D03*
X494692Y372197D03*
X504832Y366347D03*
X501452Y368296D03*
X487932D03*
X484552Y362447D03*
X498072D03*
X491312D03*
X494692Y360496D03*
X487932D03*
X501452Y344896D03*
X504832Y354647D03*
X494692Y344896D03*
Y348796D03*
X491312Y350747D03*
Y366347D03*
X487932Y372197D03*
X484552Y370247D03*
X481172Y372197D03*
X484552Y366347D03*
X487932Y364396D03*
X494692D03*
X501452D03*
X491312Y358547D03*
X498072Y350747D03*
Y346847D03*
X501452Y360496D03*
X498072Y342947D03*
X491312Y346847D03*
X494692Y356596D03*
X498072Y358547D03*
Y354647D03*
X481172Y344896D03*
Y360496D03*
X484552Y346847D03*
X508212Y352696D03*
Y360496D03*
X504832Y346847D03*
Y358547D03*
X501452Y356596D03*
Y348796D03*
Y352696D03*
X511592Y370247D03*
X481172Y352696D03*
X484552Y393647D03*
X481172Y391696D03*
X484552Y385847D03*
X498072Y393647D03*
X494692Y391696D03*
X491312Y385847D03*
X498072D03*
X508212Y387796D03*
X501452Y391696D03*
Y395597D03*
X491312Y389747D03*
X504832Y381947D03*
Y378047D03*
X501452Y379996D03*
X481172Y395596D03*
X511592Y378047D03*
Y397546D03*
X491312Y378047D03*
X484552D03*
X481172Y379996D03*
X487932Y376096D03*
X491312Y381947D03*
Y374146D03*
X498072Y397546D03*
X487932Y403396D03*
Y399496D03*
X491312Y397546D03*
X487932Y395597D03*
X514972Y372197D03*
Y356596D03*
X521731Y360496D03*
Y356596D03*
Y348796D03*
X518352Y342947D03*
Y362447D03*
X521731Y372197D03*
X518352Y370247D03*
X525111Y354647D03*
X531871Y346847D03*
X535251Y356596D03*
X538631Y366347D03*
X528491Y364396D03*
X525111Y342947D03*
X514972Y403396D03*
Y379996D03*
X531871Y374146D03*
X521731Y399496D03*
X518352Y397546D03*
Y389747D03*
X535251Y383896D03*
X525111Y381947D03*
X538631Y393647D03*
Y378047D03*
X528491Y403396D03*
X531871Y401447D03*
Y389747D03*
X525111Y393647D03*
X484552Y405347D03*
X538750Y406200D03*
X511712Y495800D03*
X488384Y495887D03*
X494777D03*
X491380Y493744D03*
X506644Y490867D03*
X501560D03*
X497723Y493494D03*
X506620Y510100D03*
X506644Y518114D03*
X501544Y510098D03*
X485037Y515814D03*
X481691Y510114D03*
X491380Y515714D03*
X511809Y510114D03*
X497723Y515814D03*
X494927Y510114D03*
X488384D03*
X501520Y517900D03*
X506644Y498867D03*
X501560D03*
X514755Y491044D03*
X521048Y491144D03*
X538370Y490609D03*
X528241Y490944D03*
X534534Y490794D03*
X515155Y515814D03*
X530792Y495787D03*
X524595D03*
X517892Y495800D03*
X534534Y515814D03*
X528191Y515714D03*
X531738Y510114D03*
X525195D03*
X538355Y510098D03*
X538331Y517900D03*
X521848Y515814D03*
X518502Y510114D03*
X538370Y498609D03*
X506670Y536750D03*
X501570Y529150D03*
X506657Y528936D03*
X501544Y536999D03*
X511809Y547914D03*
Y537049D03*
X491380Y553514D03*
X497723Y553614D03*
X485037D03*
X506620Y547900D03*
X501544Y547898D03*
X481691Y547914D03*
X494927D03*
X488384D03*
X481691Y537049D03*
X491344Y530949D03*
X488384Y536999D03*
X495077Y537049D03*
X497723Y531100D03*
X485037Y530949D03*
Y568749D03*
X481691Y574849D03*
Y585714D03*
X501544Y585698D03*
Y574799D03*
X506657Y566736D03*
X501570Y566950D03*
X506670Y574550D03*
X506620Y585700D03*
X488384Y585714D03*
X511809D03*
Y574849D03*
X494927Y585714D03*
X491344Y568749D03*
X501520Y555700D03*
X506644Y555914D03*
X497723Y568900D03*
X488384Y574799D03*
X495077Y574849D03*
X515155Y553614D03*
Y530949D03*
X534534Y531100D03*
X531888Y537049D03*
X528155Y530949D03*
X525195Y536999D03*
X538355D03*
X538381Y529150D03*
X525195Y547914D03*
X531738D03*
X538355Y547898D03*
X534534Y553614D03*
X528191Y553514D03*
X518502Y547914D03*
X521848Y553614D03*
X518502Y537049D03*
X521848Y530949D03*
X515155Y568749D03*
X538331Y555700D03*
X518502Y585714D03*
Y574849D03*
X521848Y568749D03*
X538355Y585698D03*
Y574799D03*
X538381Y566950D03*
X531738Y585714D03*
X525195D03*
X534534Y568900D03*
X525195Y574799D03*
X528155Y568749D03*
X531888Y574849D03*
X525195Y612599D03*
X518502Y612649D03*
X538355Y612599D03*
X531888Y612649D03*
X501544Y612599D03*
X495077Y612649D03*
X488384Y612599D03*
X511809Y612649D03*
X497723Y591414D03*
X486250Y591020D03*
X491380Y591314D03*
X501520Y593500D03*
X506644Y593714D03*
X501570Y604750D03*
X506657Y604536D03*
X491344Y606549D03*
X497723Y606700D03*
X485037Y607230D03*
X506670Y612350D03*
X480950Y612430D03*
X515155Y606549D03*
Y591414D03*
X521848D03*
Y606549D03*
X534534Y591414D03*
X528191Y591314D03*
X538331Y593500D03*
X538381Y604750D03*
X534534Y606700D03*
X528155Y606549D03*
X562006Y9114D03*
X568549D03*
X555313D03*
X548620D03*
X571345Y-7700D03*
X551966Y-7851D03*
X564966D03*
X558659D03*
X562006Y-1801D03*
X555313Y-1751D03*
X568699D03*
X548620D03*
X543503Y-2000D03*
X543468Y-9864D03*
X543455Y17114D03*
X564992Y14714D03*
X543415Y9300D03*
X558659Y14814D03*
Y29949D03*
X551966Y14814D03*
Y29949D03*
X564966D03*
X571345Y14814D03*
Y30100D03*
X543468Y27936D03*
X575166Y9098D03*
X602163Y16999D03*
X575214Y-9700D03*
X575166Y-1801D03*
X580279Y-9864D03*
X580314Y-2000D03*
X588777Y-7851D03*
X598817Y-9901D03*
X595470Y-7851D03*
X592124Y-1751D03*
X598817D03*
X585431D03*
X602163Y-9901D03*
X598817Y9157D03*
X592124Y9114D03*
X585431D03*
X575182Y16900D03*
X575192Y28100D03*
X580192Y9300D03*
X588777Y29949D03*
X580279Y27936D03*
X595470Y29949D03*
Y14814D03*
X598817Y27899D03*
X588777Y14814D03*
X580266Y17114D03*
X562006Y46914D03*
X551966Y52614D03*
X565352Y52864D03*
X548620Y46914D03*
Y36049D03*
X558659Y52614D03*
X568699Y36049D03*
X555313D03*
X562006Y35999D03*
X551966Y67749D03*
X564966D03*
X571345Y52614D03*
Y67900D03*
X558659Y67749D03*
X568549Y46914D03*
X555313D03*
X543468Y65736D03*
X543404Y47000D03*
X543415Y35800D03*
X543455Y54914D03*
Y92714D03*
X548620Y84714D03*
X568549D03*
X555313D03*
X562006D03*
X543481Y73550D03*
X543431Y84700D03*
X548620Y73849D03*
X568699D03*
X562006Y73799D03*
X555313Y73849D03*
X558659Y90414D03*
X551966D03*
X571345D03*
X575166Y46898D03*
Y35999D03*
X575192Y65950D03*
X585431Y46914D03*
X595470Y52614D03*
X588777D03*
X585431Y36049D03*
X592124D03*
X598817D03*
Y46957D03*
X592124Y46914D03*
X598817Y65699D03*
X595470Y67749D03*
X588777D03*
X580266Y54914D03*
X580192Y35750D03*
X580279Y65736D03*
X602163Y65699D03*
X592124Y84714D03*
X585431D03*
X598817Y84757D03*
X580242Y84700D03*
X580266Y92714D03*
X588777Y90414D03*
X602163Y92599D03*
X575166Y73799D03*
X575142Y92500D03*
X575166Y84698D03*
X595470Y90414D03*
X585431Y73849D03*
X592124D03*
X598817D03*
X580292Y73550D03*
X548620Y104314D03*
X555313D03*
X558659Y110014D03*
X551966D03*
X543481Y112865D03*
X543468Y105051D03*
X602100Y109600D03*
X555531Y216196D03*
X557000Y206800D03*
X548771Y212296D03*
X552151Y214247D03*
X547800Y201400D03*
X545391Y210346D03*
X552151Y218147D03*
Y225947D03*
X558911Y222047D03*
X552151Y233746D03*
X548771Y235696D03*
X558911Y229847D03*
X552151D03*
X562591Y220096D03*
X564084Y235685D03*
X545391Y225947D03*
Y222047D03*
Y233746D03*
X542011Y239596D03*
Y247396D03*
X552151Y241547D03*
X548771Y239596D03*
X552151Y249347D03*
X555531Y247396D03*
X562591Y251296D03*
X548771Y243496D03*
X562591D03*
X572930Y232750D03*
Y228130D03*
X552151Y257147D03*
X562591Y255196D03*
X548771D03*
X573200Y262600D03*
X573100Y258600D03*
X548771Y266896D03*
X558911Y264947D03*
X563800Y275900D03*
X559211Y280547D03*
X548771Y278596D03*
X558911Y272747D03*
X555531Y274696D03*
X564500Y264800D03*
Y268800D03*
X552151Y261047D03*
X545391Y272747D03*
Y280547D03*
Y264947D03*
Y268847D03*
X542011Y274696D03*
X580360Y234590D03*
Y230060D03*
X545391Y307847D03*
X555831Y309797D03*
Y305896D03*
X548771Y309797D03*
X555831Y298096D03*
X552151Y284447D03*
X548771Y286396D03*
X552151Y288347D03*
Y296147D03*
X558145Y286727D03*
X545391Y296147D03*
Y288347D03*
Y292245D03*
Y300047D03*
X542011Y294196D03*
Y298096D03*
X545391Y303947D03*
X548771Y313696D03*
X561971Y317320D03*
X548771Y325396D03*
X558911Y335147D03*
X555531Y333196D03*
X562591D03*
X548771Y340996D03*
X561966Y325502D03*
X559211Y319547D03*
X552151Y323446D03*
X545391Y319547D03*
X542011Y321496D03*
X545391Y335147D03*
Y331247D03*
Y315647D03*
X552151Y350747D03*
X558911Y342947D03*
X559212Y370247D03*
X548771Y368296D03*
X562591Y352696D03*
Y344896D03*
X563200Y356596D03*
X545391Y354647D03*
Y346847D03*
X542011Y368296D03*
X545391Y366347D03*
Y358547D03*
X542011Y360496D03*
Y348796D03*
X559212Y374146D03*
X555531Y387797D03*
X559212Y381947D03*
Y393647D03*
X552151Y378047D03*
X545391Y397546D03*
Y385847D03*
X542011Y376096D03*
X573867Y459903D03*
X575614Y461694D03*
X584076Y443828D03*
X588285Y448306D03*
X586136Y446335D03*
X558659Y493444D03*
X551366Y490744D03*
X543455Y490909D03*
X555313Y510114D03*
X548492Y495800D03*
X554792Y495887D03*
X543431Y510100D03*
X543455Y518114D03*
X551966Y515814D03*
X548620Y510114D03*
X543455Y498909D03*
X568549Y510114D03*
X562006D03*
X571345Y515814D03*
X558659D03*
X582912Y468948D03*
X581032Y467202D03*
X575166Y510098D03*
X575142Y517900D03*
X580266Y518114D03*
X580242Y510100D03*
X598817Y510157D03*
X595470Y515814D03*
X588777D03*
X602163Y517999D03*
X592124Y510114D03*
X585431D03*
X543468Y528936D03*
X543481Y536750D03*
X543431Y547900D03*
X548620Y547914D03*
X551966Y553614D03*
X548620Y537049D03*
X551966Y530949D03*
X558659D03*
X555313Y537049D03*
X562006Y536999D03*
X564966Y530949D03*
X568699Y537049D03*
X571345Y553614D03*
Y531100D03*
X558659Y553614D03*
X555313Y547914D03*
X568549D03*
X562006D03*
X543455Y555914D03*
X571345Y568900D03*
X564966Y568749D03*
X562006Y574799D03*
X555313Y585714D03*
Y574849D03*
X558659Y568749D03*
X568549Y585714D03*
X562006D03*
X568699Y574849D03*
X551966Y568749D03*
X548620Y574849D03*
Y585714D03*
X543481Y574550D03*
X543431Y585700D03*
X543468Y566736D03*
X575166Y547898D03*
X575192Y529150D03*
X575166Y536999D03*
X598817Y547957D03*
X592124Y547914D03*
X595470Y530949D03*
X580242Y547900D03*
X580279Y528936D03*
X580292Y536750D03*
X592124Y537049D03*
X588777Y530949D03*
X598817Y528899D03*
Y537049D03*
X602163Y528899D03*
X585431Y547914D03*
Y537049D03*
X588777Y553614D03*
X595470D03*
X580279Y566736D03*
X585431Y574849D03*
Y585714D03*
X598817Y585757D03*
Y574849D03*
Y566699D03*
X592124Y585714D03*
X595470Y568749D03*
X588777D03*
X592124Y574849D03*
X575142Y555700D03*
X575192Y566950D03*
X575166Y585698D03*
Y574799D03*
X580266Y555914D03*
X580292Y574550D03*
X580242Y585700D03*
X575166Y612599D03*
X585431Y612649D03*
X592124D03*
X598817D03*
X555313D03*
X562006Y612599D03*
X568699Y612649D03*
X548620D03*
X571345Y591414D03*
X558659D03*
X571345Y606700D03*
X558659Y606549D03*
X564966D03*
X551966D03*
Y591414D03*
X543455Y593714D03*
X543468Y604536D03*
X543481Y612350D03*
X580292D03*
X580266Y593714D03*
X595470Y591414D03*
X588777D03*
X598817Y604499D03*
X595470Y606549D03*
X588777D03*
X575192Y604750D03*
X575142Y593500D03*
X602163Y593599D03*
Y604499D03*
X580279Y604536D03*
X620092Y13078D03*
X620192Y31978D03*
Y-5822D03*
X647317Y-1310D03*
X660676Y-2600D03*
X651300Y20000D03*
X659200Y31500D03*
X651300Y17500D03*
X620070Y50878D03*
X620192Y69778D03*
X620092Y88678D03*
X663500Y48000D03*
X663700Y65600D03*
X663476Y45296D03*
X616115Y108339D03*
X622200Y112200D03*
X616167Y118627D03*
X605300Y124600D03*
X630000Y126572D03*
X624500Y129400D03*
X626900Y128300D03*
X633580Y125560D03*
X661700Y142300D03*
X636481Y124951D03*
X635951Y127419D03*
X661053Y115971D03*
X658490Y115432D03*
X650307Y115518D03*
X647809Y116121D03*
X645311Y116724D03*
X650120Y122700D03*
X660900Y123650D03*
Y126650D03*
X647120Y122700D03*
X657900Y126650D03*
Y123650D03*
X651920Y125750D03*
X656111Y121550D03*
X653111D03*
X654558Y115101D03*
X640043Y117728D03*
X639100Y124200D03*
X638800Y126700D03*
X648690Y125590D03*
X643674Y123573D03*
X644950Y125750D03*
X641950D03*
X642899Y117112D03*
X632500Y238500D03*
Y235000D03*
X632692Y248172D03*
X632532Y241717D03*
X630200Y248100D03*
X633308Y263808D03*
X662800Y248600D03*
X643500Y272262D03*
X659900Y256900D03*
Y269200D03*
X652000Y284500D03*
X663200Y298600D03*
X644800Y292150D03*
X654500Y298600D03*
X652100Y288300D03*
X639045Y299555D03*
X639100Y309500D03*
X649000Y339400D03*
X638790Y329500D03*
X639350Y339980D03*
X639100Y319500D03*
X655900Y307700D03*
X656300Y312300D03*
X660700Y307700D03*
X655900Y316500D03*
X656000Y329800D03*
X655900Y320500D03*
X656000Y325100D03*
X660900Y329800D03*
X664100Y348000D03*
X648800D03*
X658900D03*
X662936Y367171D03*
X659936Y364171D03*
X662936D03*
X654000Y348000D03*
X634200Y436800D03*
X637300Y437200D03*
X625430Y490100D03*
X607012Y465997D03*
X623660Y466746D03*
X632113Y496892D03*
X619392Y514700D03*
X656900Y482290D03*
X649600Y492400D03*
X660500Y492000D03*
X652000Y513900D03*
X655000D03*
X661500D03*
X658500D03*
X620192Y532978D03*
X618892Y555800D03*
X618292Y574300D03*
X651750Y584150D03*
X653100Y587000D03*
X618192Y593600D03*
X620033Y608878D03*
X660230Y598170D03*
X674300Y9847D03*
X671800D03*
X669300D03*
X673900Y23100D03*
X671400D03*
X668900D03*
X690000Y15300D03*
X683800Y24856D03*
X670430Y29253D03*
X684126Y28137D03*
X681426D03*
X716858Y-14448D03*
X717720Y23279D03*
X715114Y26395D03*
X704500Y26300D03*
X700500Y26600D03*
X714337Y7852D03*
Y5352D03*
Y2852D03*
X718555Y-16147D03*
X666500Y48000D03*
X665100Y68600D03*
X668100D03*
X666700Y65600D03*
X684904Y39943D03*
X678020Y69870D03*
X678300Y92630D03*
Y95130D03*
X675630Y94988D03*
X681300Y95130D03*
Y92630D03*
X684300D03*
X687400Y93900D03*
X673830Y83050D03*
X676430D03*
X676500Y80500D03*
X673900D03*
X674010Y77970D03*
X676610D03*
X692200Y83800D03*
X695000Y67000D03*
X699880Y66840D03*
X724200Y64730D03*
X722460Y69550D03*
X713680Y60910D03*
X700360Y72160D03*
X694910Y72220D03*
X713050Y63650D03*
X710440Y63710D03*
X704880Y66750D03*
X697747Y72184D03*
X723700Y67400D03*
X713620Y58270D03*
X715800Y59490D03*
Y57000D03*
X713590Y53260D03*
X713610Y55730D03*
X700640Y69500D03*
X703120Y69380D03*
X702380Y66840D03*
X697440Y66900D03*
X700904Y38439D03*
X699800Y89100D03*
X713830Y82730D03*
X692000Y45000D03*
Y48500D03*
X697500D03*
Y45000D03*
X701525Y35610D03*
X664700Y142800D03*
X675600Y144900D03*
Y150000D03*
X679900Y128200D03*
X682400Y127085D03*
X684900D03*
X673566Y116724D03*
X676494Y116940D03*
X668665Y118185D03*
X671249Y118744D03*
X677896Y119093D03*
X674896D03*
X715505Y155076D03*
X720700Y154750D03*
X725650Y155000D03*
X691583Y200124D03*
X689033D03*
X686533D03*
Y196624D03*
X689033D03*
X691583D03*
X715550Y158880D03*
X705550D03*
X710550D03*
X709200Y198700D03*
X720369Y205199D03*
X716557Y198557D03*
X692513Y213800D03*
X692673Y206200D03*
X692500Y210100D03*
X690861Y211917D03*
Y215717D03*
X692400Y218100D03*
X690861Y204317D03*
Y208117D03*
X706500Y217400D03*
Y214900D03*
X719315Y239104D03*
X669900Y224000D03*
X672500Y224100D03*
X678454Y278000D03*
X675380Y246340D03*
X678000Y246400D03*
X668100Y232200D03*
X667240Y246600D03*
X672530Y246300D03*
X677400Y232300D03*
X674300Y232200D03*
X675200Y224100D03*
X667600Y250200D03*
X688643Y225980D03*
X688388Y231280D03*
X678400Y224100D03*
X690380Y252240D03*
X690939Y266630D03*
X693530Y261240D03*
X690660Y264000D03*
X690704Y271324D03*
X671100Y232200D03*
X701800Y246480D03*
X669750Y246350D03*
X710572Y244773D03*
X719360Y241504D03*
X710627Y242061D03*
X702000Y243900D03*
X722050Y221150D03*
X707653Y226347D03*
X718300Y227400D03*
X700900Y264100D03*
X694361Y223317D03*
Y220817D03*
X690861D03*
Y223317D03*
X672300Y269200D03*
X672200Y256800D03*
X706561Y219917D03*
X719900Y269300D03*
X725500Y279300D03*
X725300Y269400D03*
X719600Y279400D03*
X704175Y287275D03*
X704214Y290775D03*
X680000Y281900D03*
X672150Y288350D03*
X695300Y338100D03*
X695400Y328000D03*
X684100Y338200D03*
X695400Y318000D03*
X695800Y308000D03*
X696088Y297069D03*
X704500Y293800D03*
X707130Y310150D03*
X718200Y295000D03*
X706300Y318400D03*
X678200Y307800D03*
X672700Y307700D03*
X667100D03*
X678100Y324800D03*
X672200Y329800D03*
X678100Y329600D03*
X666900Y329700D03*
X678200Y313700D03*
Y319300D03*
X679000Y348000D03*
X688600Y365100D03*
X671936Y367171D03*
X665936Y370171D03*
X684900Y348000D03*
X674600D03*
X671936Y370171D03*
X665936Y367171D03*
X668936Y370171D03*
Y367171D03*
X665936Y364171D03*
X668936D03*
X669093Y348120D03*
X671936Y373171D03*
X668936D03*
X670300Y375600D03*
X713900Y347800D03*
X698560Y374430D03*
X713900Y342800D03*
Y352800D03*
Y350300D03*
Y345300D03*
X690040Y412030D03*
X685600Y432500D03*
X690600D03*
Y437500D03*
X703876Y414949D03*
X705850Y417093D03*
X710600Y420267D03*
X710423Y417423D03*
X708346Y415859D03*
X708011Y419078D03*
X712980Y417900D03*
X713493Y420449D03*
X723748Y499091D03*
X701255Y521538D03*
X676900Y489400D03*
X666500Y487600D03*
Y484600D03*
X669500D03*
Y481600D03*
X664610Y512810D03*
X685050Y503970D03*
X704500Y512850D03*
X716267Y522020D03*
X703028Y495600D03*
X709028D03*
X706028D03*
X703028Y492600D03*
X706028D03*
X700500Y512850D03*
X701200Y524250D03*
X686200Y511700D03*
X680000Y511800D03*
X686375Y527778D03*
X674200Y588900D03*
X690100Y575860D03*
X689193Y573493D03*
X693126Y581380D03*
X671599Y573493D03*
X671791Y588920D03*
X674099Y573493D03*
X669099D03*
X668891Y588900D03*
X713650Y540750D03*
X715650Y542250D03*
Y545250D03*
X713650Y546750D03*
X708000Y553250D03*
X720200Y551750D03*
X715650Y551250D03*
X696000Y553250D03*
X715650Y548250D03*
X713650Y549750D03*
X723200Y551750D03*
X699000Y553250D03*
X702000D03*
X705000D03*
X713650Y543750D03*
X723200Y554750D03*
X706500Y555750D03*
X703500D03*
X700500D03*
X720200Y554750D03*
X709500Y555750D03*
X712600Y571900D03*
X716300Y569400D03*
X707500Y587800D03*
X691900Y531350D03*
Y534850D03*
X697500Y534750D03*
Y531250D03*
X725173Y598171D03*
X724106Y609550D03*
X721106D03*
X708900Y589850D03*
X706100D03*
X732600Y3600D03*
X755500Y8700D03*
X753600Y-4300D03*
X736715Y33487D03*
X734201Y33510D03*
X726250Y23550D03*
X731457Y8471D03*
X732335Y6000D03*
X786414Y-9650D03*
X779771Y9114D03*
X773228D03*
Y-1801D03*
X779921Y-1751D03*
X776188Y-7851D03*
X769881Y-9901D03*
X782567Y-7700D03*
X786388Y9098D03*
Y-1801D03*
X786414Y28150D03*
X769881Y27899D03*
X782567Y14814D03*
Y30100D03*
X769881Y16839D03*
X776224Y14714D03*
X776188Y29949D03*
X786364Y16900D03*
X736631Y36122D03*
X736655Y38531D03*
X731887Y40916D03*
X734155Y38531D03*
X734131Y36122D03*
X731843Y43571D03*
X756100Y36200D03*
X755500Y46700D03*
X737800Y55800D03*
X751708Y73800D03*
X755500Y84361D03*
X786388Y35999D03*
X786364Y54700D03*
X786388Y46898D03*
X773228Y46914D03*
X779771D03*
X776188Y67749D03*
X769881Y66000D03*
X782567Y67900D03*
Y52614D03*
X769881Y54839D03*
X779921Y35983D03*
X773228D03*
X776224Y52514D03*
X769881Y92500D03*
X773228Y84714D03*
X779771D03*
X776224Y90314D03*
X782567Y90414D03*
X779921Y73849D03*
X773228Y73799D03*
X786414Y65950D03*
X786388Y73799D03*
X786364Y92500D03*
X786388Y84698D03*
X730600Y154984D03*
X746000Y150500D03*
X740718Y150957D03*
X769100Y102900D03*
X758400Y156200D03*
X747600Y161450D03*
X740650Y164800D03*
X735600Y164900D03*
X740650Y158800D03*
X754726Y205037D03*
X752226D03*
X749726D03*
X754726Y207537D03*
X752226D03*
X749726D03*
X742937Y218574D03*
X758400Y159200D03*
X774582Y212033D03*
X770200Y208600D03*
X775171Y218616D03*
X787371Y215216D03*
Y217716D03*
X777700Y218600D03*
X727969Y236770D03*
X736612Y237908D03*
X727997Y239195D03*
X736625Y240308D03*
X742897Y229573D03*
X746303Y243122D03*
X746321Y240569D03*
X760304Y235827D03*
X768560Y244055D03*
X769019Y276400D03*
X762616Y270113D03*
X761480Y242720D03*
X731100Y269300D03*
Y279300D03*
X787371Y247216D03*
Y249716D03*
X775232Y221133D03*
X777700Y250600D03*
X775232Y223633D03*
X775171Y250616D03*
X775232Y253133D03*
Y255633D03*
X787371Y279216D03*
X774347Y339983D03*
X762760Y339500D03*
X727300Y302910D03*
X727474Y338363D03*
Y335363D03*
X732474D03*
Y338363D03*
X756114Y316209D03*
X729974Y338363D03*
Y335363D03*
X771278Y307918D03*
X762842Y302434D03*
X765730Y335064D03*
X777700Y282600D03*
X775232Y287633D03*
Y285133D03*
X775171Y282616D03*
X787371Y281716D03*
Y311216D03*
X777800Y314700D03*
X775171Y314616D03*
X787371Y313716D03*
X775232Y317133D03*
Y319633D03*
X727474Y344663D03*
Y367463D03*
X732474D03*
X729974D03*
X727474Y364863D03*
X732474D03*
X729974D03*
Y347663D03*
X727474D03*
X732474D03*
Y344663D03*
X727574Y373463D03*
X732574D03*
X730074D03*
X732574Y376063D03*
X730074D03*
X729974Y344663D03*
X731100Y362300D03*
X772443Y371976D03*
X760140Y362819D03*
X758952Y384100D03*
X763333Y400212D03*
X772300Y403520D03*
X775171Y346616D03*
X787371Y343216D03*
Y345716D03*
X775232Y349133D03*
X777600Y346600D03*
X775232Y351633D03*
X787321Y374916D03*
Y377316D03*
X775182Y383633D03*
Y381133D03*
X778000Y378700D03*
X775121Y378616D03*
X749640Y431797D03*
X728940Y457806D03*
X775417Y435799D03*
X777979Y436516D03*
X752496Y515974D03*
X732522Y526808D03*
Y524308D03*
X750518Y522108D03*
X734922Y526808D03*
X776224Y515714D03*
X779771Y510114D03*
X773228D03*
X769881Y517900D03*
X782567Y515814D03*
X786388Y510098D03*
X786364Y517900D03*
X732442Y529300D03*
X734842D03*
X736300Y541500D03*
X756000Y537000D03*
X737400Y529400D03*
X734900Y531800D03*
X732400D03*
X726200Y551750D03*
X754910Y556400D03*
X726200Y554750D03*
X727400Y571300D03*
X755000Y574800D03*
X752500Y585150D03*
X727106Y586550D03*
X773228Y536999D03*
X763677Y547783D03*
X776188Y530949D03*
X782567Y531100D03*
X769818Y529200D03*
X779921Y537049D03*
X782567Y553614D03*
X773228Y547914D03*
X779771D03*
X776224Y553514D03*
X786388Y536999D03*
X786414Y529150D03*
X786388Y547898D03*
X786364Y555700D03*
X769881D03*
X773228Y574799D03*
X782567Y568900D03*
X769700Y566900D03*
X776188Y568749D03*
X779921Y574849D03*
X773228Y585714D03*
X779771D03*
X786388Y574799D03*
Y585698D03*
X786414Y566950D03*
X779921Y612649D03*
X773228Y612599D03*
X786388D03*
X755000Y614500D03*
X727000Y606600D03*
X766600Y590700D03*
X769700Y604900D03*
X776188Y606549D03*
X782567Y606700D03*
Y591414D03*
X776224Y591314D03*
X786414Y604750D03*
X786364Y593500D03*
X803346Y-1751D03*
X810039Y-1801D03*
X791514Y-2050D03*
X791501Y-9864D03*
X812999Y-7851D03*
X806692D03*
X799999D03*
X816582Y9114D03*
X796653D03*
X791464Y9100D03*
X810039Y9114D03*
X803346D03*
X816732Y-1751D03*
X796653D03*
X799999Y29949D03*
X806692D03*
X812999D03*
X791501Y27936D03*
X791488Y17114D03*
X799999Y14814D03*
X813035Y14714D03*
X806692Y14814D03*
X828275Y9100D03*
X833464Y9114D03*
X840157D03*
X819378Y-7700D03*
X823199Y9098D03*
Y-1801D03*
X823225Y-9650D03*
X828312Y-9864D03*
X843503Y-7851D03*
X836810D03*
X846850Y-1801D03*
X828325Y-2050D03*
X833464Y-1751D03*
X840157D03*
X846850Y9114D03*
X819378Y14814D03*
Y30100D03*
X843503Y14814D03*
X823175Y16900D03*
X823225Y28150D03*
X828312Y27936D03*
X836810Y29949D03*
X828299Y17114D03*
X836810Y14814D03*
X843503Y29949D03*
X791488Y54914D03*
X799999Y52614D03*
X796653Y46914D03*
X791464Y46900D03*
X810039Y35999D03*
X803346Y36049D03*
X799999Y90414D03*
X791488Y92714D03*
X806692Y90414D03*
X816582Y46914D03*
X816732Y36049D03*
X799999Y67749D03*
X812999D03*
X806692D03*
X791501Y65736D03*
X803346Y46914D03*
X806692Y52614D03*
X813035Y52514D03*
X810039Y46914D03*
X791514Y35750D03*
X796653Y36049D03*
X816582Y73849D03*
X791514Y73550D03*
X796653Y73849D03*
X810039Y73799D03*
X803346Y73849D03*
X816582Y84714D03*
X813035Y90314D03*
X803346Y84714D03*
X810039D03*
X796653D03*
X791464Y84700D03*
X819378Y67900D03*
Y52614D03*
X846850Y35999D03*
X833464Y36049D03*
X840157D03*
X823225Y65950D03*
X823175Y54700D03*
X823199Y46898D03*
Y35999D03*
X828299Y54914D03*
X828275Y46900D03*
X828325Y35750D03*
X833464Y46914D03*
X836810Y52614D03*
X840157Y46914D03*
X828312Y65736D03*
X836810Y67749D03*
X843503D03*
X846850Y46914D03*
X843503Y52614D03*
X823175Y92500D03*
X823199Y84698D03*
X846850Y73799D03*
X843503Y90414D03*
X846850Y84714D03*
X828325Y73550D03*
X840157Y73849D03*
X833464D03*
X828299Y92714D03*
X836810Y90414D03*
X840157Y84714D03*
X833464D03*
X828275Y84700D03*
X819378Y90364D03*
X823199Y73799D03*
X790871Y215216D03*
Y217716D03*
X845100Y268200D03*
X847600D03*
X842600D03*
X847600Y243400D03*
X841400Y243300D03*
X847600Y238400D03*
X841400Y238300D03*
X847600Y240900D03*
X841400Y240800D03*
X789500Y231800D03*
X790900Y234000D03*
Y229700D03*
X790846Y225774D03*
X790882Y221723D03*
X790871Y247216D03*
Y249716D03*
X789471Y227742D03*
X789576Y223737D03*
X789554Y219723D03*
X790900Y253900D03*
X789432Y252000D03*
X790871Y266216D03*
X789432Y255800D03*
X790867Y257724D03*
X789432Y259800D03*
X789500Y263900D03*
X790885Y261711D03*
X790871Y279216D03*
X842600Y299900D03*
X845100D03*
X847600D03*
X845100Y331500D03*
X842600D03*
X847600D03*
X790871Y311216D03*
X789432Y284200D03*
Y288300D03*
Y292400D03*
X789400Y296200D03*
X790871Y298216D03*
X790937Y294270D03*
X790900Y290300D03*
Y286200D03*
X790871Y281716D03*
Y313716D03*
X789432Y319900D03*
Y323900D03*
X790900Y322000D03*
Y326000D03*
X790871Y330216D03*
X789500Y328000D03*
X789478Y315671D03*
X790800Y317700D03*
X847600Y363000D03*
X845100D03*
X842600D03*
X847577Y381842D03*
X789432Y348100D03*
Y352100D03*
X789597Y356105D03*
X789500Y360200D03*
X790900Y358200D03*
X790835Y354048D03*
X790867Y350024D03*
X790871Y345716D03*
Y343216D03*
Y362216D03*
X790821Y374916D03*
X790900Y389300D03*
X789500Y391300D03*
X790900Y393400D03*
Y381100D03*
X789582Y383200D03*
X790900Y385300D03*
X789500Y387300D03*
X790821Y377316D03*
X789282Y379200D03*
X816582Y510114D03*
X806692Y515814D03*
X813035Y515714D03*
X810039Y510114D03*
X791488Y518114D03*
X791464Y510100D03*
X799999Y515814D03*
X796653Y510114D03*
X803346D03*
X819378Y515764D03*
X843503Y515814D03*
X846850Y510114D03*
X823175Y517900D03*
X823199Y510098D03*
X828299Y518114D03*
X840157Y510114D03*
X833464D03*
X836810Y515814D03*
X816582Y537049D03*
Y547914D03*
X810039Y536999D03*
X806692Y530949D03*
X812999D03*
X803346Y537049D03*
X796653D03*
X799999Y530949D03*
X791501Y528936D03*
X791514Y536750D03*
X799999Y553614D03*
X810039Y547914D03*
X796653D03*
X803346D03*
X791464Y547900D03*
X806692Y553614D03*
X813035Y553514D03*
X791488Y555914D03*
X810039Y585714D03*
X806692Y568749D03*
X810039Y574799D03*
X812999Y568749D03*
X803346Y585714D03*
X796653D03*
X791514Y574550D03*
X791464Y585700D03*
X799999Y568749D03*
X796653Y574849D03*
X803346D03*
X791501Y566736D03*
X816582Y585714D03*
Y574849D03*
X819378Y553564D03*
Y531100D03*
X836810Y530949D03*
X833464Y537049D03*
X846850Y547914D03*
X833464D03*
X840157D03*
X828275Y547900D03*
X843503Y553614D03*
X836810D03*
X846850Y536999D03*
X843503Y530949D03*
X823199Y547898D03*
Y536999D03*
X823225Y529150D03*
X828325Y536750D03*
X840157Y537049D03*
X828312Y528936D03*
X819378Y568900D03*
X823175Y555700D03*
X828299Y555914D03*
X828275Y585700D03*
X823225Y566950D03*
X823199Y585698D03*
Y574799D03*
X828312Y566736D03*
X840157Y585714D03*
X833464D03*
X828325Y574550D03*
X840157Y574849D03*
X833464D03*
X836810Y568749D03*
X846850Y585714D03*
Y574799D03*
X843503Y568749D03*
X846850Y612599D03*
X840157Y612649D03*
X833464D03*
X823199Y612599D03*
X810039D03*
X803346Y612649D03*
X796653D03*
X816582D03*
X791514Y612350D03*
X806692Y606549D03*
X812999D03*
X799999D03*
X791501Y604536D03*
X806692Y591414D03*
X813035Y591314D03*
X799999Y591414D03*
X791488Y593714D03*
X819378Y606700D03*
Y591364D03*
X823225Y604750D03*
X823175Y593500D03*
X843503Y591414D03*
X828312Y604536D03*
X843503Y606549D03*
X836810D03*
X828325Y612350D03*
X836810Y591414D03*
X828299Y593714D03*
X870275Y9114D03*
X865086Y9100D03*
X860010Y9098D03*
X876968Y9114D03*
Y-1751D03*
X873621Y-7851D03*
X865123Y-9864D03*
X860036Y-9650D03*
X849810Y-7851D03*
X856189Y-7700D03*
X860010Y-1801D03*
X865136Y-2050D03*
X853543Y-1751D03*
X870275D03*
X853393Y9114D03*
X860036Y28150D03*
X859986Y16900D03*
X865110Y17114D03*
X856189Y14814D03*
X849846Y14714D03*
X873621Y14814D03*
Y29949D03*
X865123Y27936D03*
X849810Y29949D03*
X856189Y30100D03*
X896847Y-9650D03*
X910432Y-7851D03*
X883661Y-1801D03*
X880314Y-7851D03*
X886621D03*
X907086Y-1751D03*
X890354D03*
X896821Y-1801D03*
X901947Y-2050D03*
X901934Y-9864D03*
X893000Y-7700D03*
X883661Y9114D03*
X907086D03*
X896821Y9098D03*
X901897Y9100D03*
X890204Y9114D03*
X910432Y29949D03*
X896797Y16900D03*
X893000Y14814D03*
X901921Y17114D03*
X901934Y27936D03*
X893000Y30100D03*
X880314Y14814D03*
X886657Y14714D03*
X886621Y29949D03*
X880314D03*
X896847Y28150D03*
X910432Y14814D03*
X859986Y54700D03*
X870275Y36049D03*
X865136Y35750D03*
X865086Y46900D03*
X876968Y46914D03*
Y36049D03*
X873621Y67749D03*
Y52614D03*
X860010Y46898D03*
X860036Y65950D03*
X865123Y65736D03*
X849810Y67749D03*
X856189Y67900D03*
X853393Y46914D03*
X870275D03*
X865110Y54914D03*
X860010Y35999D03*
X856189Y52614D03*
X853543Y36049D03*
X849846Y52514D03*
X876968Y84714D03*
Y73849D03*
X873621Y90414D03*
X870275Y73849D03*
X853543D03*
X860010Y73799D03*
X849846Y90314D03*
X856189Y90414D03*
X865110Y92714D03*
X870275Y84714D03*
X865086Y84700D03*
X853393Y84714D03*
X860010Y84698D03*
X859986Y92500D03*
X865136Y73550D03*
X910432Y67749D03*
X893000Y67900D03*
X901934Y65736D03*
X896847Y65950D03*
X910432Y52614D03*
X890204Y46914D03*
X896821Y35999D03*
X901921Y54914D03*
X896797Y54700D03*
X883661Y35999D03*
X886621Y67749D03*
X880314D03*
X883661Y46914D03*
X880314Y52614D03*
X886657Y52514D03*
X901947Y35750D03*
X901897Y46900D03*
X896821Y46898D03*
X893000Y52614D03*
X890354Y36049D03*
X907086D03*
X883661Y73799D03*
X910432Y90414D03*
X907086Y84714D03*
X901897Y84700D03*
X907086Y46914D03*
X896821Y84698D03*
X893000Y90414D03*
X890204Y84714D03*
X896797Y92500D03*
X901921Y92714D03*
X890354Y73849D03*
X896821Y73799D03*
X901947Y73550D03*
X907086Y73849D03*
X883661Y84714D03*
X886657Y90314D03*
X880314Y90414D03*
X886657Y109884D03*
X907086Y104284D03*
X901934Y105051D03*
X896847Y105265D03*
X890204Y104284D03*
X893000Y109534D03*
X896821Y113114D03*
X901947Y112865D03*
X910432Y109984D03*
X883661Y104284D03*
X873621Y515814D03*
X876968Y510114D03*
X870275D03*
X859986Y517900D03*
X865086Y510100D03*
X860010Y510098D03*
X865110Y518114D03*
X853393Y510114D03*
X856189Y515814D03*
X849846Y515714D03*
X907000Y495800D03*
X882900Y495900D03*
X893000Y493094D03*
X886500Y493400D03*
X910432Y491044D03*
X901921Y490514D03*
X896785D03*
X901921Y498514D03*
X896785D03*
X889100Y498500D03*
X901897Y510100D03*
X893000Y515814D03*
X890204Y510114D03*
X896821Y510098D03*
X901921Y518114D03*
X896797Y517900D03*
X880314Y515814D03*
X886657Y515714D03*
X883661Y510114D03*
X910432Y515814D03*
X907086Y510114D03*
X860010Y536999D03*
X865123Y528936D03*
X873621Y530949D03*
Y553614D03*
X876968Y537049D03*
Y547914D03*
X860010Y547898D03*
X870275Y547914D03*
X853393D03*
X865086Y547900D03*
X856189Y553614D03*
X849846Y553514D03*
X870275Y537049D03*
X853543D03*
X856189Y531100D03*
X849810Y530949D03*
X865136Y536750D03*
X860036Y529150D03*
X849810Y568749D03*
X865086Y585700D03*
X860010Y585698D03*
X865136Y574550D03*
X859986Y555700D03*
X865110Y555914D03*
X860010Y574799D03*
X853393Y585714D03*
X870275D03*
X873621Y568749D03*
X876968Y574849D03*
Y585714D03*
X860036Y566950D03*
X865123Y566736D03*
X870275Y574849D03*
X853543D03*
X856189Y568900D03*
X890354Y537049D03*
X893000Y531100D03*
X896821Y536999D03*
X901934Y528936D03*
X901947Y536750D03*
X910432Y530949D03*
X907086Y537049D03*
X886621Y530949D03*
X883661Y536999D03*
X880314Y530949D03*
Y553614D03*
X886657Y553514D03*
X883661Y547914D03*
X893000Y553614D03*
X910432D03*
X890204Y547914D03*
X896821Y547898D03*
X901897Y547900D03*
X907086Y547914D03*
X880314Y568749D03*
X886621D03*
X883661Y574799D03*
Y585714D03*
X901921Y555914D03*
X896797Y555700D03*
X901934Y566736D03*
X896847Y566950D03*
X901897Y585700D03*
X890354Y574849D03*
X896821Y574799D03*
X893000Y568900D03*
X901947Y574550D03*
X896821Y585698D03*
X890204Y585714D03*
X910432Y568749D03*
X907086Y574849D03*
Y585714D03*
X890354Y612649D03*
X896821Y612599D03*
X883661D03*
X907086Y612649D03*
X870275D03*
X876968D03*
X860010Y612599D03*
X853543Y612649D03*
X859986Y593500D03*
X865110Y593714D03*
X856189Y591414D03*
X849846Y591314D03*
X860036Y604750D03*
X865123Y604536D03*
X856189Y606700D03*
X849810Y606549D03*
X865136Y612350D03*
X873621Y606549D03*
Y591414D03*
X886657Y591314D03*
X896847Y604750D03*
X901934Y604536D03*
X901947Y612350D03*
X896797Y593500D03*
X901921Y593714D03*
X893000Y591414D03*
X910432D03*
Y606549D03*
X893000Y606700D03*
X880314Y606549D03*
X886621D03*
X880314Y591414D03*
X923432Y-7851D03*
X929811Y-7700D03*
X933658Y-9650D03*
X917125Y-7851D03*
X913779Y-1751D03*
X933632Y-1801D03*
X927165Y-1751D03*
X920472Y-1801D03*
X927015Y9114D03*
X933632Y9098D03*
X913779Y9114D03*
X920472D03*
X923432Y29949D03*
X917125D03*
Y14814D03*
X929811D03*
X933608Y16900D03*
X923468Y14714D03*
X933658Y28150D03*
X929811Y30100D03*
X938745Y-9864D03*
X938758Y-2050D03*
X938708Y9100D03*
X947243Y-7851D03*
X950590Y-1751D03*
X953936Y-7851D03*
X943897Y-1751D03*
Y9114D03*
X950590D03*
X960629Y-9786D03*
X963976Y-1843D03*
X970669Y-1743D03*
X967322Y-9786D03*
X963976Y9114D03*
X970669D03*
X967322Y28014D03*
X960629Y17057D03*
Y28014D03*
X967322Y17057D03*
X938745Y27936D03*
X938732Y17114D03*
X953936Y14814D03*
Y29949D03*
X947243D03*
Y14814D03*
X933658Y65950D03*
X923432Y67749D03*
X929811Y67900D03*
X917125Y67749D03*
X920472Y35999D03*
X917125Y52614D03*
X913779Y46914D03*
Y36049D03*
X927015Y73849D03*
X913779D03*
X920472Y73799D03*
X933632D03*
X913779Y84714D03*
X920472D03*
X933608Y92500D03*
X920472Y46914D03*
X933632Y35999D03*
X927165Y36049D03*
X927015Y46914D03*
X933608Y54700D03*
X933632Y46898D03*
X929811Y52614D03*
X933632Y84698D03*
X927015Y84714D03*
X923468Y90314D03*
X929811Y90414D03*
X917125D03*
X953936Y52614D03*
X967322Y65814D03*
X960629D03*
X970669Y35957D03*
Y46914D03*
X967322Y54857D03*
X963976Y35957D03*
Y46914D03*
X960629Y54857D03*
X938758Y35750D03*
X938708Y46900D03*
X938732Y54914D03*
X938745Y65736D03*
X950590Y36049D03*
X953936Y67749D03*
X950590Y46914D03*
X947243Y67749D03*
X943897Y36049D03*
Y46914D03*
X947243Y52614D03*
X963976Y73757D03*
X960629Y89964D03*
X963976Y87392D03*
X967322Y89964D03*
X970669Y87392D03*
Y73757D03*
X938708Y84700D03*
X938732Y92714D03*
X938758Y73550D03*
X943897Y84714D03*
X947243Y90414D03*
X943897Y73849D03*
X950590D03*
X953886Y90414D03*
X950590Y84714D03*
X933658Y105265D03*
X929811Y109534D03*
X933632Y113114D03*
X923468Y109884D03*
X917125Y109984D03*
X920472Y104284D03*
X913779D03*
X927015D03*
X963245Y105725D03*
X938758Y112865D03*
X938745Y105051D03*
X947250Y107700D03*
X950600Y112300D03*
X953800Y105000D03*
X927607Y203260D03*
Y207159D03*
X934367D03*
Y199360D03*
X930987Y201309D03*
X934367Y214960D03*
X930987Y213009D03*
X920847Y211060D03*
X927607Y214960D03*
Y211060D03*
X937747Y216909D03*
X924227D03*
Y213009D03*
X968166Y218860D03*
X951256Y194841D03*
X958026Y201309D03*
X967036Y193507D03*
X947887Y203260D03*
Y207159D03*
X944507Y213009D03*
Y201309D03*
X947887Y199360D03*
X941127D03*
Y207159D03*
X947887Y211060D03*
Y218860D03*
X941127D03*
Y214960D03*
X962526Y205210D03*
X961406Y214960D03*
Y211060D03*
Y218860D03*
X951267Y209109D03*
X958026Y213009D03*
X954647Y211060D03*
Y218860D03*
X964786Y213009D03*
Y216909D03*
Y209109D03*
X934367Y226660D03*
X924227Y236409D03*
X920847Y238360D03*
X913787Y226660D03*
X913700Y222710D03*
X913787Y238360D03*
X924227Y232509D03*
X927607Y230559D03*
Y234460D03*
X930987Y232509D03*
X934367Y234460D03*
X924227Y228610D03*
X930987Y220809D03*
X924227Y224709D03*
X937747Y232509D03*
Y236409D03*
X924227Y240309D03*
X917467D03*
X930987D03*
X924227Y248109D03*
Y244209D03*
X917467D03*
X913787Y250060D03*
X934367Y246160D03*
X927607Y250060D03*
X924227Y220809D03*
X913787Y253960D03*
X927607D03*
X934367D03*
X937747Y252009D03*
X930987D03*
X924227D03*
X917467D03*
Y259809D03*
X924227D03*
X930987D03*
X920847Y265660D03*
X930987Y275409D03*
X937747D03*
Y271509D03*
Y255909D03*
X934367Y277360D03*
X930987Y271509D03*
X934367Y273460D03*
X927607Y269560D03*
X917467Y263709D03*
X913787Y265660D03*
X924227Y267609D03*
X934367Y265660D03*
X924227Y263709D03*
Y275409D03*
X927607Y277360D03*
X920847Y273460D03*
Y269560D03*
X924227Y255909D03*
X951267Y248109D03*
X958026Y244209D03*
X968166Y242260D03*
X944507Y228610D03*
Y224709D03*
Y244209D03*
Y248109D03*
X941127Y242260D03*
Y250060D03*
Y246160D03*
X947887D03*
X941127Y222760D03*
X947887Y226660D03*
Y234460D03*
X941127Y238360D03*
Y234460D03*
Y230559D03*
Y226660D03*
X971546Y248109D03*
X968166Y246160D03*
X951267Y240309D03*
X958026D03*
X964786D03*
X954647Y246160D03*
Y250060D03*
X958026Y228610D03*
Y236409D03*
X961406Y238360D03*
X951267Y228610D03*
X954647Y226660D03*
X958026Y224709D03*
Y232509D03*
X954647Y230559D03*
X961406Y222760D03*
X968166Y226660D03*
X971546Y236409D03*
X968166Y238360D03*
X971546Y220809D03*
X964786Y232509D03*
Y220809D03*
X947887Y253960D03*
X941127D03*
X958026Y252009D03*
X968166Y277360D03*
X951267Y275409D03*
X961406Y277360D03*
X958026Y263709D03*
X968166Y269560D03*
X961406Y261760D03*
X958026Y255909D03*
X951267Y259809D03*
X958026D03*
X954647Y277360D03*
Y265660D03*
X951267Y267609D03*
X954647Y273460D03*
X958026Y275409D03*
X954647Y269560D03*
X961406D03*
X971546Y275409D03*
Y263709D03*
X941127Y277360D03*
Y265660D03*
X944507Y275409D03*
Y263709D03*
X941127Y269560D03*
Y257860D03*
Y261760D03*
X947887Y277360D03*
Y265660D03*
X971546Y259809D03*
Y255909D03*
X964786Y279310D03*
X934367Y285160D03*
Y300760D03*
X927607D03*
Y308560D03*
X934367D03*
X927607Y285160D03*
Y292959D03*
X934367D03*
X937747Y318309D03*
Y341709D03*
Y326110D03*
X917467Y333909D03*
Y341709D03*
X913787Y339760D03*
X924227Y333909D03*
Y337809D03*
Y341709D03*
X913787Y328060D03*
X924227Y330009D03*
X920847Y328060D03*
X917467Y330009D03*
X930987Y326110D03*
X934367Y331960D03*
X927607Y328060D03*
X934367Y324160D03*
X924227Y322209D03*
X927607Y320260D03*
X930987Y318309D03*
X934367Y316360D03*
X927607D03*
X930987Y337809D03*
X924227Y326110D03*
X961406Y292959D03*
Y285160D03*
X954647Y292959D03*
Y285160D03*
X968166Y292959D03*
Y300760D03*
X971546Y310509D03*
X964786D03*
X954647Y308560D03*
X961406D03*
X954647Y300760D03*
X961406D03*
X964786Y283209D03*
X971546D03*
X947887Y308560D03*
X941127D03*
Y300760D03*
X947887D03*
X941127Y285160D03*
Y292959D03*
X947887D03*
Y285160D03*
X968166Y281260D03*
X958026Y333909D03*
Y337809D03*
Y341709D03*
Y318309D03*
X951267D03*
X954647Y316360D03*
X961406D03*
Y324160D03*
X971546Y337809D03*
X964786Y330009D03*
X971546D03*
X951267D03*
X958026D03*
X968166Y312460D03*
X964786Y314409D03*
X951267Y337809D03*
X954647Y331960D03*
Y328060D03*
X971546Y322209D03*
X968166Y320260D03*
X964786Y322209D03*
X958026Y326110D03*
X947887Y316360D03*
X941127D03*
X944507Y322209D03*
Y318309D03*
X947887Y331960D03*
Y328060D03*
X941127Y331960D03*
Y328060D03*
Y339760D03*
Y335860D03*
X944507Y333909D03*
X937747Y365109D03*
Y345609D03*
Y361209D03*
X924227Y365109D03*
X930987D03*
X927607Y367060D03*
X934367Y370959D03*
Y363160D03*
X927607D03*
X924227Y369010D03*
X913787Y343660D03*
X934367D03*
X927607D03*
Y347560D03*
X934367Y351460D03*
X930987Y357309D03*
Y345609D03*
X917467Y353409D03*
Y349509D03*
X913787Y355360D03*
X924227Y349509D03*
Y345609D03*
Y353409D03*
Y361209D03*
Y357309D03*
X920847Y355360D03*
X917167Y361209D03*
Y369010D03*
X934367Y382660D03*
X930987Y384609D03*
Y376809D03*
X934367Y390460D03*
X927607Y386560D03*
Y390460D03*
X930987Y396309D03*
X934367Y398260D03*
X927607Y394359D03*
X917467Y388509D03*
X924227Y392410D03*
X920847Y390460D03*
X924227Y372909D03*
X937747Y400209D03*
X917100Y380709D03*
X937747D03*
X924227D03*
X920847Y382660D03*
X924227Y376809D03*
X927607Y382660D03*
X968166Y370959D03*
X958026Y361209D03*
X954647Y347560D03*
X961406Y359260D03*
X958026Y357309D03*
X951267D03*
X941127Y355360D03*
Y347560D03*
Y351460D03*
X958026Y345609D03*
X951267Y349509D03*
X954647Y351460D03*
X958026Y353409D03*
X968166Y355360D03*
Y351460D03*
X964786Y357309D03*
X971546Y361209D03*
X968166Y359260D03*
X958026Y365109D03*
X964786D03*
X954647Y370959D03*
Y367060D03*
X958026Y369010D03*
X951267D03*
X971546Y349509D03*
X947887Y363160D03*
X941127D03*
X947887Y370959D03*
X941127D03*
Y367060D03*
X944507Y369010D03*
X947887Y343660D03*
X941127Y359260D03*
X944507Y349509D03*
Y353409D03*
X941127Y343660D03*
X947887Y351460D03*
X958026Y372909D03*
X941127Y374860D03*
X961406D03*
X944507Y372909D03*
X941127Y382660D03*
Y378760D03*
X947887D03*
X944507Y384609D03*
X947887Y390460D03*
Y386560D03*
X941127Y390460D03*
X947887Y398260D03*
X941127D03*
X944507Y396309D03*
X947887Y394359D03*
X964786Y376809D03*
X971546D03*
X968166Y378760D03*
Y386560D03*
X964786Y392410D03*
X968166Y390460D03*
Y394359D03*
X964786Y388509D03*
X961406Y378760D03*
X954647D03*
X958026Y384609D03*
X961406Y382660D03*
X951267Y388509D03*
X958026D03*
X954647Y394359D03*
X961406Y386560D03*
X952216Y402421D03*
X970416Y401941D03*
X971546Y380709D03*
X968166Y382660D03*
X920700Y495944D03*
X913800Y495800D03*
X927165Y495944D03*
X929811Y515814D03*
X933632Y510098D03*
X923600Y491144D03*
X917192Y491219D03*
X933632Y490644D03*
X929811D03*
X933632Y498644D03*
X933608Y517900D03*
X913779Y510114D03*
X917125Y515814D03*
X923468Y515714D03*
X920472Y510114D03*
X927015D03*
X938732Y490644D03*
X950700Y490700D03*
X943897Y490444D03*
X970669Y512792D03*
X967322Y515364D03*
X963976Y512792D03*
X960629Y515364D03*
X938708Y510100D03*
X938732Y518114D03*
Y498644D03*
X954000Y497300D03*
X953886Y515814D03*
X950590Y510114D03*
X943897D03*
X947243Y515814D03*
X947443Y497644D03*
X961309Y499136D03*
X933632Y536999D03*
X929811Y531100D03*
X933658Y529150D03*
X913779Y537049D03*
X917125Y530949D03*
X927015Y537049D03*
X923432Y530949D03*
X920472Y536999D03*
X923468Y553514D03*
X917125Y553614D03*
X913779Y547914D03*
X927015D03*
X920472D03*
X933632Y547898D03*
X929811Y553614D03*
X933608Y555700D03*
X933632Y585698D03*
X933658Y566950D03*
X929811Y568900D03*
X933632Y574799D03*
X920472D03*
X927015Y585714D03*
X920472D03*
X913779Y574849D03*
X917125Y568749D03*
X913779Y585714D03*
X923432Y568749D03*
X927015Y574849D03*
X960629Y529014D03*
X963976Y536957D03*
X970669D03*
X967322Y529014D03*
X963976Y547914D03*
X970669D03*
X938745Y528936D03*
X938758Y536750D03*
X938708Y547900D03*
X950590Y537049D03*
X953936Y530949D03*
X953886Y553614D03*
X950590Y547914D03*
X947243Y530949D03*
X943897Y537049D03*
Y547914D03*
X947243Y553614D03*
X967322Y555857D03*
X960629D03*
X970669Y585714D03*
Y574757D03*
X960629Y566814D03*
X963976Y585714D03*
Y574757D03*
X967322Y566814D03*
X938732Y555914D03*
X938745Y566736D03*
X938758Y574550D03*
X938708Y585700D03*
X950590Y574849D03*
Y585714D03*
X957456Y588334D03*
X953936Y568749D03*
X943897Y574849D03*
X947243Y568749D03*
X943897Y585714D03*
X933632Y612599D03*
X923432Y606549D03*
X917125D03*
X933658Y604750D03*
X923468Y591314D03*
X917125Y591414D03*
X933608Y593500D03*
X929811Y591414D03*
X927015Y612449D03*
X920472Y612399D03*
X913779Y612449D03*
X929811Y606700D03*
X967322Y593657D03*
X963976Y612457D03*
X970669D03*
X960629Y604614D03*
X967322D03*
X960629Y593657D03*
X938758Y612350D03*
X938745Y604536D03*
X938732Y593714D03*
X957500Y591000D03*
X953936Y606549D03*
X950590Y612249D03*
X953886Y591414D03*
X947243Y606549D03*
X943897Y612249D03*
X947243Y591414D03*
X980708Y-4536D03*
X987401Y-9901D03*
X997441Y-7108D03*
X990748Y-1743D03*
X977362Y-7108D03*
X980708Y9114D03*
X990748Y9122D03*
X977362Y28014D03*
X987401D03*
Y17057D03*
X977362D03*
X997441Y28022D03*
Y17057D03*
X1000787Y-4536D03*
Y9122D03*
X1017519Y-1858D03*
Y-9786D03*
X1007480Y-1858D03*
X1007280Y9114D03*
X1017519D03*
X1007480Y-9786D03*
Y17014D03*
Y28014D03*
X1017519D03*
Y17042D03*
X987401Y65814D03*
X977362D03*
X987401Y54857D03*
X977362D03*
X990748Y46922D03*
Y35957D03*
X980708D03*
Y46914D03*
X997441Y65822D03*
Y54857D03*
Y92757D03*
X990748Y73757D03*
Y87392D03*
X977362Y92757D03*
X987401Y89964D03*
X980708Y84714D03*
Y73757D03*
X1000787Y35957D03*
Y46922D03*
X1017519Y54842D03*
X1007480Y46914D03*
X1008226Y54842D03*
X1008217Y35942D03*
X1007480Y65736D03*
X1016600Y65950D03*
X1017519Y35942D03*
Y46914D03*
X1017919Y92500D03*
X1017519Y87500D03*
X1000787Y84599D03*
Y73757D03*
X1007480Y87500D03*
X1007573Y92500D03*
X1008099Y73479D03*
X1017350Y73450D03*
X976200Y105600D03*
X983936Y199108D03*
X973808Y201308D03*
X995206Y203260D03*
X988446Y218860D03*
X995206Y214960D03*
X981686Y218860D03*
X974926Y211060D03*
X979426Y214958D03*
X1001965Y214960D03*
X1027875Y193507D03*
X1032385Y201309D03*
X1015485Y203260D03*
Y214960D03*
X1022245D03*
X1012105Y205210D03*
X1025625Y205211D03*
X1029005Y214960D03*
X1007595Y193507D03*
X1005345Y205210D03*
X1008725Y214960D03*
X988446Y234460D03*
X985066Y248109D03*
X981686Y250060D03*
X974926D03*
X988446Y246160D03*
X981686Y242260D03*
X974926D03*
X988446D03*
X998586Y244209D03*
Y232509D03*
X991826Y244209D03*
Y232509D03*
X995206Y226660D03*
X988446Y238360D03*
X985066Y236409D03*
X981686Y234460D03*
X974926Y226660D03*
Y230559D03*
Y234460D03*
Y222760D03*
X978306Y232509D03*
Y220809D03*
X974926Y253960D03*
X988446D03*
X978306Y252009D03*
X985066D03*
X974926Y265660D03*
X991826Y259809D03*
X985066D03*
X981686Y269560D03*
X995206D03*
X985066Y267609D03*
X991826Y263709D03*
X988446Y265660D03*
X998586Y263709D03*
X991826Y271509D03*
X995206Y273460D03*
X991826Y279310D03*
Y275409D03*
X974926Y269560D03*
X978306Y267609D03*
Y259809D03*
X991826Y255909D03*
X995206Y265660D03*
X991826Y267609D03*
X974926Y273460D03*
X1032385Y232509D03*
X1018865Y244209D03*
X1012105D03*
X1018865Y232509D03*
X1015485Y226660D03*
X1022245D03*
X1012105Y232509D03*
X1025625D03*
X1029005Y226660D03*
X1005345Y244209D03*
X1008725Y226660D03*
X1005345Y232509D03*
X1001965Y226660D03*
X1029005Y250060D03*
X1032385Y248109D03*
X1025625D03*
X1022245Y250060D03*
X1001965Y261760D03*
X1012105Y255909D03*
X1015485Y253960D03*
X1018865Y252009D03*
X1005345Y259809D03*
X1008725Y257860D03*
X981686Y281260D03*
Y292959D03*
Y300760D03*
X988446D03*
X978306Y310509D03*
X991826D03*
X985066D03*
X974926Y300760D03*
X988446Y292959D03*
X991826Y283209D03*
X988446Y281260D03*
X985066Y283209D03*
X978306D03*
X974926Y292959D03*
Y281260D03*
X991826Y333909D03*
X995206Y335860D03*
Y339760D03*
Y328060D03*
X991826Y326110D03*
X981686Y339760D03*
X978306Y333909D03*
Y330009D03*
Y326110D03*
X981686Y331960D03*
X985066Y330009D03*
X974926Y324160D03*
X988446Y339760D03*
X974926Y312460D03*
X981686D03*
X988446D03*
X991826Y314409D03*
Y330009D03*
X995206Y331960D03*
X988446D03*
X995206Y324160D03*
X988446Y316360D03*
X991826Y318309D03*
X995206Y320260D03*
X991826Y322209D03*
X998586Y333909D03*
X974926Y339760D03*
Y335860D03*
X1017957Y312421D03*
X1025438Y312381D03*
X1022915Y312372D03*
X1020404Y312408D03*
X1028039Y312414D03*
X1008725Y339760D03*
X1005345Y337809D03*
X1001965Y335860D03*
X1012105Y341709D03*
X995206Y343660D03*
X985066Y361209D03*
X974926Y355360D03*
Y347560D03*
X981686D03*
X978306Y345609D03*
X981686Y355360D03*
X985066Y349509D03*
X998586D03*
X978306Y365109D03*
X981686Y363160D03*
X974926D03*
Y367060D03*
Y370959D03*
X998586Y365109D03*
Y353409D03*
X991826Y365109D03*
X995206Y370959D03*
X991826Y353409D03*
X974926Y343660D03*
X988446Y359260D03*
Y347560D03*
X991826Y345609D03*
X988446Y351460D03*
Y355360D03*
X998586Y392410D03*
X995206Y382660D03*
X985066Y372909D03*
X974926Y374860D03*
X985066Y384609D03*
X974926Y386560D03*
X974066Y399911D03*
X978306Y376809D03*
X974926Y378760D03*
X981686D03*
X985066Y380709D03*
X1005345Y365109D03*
X1008725Y370959D03*
X1001965D03*
X1005345Y353409D03*
X1018865Y365109D03*
X1012105D03*
X1025625D03*
X1022245Y370959D03*
X1015485D03*
X1018865Y353409D03*
X1012105D03*
X1025625D03*
X1029005Y370959D03*
X1032385Y365109D03*
X1005345Y349509D03*
X1018865Y345609D03*
X1022245Y347560D03*
X1015485Y343660D03*
X1025625Y345609D03*
X1029005Y347560D03*
X1032385Y349509D03*
X1007595Y402800D03*
X1008725Y382660D03*
X1001965D03*
X1005345Y392410D03*
X1029005Y390460D03*
X1025625Y392410D03*
X1022245Y382660D03*
X1015485D03*
X1012105Y392410D03*
X1018865D03*
X1029005Y382660D03*
X1027875Y402800D03*
X987401Y515364D03*
X990748Y512792D03*
X997441Y518157D03*
X976421Y499768D03*
X980708Y510114D03*
X977362Y518157D03*
X1000490Y509999D03*
X1016473Y515152D03*
Y510114D03*
X1008650Y515200D03*
X1008526Y510114D03*
X990748Y536957D03*
X977362Y529014D03*
X980708Y536957D03*
X987401Y529014D03*
X990748Y547922D03*
X980708Y547914D03*
X997441Y529022D03*
X977362Y555857D03*
X987401D03*
X997441D03*
X977362Y566814D03*
X990748Y574757D03*
Y585722D03*
X980708Y585714D03*
Y574757D03*
X997441Y566822D03*
X987401Y566814D03*
X1000787Y536957D03*
Y547922D03*
X1017300Y536200D03*
X1017519Y529057D03*
X1017300Y547914D03*
X1007518Y536727D03*
X1007480Y528942D03*
X1007280Y547914D03*
X1016800Y566814D03*
X1019277Y585714D03*
X1016800Y574742D03*
X1000787Y585722D03*
Y574757D03*
X1016819Y555842D03*
X1007518D03*
Y566814D03*
X1007480Y574742D03*
X1006633Y585714D03*
X977362Y593657D03*
X987401D03*
X997441D03*
Y607292D03*
X977362D03*
X990748Y612457D03*
X980708Y609864D03*
X987401Y604499D03*
X1016778Y611759D03*
X1017519Y604614D03*
Y593642D03*
X1007480Y612242D03*
X1000787Y609864D03*
X1007480Y604614D03*
X1006634Y593642D03*
X1047637Y-4536D03*
X1057676Y-1743D03*
X1047637Y9107D03*
X1057677D03*
X1050983Y-7108D03*
X1050984Y17042D03*
X1061023Y-9786D03*
X1067716Y-4536D03*
Y-9901D03*
X1081102Y-4536D03*
X1074409D03*
X1084448Y-7108D03*
X1077755D03*
X1091141Y-1843D03*
X1067716Y9107D03*
X1091141D03*
X1074409D03*
X1081102D03*
X1061024Y17057D03*
X1067716Y28007D03*
Y17042D03*
X1091141D03*
X1084450Y17057D03*
X1077757D03*
X1091141Y28007D03*
X1050984Y54842D03*
X1047637Y35942D03*
Y46907D03*
X1057677Y35942D03*
Y46907D03*
X1057676Y87392D03*
X1050983Y92757D03*
X1047637Y84599D03*
X1035000Y81200D03*
X1057677Y73742D03*
X1047637D03*
X1061024Y54857D03*
X1067716Y54842D03*
Y35942D03*
Y46907D03*
Y65807D03*
X1091141Y54842D03*
Y35942D03*
X1084450Y54857D03*
X1081102Y35942D03*
X1074409D03*
X1077757Y54857D03*
X1081102Y46907D03*
X1074409D03*
X1091141D03*
Y65807D03*
X1067716Y89964D03*
Y84599D03*
X1081102D03*
X1091141Y87392D03*
Y92657D03*
X1077755Y92757D03*
X1074409Y84714D03*
X1084448Y92757D03*
X1061023Y89964D03*
X1067716Y73742D03*
X1074409D03*
X1081102D03*
X1091141D03*
X1050983Y105800D03*
X1057734Y105750D03*
X1077304Y105800D03*
X1071111D03*
X1064428D03*
X1035765Y214960D03*
X1042524D03*
X1042506Y195041D03*
X1045904Y197359D03*
X1054000Y199100D03*
X1035765Y207159D03*
X1042524Y203260D03*
X1049284Y214960D03*
Y203260D03*
X1072202Y216196D03*
X1065242Y208397D03*
X1068822Y214247D03*
X1065242Y212296D03*
Y204496D03*
X1071072Y199583D03*
X1095861Y218147D03*
X1089101Y214247D03*
Y210346D03*
X1092481Y216196D03*
X1095861Y206446D03*
X1091351Y199841D03*
X1075582Y206446D03*
Y218147D03*
X1082341D03*
X1078962Y216196D03*
X1078961Y212296D03*
X1082341Y214247D03*
X1085721Y212296D03*
Y216196D03*
X1084591Y198931D03*
X1042524Y226660D03*
X1039145Y232509D03*
X1035765Y226660D03*
X1057314Y240309D03*
X1049284Y226660D03*
X1045904Y232509D03*
X1057314D03*
X1035765Y250060D03*
X1057314Y248109D03*
X1039145D03*
X1042524Y250060D03*
X1049284D03*
X1045904Y248109D03*
X1095861Y229847D03*
X1068822Y233746D03*
X1065242Y235696D03*
Y223996D03*
X1068822Y237647D03*
Y249347D03*
X1065242Y247396D03*
X1068822Y241547D03*
X1072202Y243496D03*
Y251296D03*
X1092481Y223996D03*
Y231797D03*
X1089101Y233746D03*
Y237647D03*
X1095861D03*
Y245447D03*
X1078962Y251296D03*
X1082341Y245447D03*
Y249347D03*
X1078962Y247396D03*
X1092481Y243496D03*
X1075582Y245447D03*
X1085721Y251296D03*
X1075582Y249347D03*
X1085721Y243496D03*
X1089101Y241547D03*
X1085721Y223996D03*
X1075582Y229847D03*
X1082341D03*
X1078962Y227896D03*
Y220096D03*
Y223996D03*
X1085721Y231797D03*
X1082341Y237647D03*
X1075582D03*
X1072202Y231797D03*
Y223996D03*
X1089101Y253247D03*
X1092481Y255196D03*
X1095861Y257147D03*
X1052664Y357309D03*
X1049284Y370959D03*
X1035765D03*
X1042524D03*
X1045904Y365109D03*
X1039145D03*
X1052664D03*
X1042524Y359260D03*
X1049284Y351460D03*
X1045904Y353409D03*
X1035765Y351460D03*
Y359260D03*
X1039145Y353409D03*
X1042524Y351460D03*
X1054914Y347000D03*
X1052664Y392410D03*
X1040265Y394359D03*
X1049284Y382660D03*
X1035765D03*
X1042524D03*
Y390460D03*
X1056176Y402471D03*
X1041395Y402800D03*
X1060694Y351460D03*
X1086841Y358547D03*
X1094731Y346546D03*
X1086841Y354647D03*
X1090221Y352696D03*
X1091351Y348497D03*
X1073322Y354647D03*
X1076702Y356596D03*
X1080082Y354647D03*
X1083462Y368296D03*
X1076702Y372197D03*
Y368296D03*
X1073322Y362447D03*
X1086841D03*
X1090221Y372197D03*
Y364396D03*
X1093601Y366347D03*
X1090221Y368296D03*
X1076702Y360496D03*
X1083462D03*
Y352696D03*
X1076702D03*
X1093601Y358547D03*
X1090221Y379996D03*
X1073323Y401449D03*
X1078962Y399496D03*
X1093601Y401447D03*
X1060694Y374860D03*
X1073322Y374146D03*
X1086841D03*
X1073323Y397548D03*
X1073322Y385847D03*
X1080082Y393647D03*
X1083462Y391696D03*
X1080082Y385847D03*
X1083462Y376096D03*
X1080082Y378047D03*
X1083462Y379996D03*
X1076702Y376096D03*
X1090221Y395595D03*
X1086841Y389747D03*
X1093601Y393647D03*
X1090221Y391696D03*
X1093601Y385847D03*
X1086841D03*
X1093601Y397546D03*
Y378047D03*
X1086841Y381947D03*
X1093601Y405347D03*
X1077832Y407800D03*
X1047637Y509999D03*
X1057676Y512792D03*
X1035000Y521556D03*
X1050983Y518157D03*
X1067716Y509999D03*
X1074409Y510114D03*
X1061023Y515364D03*
X1091141Y518057D03*
X1077755Y518157D03*
X1081102Y509999D03*
X1084448Y518157D03*
X1082800Y497650D03*
X1091141Y512792D03*
X1067716Y515364D03*
X1057677Y547907D03*
Y536942D03*
X1047637Y547907D03*
Y536942D03*
X1057677Y574742D03*
Y585707D03*
X1047637Y574742D03*
Y585707D03*
X1050984Y555842D03*
X1074409Y547907D03*
X1081102D03*
X1091141D03*
Y529007D03*
Y536942D03*
X1074409D03*
X1081102D03*
X1067716D03*
Y529007D03*
X1061024Y555857D03*
X1077757D03*
X1084450D03*
X1091141Y555842D03*
X1067716D03*
X1081102Y574742D03*
Y585707D03*
X1074409D03*
X1091141Y574742D03*
Y585707D03*
X1067716Y574742D03*
Y585599D03*
Y566807D03*
X1091141D03*
X1074409Y574742D03*
X1091141Y612557D03*
X1057676Y612657D03*
X1050984Y593642D03*
X1047637Y609864D03*
X1061024Y593657D03*
X1061023Y604614D03*
X1077757Y593657D03*
X1084450D03*
X1067716Y593642D03*
Y609864D03*
Y604499D03*
X1081102Y609864D03*
X1091141Y593642D03*
Y607292D03*
X1084448D03*
X1077755D03*
X1050983D03*
X1074409Y609864D03*
X1119453Y-9864D03*
X1097352Y-7180D03*
X1104141Y-7851D03*
X1110520Y-7700D03*
X1114340Y-1801D03*
X1107874Y-1751D03*
X1101181Y-1801D03*
X1107724Y9114D03*
X1101181D03*
X1114340Y9098D03*
X1114400Y28100D03*
X1110520Y14814D03*
X1104177Y14714D03*
X1098500Y17000D03*
X1114300Y16900D03*
X1119400Y9300D03*
X1119453Y27936D03*
X1119440Y17114D03*
X1110520Y30100D03*
X1104141Y29949D03*
X1156300Y-2000D03*
X1151152Y-1801D03*
X1131299Y9114D03*
X1124606D03*
X1151152Y9098D03*
X1137992Y9114D03*
X1144535D03*
X1127952Y-7851D03*
X1124606Y-1751D03*
X1131299D03*
X1134645Y-7851D03*
X1156265Y-9864D03*
X1151200Y-9700D03*
X1147331Y-7700D03*
X1140952Y-7851D03*
X1137992Y-1801D03*
X1144685Y-1751D03*
X1156212Y9300D03*
X1127952Y14814D03*
X1151211Y28100D03*
X1156252Y17114D03*
X1151112Y16900D03*
X1147331Y30100D03*
Y14814D03*
X1134645Y29949D03*
X1140952D03*
X1140988Y14714D03*
X1134645Y14814D03*
X1156265Y27936D03*
X1127952Y29949D03*
X1114340Y35999D03*
X1110520Y67900D03*
X1104141Y67749D03*
X1114366Y65950D03*
X1119440Y54914D03*
X1119400Y47100D03*
Y35800D03*
X1119453Y65736D03*
X1107874Y36049D03*
X1101181Y35999D03*
X1107724Y46914D03*
X1110520Y52614D03*
X1098581Y54883D03*
X1104177Y52514D03*
X1101181Y46900D03*
X1114300Y54700D03*
X1114340Y46898D03*
X1101181Y84714D03*
X1114340Y73799D03*
X1107874Y73849D03*
X1101181Y73799D03*
X1110520Y90314D03*
X1114340Y84698D03*
X1114316Y92500D03*
X1107724Y84714D03*
X1119440Y92714D03*
X1119416Y84700D03*
X1119466Y73550D03*
X1104177Y90314D03*
X1127952Y67749D03*
X1156211Y35800D03*
X1156200Y47000D03*
X1151152Y35999D03*
Y46898D03*
X1151100Y54700D03*
X1147331Y52614D03*
X1134645D03*
X1137992Y46914D03*
Y35999D03*
X1144535Y46914D03*
X1144685Y36049D03*
X1156252Y54914D03*
X1134645Y67749D03*
X1140952D03*
X1156265Y65736D03*
X1151178Y65950D03*
X1147331Y67900D03*
X1131299Y46914D03*
X1124606D03*
X1127952Y52614D03*
X1131299Y36049D03*
X1124606D03*
X1131299Y73849D03*
X1124606D03*
X1127952Y90414D03*
X1131299Y84714D03*
X1124606D03*
X1147331Y90414D03*
X1137992Y73799D03*
X1144535Y84714D03*
X1140988Y90314D03*
X1137992Y84714D03*
X1134645Y90414D03*
X1144685Y73849D03*
X1156252Y92714D03*
X1151128Y92500D03*
X1151152Y84698D03*
X1156228Y84700D03*
X1156278Y73550D03*
X1151152Y73799D03*
X1138242Y104314D03*
X1144685D03*
X1156278Y112865D03*
X1151152Y113114D03*
X1141038Y109564D03*
X1147331D03*
X1156265Y105051D03*
X1151178Y105265D03*
X1116141Y206446D03*
X1136420Y210346D03*
X1099241Y216196D03*
Y212296D03*
X1109381Y214247D03*
X1116141Y218147D03*
X1106001Y212296D03*
X1102621Y218147D03*
Y214247D03*
X1119521Y216196D03*
X1119520Y212296D03*
X1104871Y198050D03*
X1106001Y216196D03*
X1112761D03*
X1129660Y206447D03*
X1126280Y216196D03*
Y212296D03*
X1125300Y199900D03*
X1122900Y214247D03*
Y218147D03*
X1129660Y214247D03*
X1147950Y209900D03*
X1136420Y218147D03*
Y214247D03*
X1151060Y212296D03*
X1157820D03*
X1099241Y227896D03*
Y220096D03*
X1102621Y229847D03*
X1099241Y223996D03*
X1109381Y233746D03*
X1112761Y231797D03*
Y223996D03*
X1116141Y237647D03*
X1109381D03*
X1106001Y223996D03*
X1102621Y237647D03*
Y245447D03*
X1112761Y251296D03*
X1116141Y245447D03*
X1106001Y243496D03*
X1112761D03*
X1109381Y241547D03*
X1106001Y251296D03*
X1099241D03*
Y247396D03*
X1119521Y223996D03*
Y220096D03*
Y227896D03*
Y247396D03*
Y251296D03*
X1106001Y231797D03*
X1116141Y229847D03*
X1107561Y269038D03*
X1116141Y264947D03*
X1111631Y271300D03*
X1106001Y262996D03*
Y259096D03*
X1099241Y255196D03*
Y259096D03*
X1119521Y270796D03*
X1118391Y274997D03*
X1119521Y255196D03*
X1102621Y261047D03*
Y257147D03*
X1109381Y261047D03*
X1116141Y257147D03*
X1112761Y259096D03*
X1110648Y276899D03*
X1100200Y273300D03*
X1129660Y237647D03*
X1126280Y223996D03*
Y231797D03*
X1122900Y229847D03*
Y237647D03*
X1129660Y233746D03*
Y241547D03*
X1126280Y251296D03*
Y243496D03*
X1122900Y245447D03*
X1144300Y243496D03*
X1151060Y247396D03*
X1154440Y245447D03*
X1144300Y247396D03*
Y251296D03*
X1136420Y245447D03*
X1154440Y241547D03*
X1136420D03*
X1157820Y239596D03*
X1147680Y222047D03*
X1144300Y235696D03*
X1136420Y229847D03*
Y233746D03*
Y222047D03*
Y225947D03*
Y237647D03*
X1133040Y223996D03*
Y235696D03*
Y243496D03*
Y251296D03*
X1147680Y225947D03*
X1151060Y223996D03*
X1147680Y233746D03*
X1154440Y229847D03*
X1157820Y220096D03*
Y223996D03*
Y231797D03*
X1154440Y253247D03*
X1130780Y278596D03*
X1129660Y261047D03*
X1130780Y274696D03*
X1126280Y259096D03*
X1122900Y257147D03*
X1157820Y278596D03*
Y270796D03*
X1151060Y266896D03*
Y274696D03*
X1137540D03*
X1151060Y259096D03*
X1144300Y255196D03*
X1133040Y259096D03*
X1134160Y268847D03*
X1136420Y257147D03*
X1144300Y278596D03*
Y270796D03*
X1137540Y278596D03*
X1119521Y286396D03*
Y305896D03*
X1108251Y338746D03*
X1117261Y340996D03*
X1104871Y340697D03*
X1119521Y321496D03*
X1130780Y290296D03*
X1127400Y288347D03*
X1130780Y309797D03*
Y301996D03*
X1127400Y303947D03*
Y307847D03*
X1157820Y290296D03*
X1151060Y298096D03*
Y290296D03*
Y282496D03*
X1144300Y286396D03*
Y294196D03*
X1157820D03*
X1140920Y300047D03*
X1134160Y292247D03*
Y300047D03*
X1140920Y292247D03*
X1137540Y282496D03*
X1144300Y309797D03*
X1137540D03*
X1147680Y303947D03*
X1154440Y307847D03*
X1130780Y313696D03*
X1157820D03*
X1124021Y340996D03*
Y337096D03*
X1127400Y327347D03*
X1157820Y337096D03*
Y333196D03*
X1134160Y323446D03*
X1151060Y340996D03*
Y333196D03*
X1154440Y319547D03*
X1157820Y317596D03*
X1137540D03*
X1157820Y329296D03*
X1147680Y327347D03*
X1154440Y335147D03*
X1144300Y340996D03*
Y337096D03*
X1140920Y339047D03*
Y331247D03*
X1154440Y323446D03*
Y315647D03*
X1147680Y319547D03*
X1157820Y325396D03*
X1154440Y339047D03*
Y331247D03*
X1127400Y319547D03*
Y315647D03*
X1100361Y350747D03*
X1113881D03*
Y358547D03*
X1117261Y348796D03*
X1100361Y358547D03*
X1103741Y348796D03*
Y352696D03*
X1110501D03*
X1107121Y346847D03*
Y354647D03*
Y358547D03*
Y362447D03*
X1103741Y372197D03*
X1110501Y364396D03*
X1103741D03*
X1113881Y366347D03*
X1117261Y372197D03*
Y368296D03*
X1110501Y372197D03*
X1096981Y368296D03*
Y372197D03*
X1100361Y366347D03*
X1113881Y401447D03*
X1110501Y391696D03*
Y395595D03*
X1107121Y389747D03*
X1100361Y385847D03*
X1107121D03*
X1100361Y393647D03*
X1103741Y391696D03*
X1100361Y397547D03*
X1113881Y385847D03*
Y397546D03*
Y393647D03*
X1103741Y379996D03*
X1113881Y378047D03*
X1117261Y376096D03*
X1110501Y379996D03*
X1107121Y381947D03*
X1096981Y376096D03*
X1100361Y378047D03*
X1151060Y368296D03*
X1147680Y366347D03*
X1120641Y350747D03*
Y358547D03*
Y366347D03*
X1127400Y362447D03*
X1124021Y348796D03*
Y352696D03*
X1127400Y354647D03*
Y358547D03*
X1130780Y360496D03*
X1127400Y342947D03*
X1134160Y346847D03*
Y362447D03*
Y366347D03*
Y370247D03*
X1147680Y342947D03*
X1151060Y356596D03*
Y360496D03*
X1144300D03*
X1137540D03*
X1144300Y356596D03*
X1140920Y358547D03*
X1147680Y346847D03*
Y350747D03*
X1151060Y352696D03*
Y348796D03*
X1147680Y358547D03*
X1157820Y360496D03*
X1154440Y358547D03*
Y342947D03*
Y354647D03*
X1157820Y352696D03*
X1147680Y354647D03*
X1144300Y348796D03*
X1140920Y346847D03*
Y350747D03*
X1144300Y344896D03*
X1151060D03*
X1154440Y346847D03*
X1140920Y362447D03*
X1154440Y366347D03*
X1144300Y372197D03*
X1137540D03*
Y368296D03*
X1140920Y366347D03*
Y370247D03*
X1151060Y364396D03*
X1144300D03*
X1137540D03*
X1147680Y362447D03*
X1130780Y352696D03*
Y344896D03*
X1124021Y372197D03*
X1130780D03*
X1124021Y364396D03*
X1137540Y403396D03*
Y399496D03*
X1124021Y391696D03*
X1130780Y395596D03*
X1127400Y385847D03*
Y389747D03*
X1130780Y391696D03*
X1124021Y379996D03*
X1127400Y381947D03*
X1130780Y379996D03*
X1137540Y395597D03*
X1140920Y397546D03*
X1137540Y376096D03*
X1157820Y387796D03*
X1140920Y378047D03*
Y381947D03*
X1147680Y393647D03*
X1120641Y385847D03*
Y393647D03*
Y378047D03*
Y401447D03*
X1140920Y374146D03*
X1151060Y395597D03*
Y391696D03*
X1147680Y385847D03*
Y397546D03*
X1151060Y379996D03*
X1154440Y378047D03*
Y381947D03*
X1140920Y389747D03*
X1134160Y393647D03*
Y385847D03*
Y378047D03*
X1140920Y385847D03*
X1144300Y391696D03*
X1117261Y407296D03*
X1113881Y405347D03*
X1096699Y407782D03*
X1134160Y405347D03*
X1119440Y518114D03*
X1114316Y517900D03*
X1114340Y510098D03*
X1110520Y515714D03*
X1097343Y512794D03*
X1104177Y515714D03*
X1101181Y510114D03*
X1098300Y515300D03*
X1107724Y510114D03*
X1137992Y495887D03*
X1144385D03*
X1140988Y493744D03*
X1156252Y490867D03*
X1147331Y493494D03*
X1151168Y490867D03*
X1127952Y515814D03*
X1124606Y510114D03*
X1131299D03*
X1156252Y518114D03*
X1147331Y515814D03*
X1151128Y517900D03*
X1156252Y498867D03*
X1151168D03*
X1151152Y510098D03*
X1134645Y515814D03*
X1137992Y510114D03*
X1140988Y515714D03*
X1144535Y510114D03*
X1156228Y510100D03*
X1104141Y530949D03*
X1098040Y536723D03*
X1098160Y533809D03*
X1119416Y547900D03*
X1119466Y536750D03*
X1119453Y528936D03*
X1098300Y553100D03*
X1114340Y547898D03*
X1107724Y547914D03*
X1101181D03*
X1110520Y553514D03*
X1104177D03*
X1098118Y549843D03*
X1098018Y531156D03*
X1114366Y529150D03*
X1114340Y536999D03*
X1110520Y531100D03*
X1107874Y537049D03*
X1101181Y536999D03*
X1119440Y555914D03*
X1114316Y555700D03*
X1119416Y585700D03*
X1119466Y574550D03*
X1119453Y566736D03*
X1104141Y568749D03*
X1097899Y574773D03*
X1101181Y585714D03*
X1097834Y569200D03*
X1107724Y585714D03*
X1107874Y574849D03*
X1110520Y568900D03*
X1101181Y574799D03*
X1114340D03*
Y585698D03*
X1114366Y566950D03*
X1140988Y553514D03*
X1151152Y547898D03*
X1156228Y547900D03*
X1137992Y547914D03*
X1144535D03*
X1127952Y553614D03*
X1131299Y547914D03*
X1124606D03*
X1131299Y537049D03*
X1124606D03*
X1127952Y530949D03*
X1151178Y529150D03*
X1151152Y536999D03*
X1147331Y531100D03*
X1156278Y536750D03*
X1156265Y528936D03*
X1134645Y530949D03*
X1140952D03*
X1137992Y536999D03*
X1144685Y537049D03*
X1147331Y553614D03*
X1134645D03*
X1156252Y555914D03*
X1151128Y555700D03*
X1156265Y566736D03*
X1151178Y566950D03*
X1134645Y568749D03*
X1137992Y585714D03*
X1144535D03*
X1140952Y568749D03*
X1137992Y574799D03*
X1144685Y574849D03*
X1151152Y585698D03*
Y574799D03*
X1147331Y568900D03*
X1156228Y585700D03*
X1156278Y574550D03*
X1131299Y585714D03*
X1124606D03*
X1131299Y574849D03*
X1127952Y568749D03*
X1124606Y574849D03*
X1137992Y612599D03*
X1144685Y612649D03*
X1151152Y612599D03*
X1124606Y612649D03*
X1131299D03*
X1114340Y612599D03*
X1107874Y612649D03*
X1101181Y612599D03*
X1097352Y607220D03*
X1110520Y606700D03*
X1119453Y604536D03*
X1119466Y612350D03*
X1119440Y593714D03*
X1104177Y591314D03*
X1110520D03*
X1114316Y593500D03*
X1098300Y590900D03*
X1114366Y604750D03*
X1104141Y606549D03*
X1156265Y604536D03*
X1147331Y606700D03*
X1134645Y606549D03*
X1140952D03*
X1156278Y612350D03*
X1134645Y591414D03*
X1140988Y591314D03*
X1151128Y593500D03*
X1147331Y591414D03*
X1156252Y593714D03*
X1151178Y604750D03*
X1127952Y606549D03*
Y591414D03*
X1161417Y9114D03*
X1168110D03*
X1174803D03*
X1171456Y-7851D03*
X1164763D03*
X1177763D03*
X1168110Y-1751D03*
X1161417D03*
X1174803Y-1801D03*
X1171456Y14814D03*
X1164763Y29949D03*
X1171456D03*
X1164763Y14814D03*
X1177799Y14714D03*
X1177763Y29949D03*
X1181496Y-1751D03*
X1181346Y9114D03*
X1187963Y9098D03*
X1204921Y9114D03*
X1198228D03*
X1188011Y-9700D03*
X1193076Y-9864D03*
X1184142Y-7700D03*
X1193111Y-2000D03*
X1187963Y-1801D03*
X1201574Y-7851D03*
X1204921Y-1751D03*
X1198228D03*
X1218307D03*
X1211614Y-1801D03*
X1214574Y-7851D03*
X1208267D03*
X1218157Y9114D03*
X1211614D03*
X1193023Y9300D03*
X1184142Y30100D03*
Y14814D03*
X1188023Y28100D03*
X1187923Y16900D03*
X1193063Y17114D03*
X1193076Y27936D03*
X1201574Y14814D03*
Y29949D03*
X1208267Y14814D03*
Y29949D03*
X1214600Y14714D03*
X1214574Y29949D03*
X1161417Y36049D03*
X1164763Y52614D03*
X1168110Y36049D03*
Y46914D03*
X1161417D03*
X1174803D03*
X1171456Y52614D03*
X1174803Y35999D03*
X1177763Y67749D03*
X1171456D03*
X1164763D03*
X1177799Y90314D03*
X1174803Y84714D03*
X1168110D03*
Y73849D03*
X1161417D03*
X1174803Y73799D03*
X1161417Y84714D03*
X1164763Y90414D03*
X1171456D03*
X1181346Y46914D03*
X1181496Y36049D03*
X1184142Y52614D03*
X1193012Y47000D03*
X1187963Y46898D03*
Y35999D03*
X1187912Y54700D03*
X1187989Y65950D03*
X1193076Y65736D03*
X1193063Y54914D03*
X1193023Y35800D03*
X1204921Y36049D03*
X1198228D03*
Y46914D03*
X1204921D03*
X1201574Y52614D03*
X1184142Y67900D03*
X1201574Y67749D03*
X1218307Y36049D03*
X1211614Y35999D03*
X1214960Y52864D03*
X1211614Y46914D03*
X1218157D03*
X1208267Y52614D03*
X1211614Y73799D03*
X1218307Y73849D03*
X1208267Y90414D03*
X1218157Y84714D03*
X1211614D03*
X1214574Y67749D03*
X1208267D03*
X1181346Y84714D03*
X1181496Y73849D03*
X1184142Y90414D03*
X1193039Y84700D03*
X1193063Y92714D03*
X1187939Y92500D03*
X1187963Y84698D03*
Y73799D03*
X1193089Y73550D03*
X1198228Y73849D03*
X1204921D03*
X1198228Y84714D03*
X1204921D03*
X1201574Y90414D03*
X1177799Y109914D03*
X1161632Y104314D03*
X1170721Y109564D03*
X1164428D03*
X1168075Y104314D03*
X1174742D03*
X1208267Y110014D03*
X1181346Y104314D03*
X1187963Y113114D03*
X1193089Y112865D03*
X1184142Y109564D03*
X1193076Y105051D03*
X1187989Y105265D03*
X1201574Y110014D03*
X1198228Y104314D03*
X1204921D03*
X1161200Y206446D03*
X1167960Y206447D03*
Y218147D03*
X1171339Y208397D03*
X1174719Y218147D03*
Y206447D03*
X1178099Y208397D03*
Y216196D03*
X1161200Y210346D03*
Y218147D03*
X1181479Y206447D03*
X1188239Y210346D03*
Y206447D03*
X1201759Y218147D03*
X1205759Y206682D03*
X1197492Y201356D03*
X1198379Y212296D03*
X1194999Y210346D03*
X1184859Y204496D03*
X1188239Y214247D03*
X1164580Y235696D03*
X1167960Y229847D03*
X1164580Y223996D03*
Y227896D03*
Y239596D03*
X1178099Y247396D03*
X1161200Y241547D03*
X1164580Y247396D03*
X1161200Y249347D03*
X1171339Y247396D03*
X1178099Y243496D03*
X1171339Y235696D03*
Y220096D03*
Y231797D03*
X1178099Y227896D03*
Y235696D03*
Y220096D03*
X1174719Y237647D03*
X1167960Y253247D03*
X1174719D03*
X1164580Y270796D03*
X1171339Y274696D03*
X1174719Y280547D03*
X1171339Y266896D03*
X1164580Y278596D03*
X1159578Y265117D03*
X1171339Y259096D03*
X1178099Y274696D03*
X1181479Y222047D03*
X1188239D03*
X1191619Y239596D03*
X1188239Y225947D03*
X1184859Y235696D03*
X1188239Y237647D03*
X1184859Y247396D03*
X1188239Y249347D03*
X1201759Y229847D03*
Y225947D03*
Y233746D03*
X1198379Y235696D03*
Y243496D03*
X1201759Y241547D03*
Y249347D03*
X1198379Y239596D03*
X1194999Y225947D03*
Y222047D03*
Y233746D03*
X1184859Y239596D03*
Y251296D03*
X1212199D03*
Y243496D03*
X1208519Y233746D03*
X1215700Y223600D03*
X1194999Y264947D03*
Y268847D03*
Y272747D03*
Y280547D03*
X1188239Y257147D03*
X1208519Y272747D03*
X1208819Y280547D03*
X1181479Y261047D03*
Y268847D03*
Y276646D03*
X1212199Y274696D03*
X1217200Y270500D03*
X1213808Y264800D03*
X1208519Y264947D03*
X1184859Y259096D03*
X1191619Y274696D03*
X1205139D03*
X1198379Y278596D03*
X1201759Y261047D03*
X1198379Y255196D03*
X1201759Y257147D03*
X1174719Y300047D03*
Y284447D03*
X1164580Y294196D03*
Y290296D03*
Y286396D03*
X1161200Y284447D03*
X1178099Y294196D03*
Y298096D03*
Y286396D03*
X1164580Y301996D03*
X1171339D03*
X1161200Y307847D03*
Y335147D03*
Y339047D03*
X1164580Y329296D03*
Y333196D03*
Y337096D03*
X1167960Y339047D03*
Y327347D03*
X1161200Y331247D03*
Y327347D03*
X1178099Y337096D03*
Y317596D03*
X1164580Y321496D03*
Y317596D03*
X1161200Y323446D03*
Y319547D03*
Y315647D03*
X1167960Y323446D03*
Y315647D03*
Y319547D03*
X1174719Y315647D03*
X1171339Y317596D03*
X1164580Y325396D03*
X1171339D03*
X1174719Y335147D03*
X1205500Y309797D03*
X1198379D03*
X1194999Y288347D03*
Y292247D03*
Y296147D03*
Y300047D03*
Y307847D03*
Y303947D03*
X1191619Y298096D03*
X1181479Y300047D03*
Y288347D03*
Y292247D03*
Y311747D03*
Y307847D03*
Y303947D03*
X1188239Y288347D03*
Y284447D03*
Y292247D03*
X1184859Y294196D03*
Y290296D03*
X1191619Y294196D03*
X1184859Y309797D03*
X1188239Y311747D03*
X1184859Y301996D03*
X1201759Y284447D03*
Y288347D03*
X1205439Y298096D03*
X1198379Y286396D03*
X1205439Y305896D03*
X1194999Y335147D03*
Y331247D03*
X1212200Y333196D03*
X1208519Y339047D03*
X1208826Y319544D03*
X1181479Y327347D03*
Y319547D03*
Y335147D03*
X1198379Y313696D03*
X1188239Y319547D03*
X1184859Y321496D03*
X1188239Y339047D03*
Y335147D03*
X1184859Y329296D03*
X1191619Y321496D03*
X1198379Y325396D03*
Y340996D03*
X1201759Y323446D03*
X1205139Y333196D03*
X1194999Y319547D03*
Y315647D03*
X1167960Y370247D03*
X1164580Y372197D03*
X1171339Y356596D03*
Y360496D03*
X1164580Y356596D03*
X1167960Y342947D03*
X1171339Y348796D03*
X1174719Y354647D03*
Y342947D03*
X1161200Y370247D03*
X1171339Y372197D03*
X1167960Y362447D03*
X1178099Y364396D03*
X1171339Y399496D03*
X1164580Y403396D03*
X1178099D03*
X1167960Y389747D03*
X1161200Y397546D03*
X1167960Y397547D03*
X1174719Y393647D03*
X1161200Y378047D03*
X1164580Y379996D03*
X1174719Y381947D03*
X1194999Y346847D03*
Y354647D03*
X1209219Y370247D03*
X1212199Y356597D03*
Y344896D03*
Y352696D03*
X1181479Y346847D03*
X1188239Y366347D03*
X1194999D03*
X1191619Y348796D03*
X1184859Y356596D03*
X1191619Y360496D03*
X1201759Y350747D03*
X1205139Y360496D03*
X1181479Y374146D03*
Y389747D03*
X1209769Y374146D03*
X1184859Y383896D03*
X1188239Y393647D03*
X1201759Y389747D03*
X1197258Y397546D03*
X1194999Y385847D03*
X1188239Y378047D03*
X1201759D03*
X1208819Y393647D03*
Y381897D03*
X1195555Y405773D03*
X1192200Y409550D03*
X1185989Y407800D03*
X1180400Y495787D03*
X1167500Y495800D03*
X1174203Y495787D03*
X1161320Y495800D03*
X1170656Y491144D03*
X1164363Y491044D03*
X1177849Y490944D03*
X1168110Y510114D03*
X1164763Y515814D03*
X1161417Y510114D03*
X1177799Y515714D03*
X1171456Y515814D03*
X1174803Y510114D03*
X1208267Y493444D03*
X1200974Y490744D03*
X1193063Y490909D03*
X1187978Y490609D03*
X1184142Y490794D03*
X1181346Y510114D03*
X1204400Y495887D03*
X1198100Y495800D03*
X1208267Y515814D03*
X1211614Y510114D03*
X1218157D03*
X1187963Y510098D03*
X1204921Y510114D03*
X1198228D03*
X1201574Y515814D03*
X1184142D03*
X1187939Y517900D03*
X1193039Y510100D03*
X1193063Y518114D03*
X1187978Y498609D03*
X1193063Y498909D03*
X1161417Y547914D03*
X1168110D03*
X1174803D03*
X1177799Y553514D03*
X1177763Y530949D03*
X1168110Y537049D03*
X1164763Y530949D03*
X1161417Y537049D03*
X1171456Y530949D03*
X1174803Y536999D03*
X1164763Y553614D03*
X1171456D03*
X1174803Y574799D03*
X1161417Y574849D03*
X1171456Y568749D03*
X1168110Y585714D03*
X1161417D03*
X1168110Y574849D03*
X1164763Y568749D03*
X1174803Y585714D03*
X1177763Y568749D03*
X1181496Y537049D03*
X1181346Y547914D03*
X1211614Y536999D03*
X1214574Y530949D03*
X1184142Y531100D03*
X1193076Y528936D03*
X1198228Y547914D03*
X1204921D03*
X1201574Y553614D03*
Y530949D03*
X1204921Y537049D03*
X1198228D03*
X1193039Y547900D03*
X1187963Y547898D03*
X1184142Y553614D03*
X1193089Y536750D03*
X1187989Y529150D03*
X1187963Y536999D03*
X1218307Y537049D03*
X1211614Y547914D03*
X1208267Y553614D03*
Y530949D03*
X1218157Y547914D03*
X1181346Y585714D03*
X1181496Y574849D03*
X1193063Y555914D03*
X1187939Y555700D03*
X1218157Y585714D03*
X1218307Y574849D03*
X1208267Y568749D03*
X1214574D03*
X1211614Y574799D03*
Y585714D03*
X1184142Y568900D03*
X1187989Y566950D03*
X1193076Y566736D03*
X1193039Y585700D03*
X1187963Y585698D03*
X1193089Y574550D03*
X1187963Y574799D03*
X1198228Y585714D03*
Y574849D03*
X1204921Y585714D03*
Y574849D03*
X1201574Y568749D03*
X1181496Y612649D03*
X1218307D03*
X1211614Y612599D03*
X1187963D03*
X1204921Y612649D03*
X1198228D03*
X1168110D03*
X1161417D03*
X1174803Y612599D03*
X1171456Y606549D03*
X1164763D03*
Y591414D03*
X1171456D03*
X1177799Y591314D03*
X1177763Y606549D03*
X1208267Y591414D03*
X1214574Y606549D03*
X1208267D03*
X1187939Y593500D03*
X1184142Y591414D03*
X1193063Y593714D03*
X1187989Y604750D03*
X1193076Y604536D03*
X1193089Y612350D03*
X1184142Y606700D03*
X1201574Y591414D03*
Y606549D03*
X1238385Y29949D03*
Y14814D03*
X1245078Y29949D03*
Y14814D03*
X1251771Y16999D03*
X1248425Y27899D03*
X1269700Y13078D03*
X1267960Y28494D03*
X1241732Y-1751D03*
X1238385Y-7851D03*
X1241732Y9114D03*
X1248425Y-1751D03*
Y-9901D03*
X1251771D03*
X1245078Y-7851D03*
X1248425Y9157D03*
X1269800Y-5822D03*
X1235039Y9114D03*
X1224774Y9098D03*
X1224822Y-9700D03*
X1229887Y-9864D03*
X1224774Y-1801D03*
X1235039Y-1751D03*
X1229922Y-2000D03*
X1220953Y-7700D03*
X1229800Y9300D03*
X1224790Y16900D03*
X1229874Y17114D03*
X1229887Y27936D03*
X1220953Y30100D03*
X1224800Y28100D03*
X1220953Y14814D03*
X1241732Y36049D03*
Y46914D03*
X1238385Y52614D03*
Y67749D03*
X1245078Y52614D03*
X1251771Y65699D03*
X1248425D03*
Y36049D03*
Y46957D03*
X1245078Y67749D03*
X1267976Y73676D03*
X1268022Y54443D03*
X1241732Y84714D03*
Y73849D03*
X1238385Y90414D03*
X1251771Y92599D03*
X1245078Y90414D03*
X1248425Y84757D03*
Y73849D03*
X1268581Y92706D03*
X1224774Y84698D03*
X1224750Y92500D03*
X1224774Y73799D03*
X1235039Y84714D03*
Y73849D03*
X1229800Y35750D03*
X1229874Y54914D03*
X1235039Y46914D03*
Y36049D03*
X1224774Y46898D03*
X1220953Y52614D03*
X1224774Y35999D03*
X1229887Y65736D03*
X1224800Y65950D03*
X1220953Y67900D03*
X1229900Y73550D03*
X1229850Y84700D03*
X1229874Y92714D03*
X1220953Y90414D03*
X1240927Y154932D03*
X1266200Y122500D03*
X1254024Y128013D03*
X1246251Y130066D03*
X1257800Y110900D03*
X1260500Y117500D03*
X1247326Y122802D03*
X1254300Y105200D03*
X1277660Y109450D03*
X1277230Y117570D03*
X1237400Y103100D03*
X1241712Y187710D03*
X1220167Y194407D03*
X1220017Y220323D03*
X1220194Y243384D03*
X1223100Y258600D03*
X1223508Y262600D03*
X1259800Y463300D03*
X1255530Y474770D03*
X1269050Y486650D03*
X1269600Y480800D03*
X1272830Y471660D03*
X1257720Y493060D03*
X1255388Y483557D03*
X1256130Y467820D03*
X1241732Y510114D03*
X1238385Y515814D03*
X1269000Y514700D03*
X1245078Y515814D03*
X1251771Y517999D03*
X1248425Y510157D03*
X1235039Y510114D03*
X1220953Y515814D03*
X1229874Y518114D03*
X1229850Y510100D03*
X1224750Y517900D03*
X1224774Y510098D03*
X1241732Y547914D03*
Y537049D03*
X1238385Y530949D03*
Y553614D03*
X1269800Y532978D03*
X1251771Y528899D03*
X1248425Y537049D03*
Y528899D03*
X1245078Y553614D03*
Y530949D03*
X1248425Y547957D03*
X1241732Y574849D03*
Y585714D03*
X1238385Y568749D03*
X1268500Y555800D03*
X1267900Y574300D03*
X1248425Y585757D03*
Y574849D03*
Y566699D03*
X1245078Y568749D03*
X1220953Y531100D03*
X1229887Y528936D03*
X1229900Y536750D03*
X1224800Y529150D03*
X1224774Y536999D03*
X1235039Y537049D03*
Y547914D03*
X1229850Y547900D03*
X1224774Y547898D03*
X1220953Y553614D03*
X1229874Y555914D03*
X1224750Y555700D03*
X1220953Y568900D03*
X1229900Y574550D03*
X1224774Y574799D03*
X1229850Y585700D03*
X1224774Y585698D03*
X1229887Y566736D03*
X1224800Y566950D03*
X1235039Y585714D03*
Y574849D03*
X1241732Y612649D03*
X1238385Y606549D03*
Y591414D03*
X1263800Y606800D03*
X1267800Y593600D03*
X1248425Y612649D03*
X1251771Y604499D03*
X1248425D03*
X1245078Y606549D03*
X1251771Y593599D03*
X1245078Y591414D03*
X1224774Y612599D03*
X1235039Y612649D03*
X1220953Y591414D03*
X1229874Y593714D03*
X1224750Y593500D03*
X1224800Y604750D03*
X1229887Y604536D03*
X1220953Y606700D03*
X1229900Y612350D03*
X1304940Y32350D03*
X1296928Y48700D03*
X1301000Y62000D03*
X1323500Y68000D03*
X1318341Y60000D03*
X1321841Y63000D03*
X1304000Y62000D03*
X1318341Y63000D03*
X1341400Y46100D03*
X1336900Y89896D03*
X1323500Y75000D03*
Y71500D03*
X1335120Y94450D03*
X1286000Y134500D03*
Y139500D03*
Y137000D03*
X1298400Y144500D03*
X1288500Y137000D03*
Y139500D03*
Y134500D03*
X1286000Y132000D03*
X1288500D03*
X1338500Y96000D03*
X1322628Y100134D03*
X1323800Y104250D03*
X1326800D03*
Y107250D03*
X1323800D03*
X1326600Y123450D03*
X1323600D03*
X1326600Y126450D03*
X1323600D03*
X1340100Y145000D03*
X1335100Y155000D03*
Y145000D03*
X1330100Y150000D03*
X1340100D03*
Y155000D03*
X1315100Y145000D03*
X1335100Y150000D03*
X1330100Y145000D03*
Y155000D03*
Y160000D03*
X1340100D03*
X1306363Y169928D03*
X1335100Y160000D03*
X1324938Y209251D03*
X1322500D03*
X1320390Y216824D03*
X1303838Y169922D03*
X1320400Y234959D03*
X1325900D03*
X1314900D03*
X1336900D03*
X1331400D03*
X1342400D03*
X1334113Y273115D03*
X1340866Y268795D03*
X1327625Y275971D03*
X1336480Y309755D03*
X1336793Y303784D03*
X1342500Y312100D03*
X1316300Y282000D03*
X1325300Y282600D03*
X1341920Y309755D03*
X1342480Y303852D03*
X1319906Y338025D03*
X1338500Y319600D03*
X1326626Y464400D03*
X1300100Y442500D03*
X1301000Y460900D03*
X1305100Y432500D03*
X1320100Y427500D03*
Y432500D03*
X1325100Y427500D03*
Y432500D03*
X1305181Y427834D03*
X1310100Y427500D03*
Y432500D03*
X1315100Y427500D03*
Y432500D03*
X1340100Y427500D03*
X1330100Y432500D03*
Y427500D03*
X1335100Y457500D03*
Y452500D03*
Y447500D03*
Y442500D03*
X1330100D03*
X1305100D03*
X1310100D03*
X1320100D03*
X1315100D03*
X1325100D03*
X1340100Y457500D03*
Y452500D03*
Y447500D03*
Y442500D03*
X1337100Y499300D03*
X1319738Y477497D03*
X1326877Y469279D03*
X1319699Y472327D03*
X1301000Y466500D03*
X1334300Y499300D03*
X1340986Y511187D03*
X1319300Y525450D03*
X1321800D03*
X1311772Y501000D03*
X1319075D03*
X1316675Y500983D03*
X1314272Y501000D03*
X1343100Y566300D03*
X1340700D03*
X1338000D03*
X1340526Y563337D03*
X1343026D03*
X1338026D03*
X1333026D03*
X1335526D03*
Y566237D03*
X1321800Y532750D03*
X1319300Y532650D03*
X1321800Y527850D03*
X1319300D03*
Y530250D03*
X1321800D03*
X1333026Y566237D03*
X1298100Y598300D03*
Y595800D03*
Y590000D03*
Y592500D03*
X1307600Y620100D03*
X1357400Y-19800D03*
X1360400Y10600D03*
X1350654Y-18411D03*
X1348154Y-15911D03*
Y-18411D03*
X1357600Y5140D03*
X1345518Y-18476D03*
X1353154Y-18411D03*
X1375676Y7630D03*
X1385608Y-17485D03*
X1388294Y-5675D03*
X1389523Y4966D03*
X1355950Y-16507D03*
X1359450Y-7D03*
X1355950D03*
X1357489Y-1924D03*
X1359450Y2493D03*
X1355950D03*
X1357489Y-14424D03*
Y-10524D03*
Y-6124D03*
X1355889Y-8524D03*
X1355847Y-12275D03*
X1355989Y-3924D03*
X1356261Y32017D03*
X1356300Y20100D03*
X1356376Y24167D03*
X1356200Y28200D03*
X1357900Y30200D03*
X1357800Y26100D03*
X1357803Y22200D03*
X1356261Y15517D03*
X1357700Y17800D03*
X1359761Y32317D03*
X1371650Y-907D03*
X1371589Y-3424D03*
Y-5924D03*
X1371900Y28600D03*
Y26100D03*
Y31100D03*
X1369408Y50479D03*
X1375500Y76000D03*
X1397500Y51000D03*
X1365855Y46972D03*
X1359800Y37300D03*
X1357300D03*
X1361634Y95519D03*
X1347000Y87500D03*
X1343500D03*
X1360700Y86550D03*
X1344000Y83000D03*
X1402700Y51100D03*
X1381817Y46484D03*
X1388627Y35032D03*
X1380500Y54500D03*
X1380900Y59820D03*
X1372400Y37785D03*
X1389138Y58499D03*
X1370100Y82500D03*
X1366100D03*
X1364700Y86550D03*
X1389068Y78556D03*
X1389100Y74600D03*
X1350830Y60730D03*
X1356261Y34517D03*
X1356950Y54370D03*
X1356760Y66660D03*
X1357000Y60500D03*
X1359761Y34817D03*
X1350800Y66600D03*
X1351190Y54710D03*
X1363170Y54280D03*
X1362900Y60500D03*
X1363040Y66660D03*
X1380500Y50500D03*
X1356230Y126500D03*
X1359230D03*
X1360730Y129000D03*
X1362230Y126500D03*
X1355100Y155000D03*
Y145000D03*
Y150000D03*
X1360100Y155000D03*
Y145000D03*
Y150000D03*
X1361634Y97919D03*
X1345100Y150000D03*
X1350100Y155000D03*
Y150000D03*
Y145000D03*
X1345100D03*
Y155000D03*
X1397994Y103350D03*
X1397952Y105998D03*
X1395326Y100913D03*
Y103413D03*
X1395347Y106040D03*
X1386700Y125450D03*
Y128450D03*
X1383700Y125450D03*
Y128450D03*
X1380700Y125450D03*
Y128450D03*
X1376100Y116100D03*
X1376669Y121763D03*
Y118763D03*
X1376100Y124950D03*
X1373850Y114450D03*
X1369730Y129000D03*
X1363730D03*
X1366730D03*
X1373850Y117450D03*
X1368230Y126500D03*
X1373850Y123450D03*
X1365230Y126500D03*
X1397193Y112602D03*
X1394253Y116989D03*
X1385100Y155000D03*
X1375100D03*
X1365100D03*
X1380100D03*
Y145000D03*
X1385100D03*
X1380100Y150000D03*
X1385100D03*
X1365100Y145000D03*
Y150000D03*
X1375100D03*
X1370100Y155000D03*
Y145000D03*
X1375100D03*
X1370100Y150000D03*
X1352200Y104950D03*
Y108400D03*
X1357700D03*
Y104950D03*
X1373850Y120450D03*
X1380100Y160000D03*
X1360100D03*
X1355100D03*
X1345100D03*
X1350100D03*
X1390100D03*
X1370100D03*
X1390100Y170000D03*
X1385100Y160000D03*
Y165000D03*
Y170000D03*
X1365100Y160000D03*
X1375100D03*
X1390100Y165000D03*
X1383753Y265548D03*
X1397400Y234959D03*
X1391900D03*
X1386400D03*
X1358900D03*
X1353400D03*
X1347900D03*
X1349500Y265500D03*
X1359100Y265600D03*
X1380900Y234959D03*
X1369900D03*
X1364400D03*
X1375400Y235100D03*
X1369100Y265500D03*
X1374864Y265629D03*
X1398062Y315743D03*
X1403100Y321350D03*
X1383639Y315274D03*
X1389600Y315200D03*
X1384024Y320225D03*
X1386048Y310310D03*
X1386265Y304310D03*
X1389600Y320100D03*
X1397640Y310631D03*
X1397880Y304640D03*
X1392380D03*
X1392340Y310625D03*
X1403260Y310623D03*
X1403300Y304640D03*
X1388208Y341489D03*
X1348080Y309825D03*
X1353142Y309761D03*
X1358792Y309760D03*
X1358800Y303700D03*
X1353359Y303767D03*
X1348190Y303810D03*
X1346550Y322350D03*
X1350650Y315050D03*
X1357452Y319395D03*
X1369540Y310125D03*
X1374900Y310130D03*
X1381100Y304360D03*
X1380910Y310300D03*
X1364044Y309691D03*
X1364213Y303694D03*
X1375040Y304135D03*
X1369540D03*
X1371000Y322400D03*
X1363059Y314514D03*
X1368947Y313993D03*
X1358500Y338400D03*
X1370200D03*
X1364300Y338300D03*
X1392144Y364617D03*
X1389450Y372250D03*
X1384700Y359700D03*
X1392500Y344600D03*
X1392805Y360466D03*
X1388500Y350864D03*
X1391200Y386300D03*
X1384531Y382957D03*
X1394760Y394720D03*
X1362510Y360717D03*
X1354024Y398985D03*
X1352338Y404153D03*
X1351379Y399227D03*
X1352239Y401593D03*
X1358512Y371792D03*
X1360450Y402100D03*
X1359360Y398810D03*
X1357880Y403760D03*
X1356560Y398910D03*
X1362250Y399160D03*
X1354681Y401444D03*
X1354982Y404154D03*
X1357542Y401381D03*
X1364856Y366666D03*
X1382017Y367584D03*
X1363250Y401700D03*
X1371200Y402100D03*
X1381500Y396200D03*
X1375201Y396303D03*
X1365731Y360698D03*
X1358500Y374500D03*
X1360200Y377400D03*
X1358655Y379352D03*
X1362068Y393385D03*
X1360300Y381100D03*
X1360200Y384700D03*
Y389000D03*
X1358700Y386700D03*
X1358568Y390885D03*
Y393385D03*
X1358600Y382800D03*
X1362068Y390885D03*
X1374268Y389985D03*
X1374207Y384968D03*
Y387468D03*
X1370300Y350200D03*
X1358300Y344200D03*
X1358400Y350100D03*
X1370200Y343900D03*
X1364100Y350200D03*
X1385416Y410502D03*
X1404558Y416575D03*
X1402725Y408136D03*
X1402520Y413246D03*
X1388085Y410479D03*
X1403998Y429775D03*
X1404558Y421575D03*
X1398275Y453561D03*
X1397975Y457561D03*
X1403998Y434775D03*
X1382849Y410471D03*
X1380449Y410479D03*
X1358990Y411040D03*
X1358910Y408480D03*
X1358980Y406060D03*
X1355100Y427500D03*
Y432500D03*
X1361558Y410527D03*
X1345100Y442500D03*
X1350100D03*
X1345100Y437500D03*
X1350100D03*
X1355100D03*
Y442500D03*
X1369034Y458075D03*
X1369907Y410513D03*
X1372535Y410512D03*
X1375239Y410590D03*
X1377928Y410451D03*
X1366984Y410481D03*
X1364403Y410496D03*
X1380100Y447500D03*
X1370100Y442500D03*
X1365100Y452500D03*
X1379857Y458108D03*
X1365100Y442500D03*
X1375100D03*
X1380100Y452500D03*
X1365100Y447500D03*
X1388900Y525230D03*
X1395581Y525357D03*
X1383600Y482504D03*
X1386041Y493723D03*
X1383519Y487445D03*
X1390330Y516690D03*
X1385033Y516848D03*
X1387568Y516892D03*
X1388865Y519788D03*
X1388850Y522266D03*
X1386033Y498811D03*
X1355800Y508500D03*
X1363800Y481600D03*
X1363662Y486636D03*
X1365741Y492723D03*
X1382578Y516805D03*
X1377492Y516892D03*
X1369757Y517465D03*
X1365719Y497545D03*
X1352490Y515470D03*
X1346870Y515450D03*
X1352590Y519170D03*
X1346970Y519150D03*
X1401777Y557632D03*
X1385033Y544267D03*
X1390623Y574986D03*
X1400830Y564090D03*
X1400288Y570099D03*
X1404420Y576330D03*
X1404519Y560280D03*
Y557380D03*
X1361600Y559400D03*
X1358529Y537492D03*
X1361163Y540052D03*
X1358518Y540073D03*
X1356018D03*
X1356029Y537492D03*
X1363674Y537471D03*
X1355548Y559959D03*
X1361926Y584037D03*
Y586537D03*
X1359100Y586200D03*
X1357400Y588400D03*
X1360100D03*
X1344613Y556376D03*
Y561376D03*
Y558876D03*
X1347700Y554100D03*
X1353520Y537480D03*
X1344613Y553876D03*
X1361174Y537471D03*
X1358439Y559959D03*
X1375479Y540117D03*
X1375500Y537717D03*
X1366265Y537437D03*
X1363663Y540052D03*
X1363568Y550589D03*
X1380521Y535276D03*
X1378021D03*
X1375621Y535254D03*
X1371265Y537437D03*
X1368765D03*
X1366459Y550589D03*
X1377979Y537717D03*
Y540117D03*
X1380479Y537717D03*
X1368596Y539889D03*
X1371096D03*
X1366096D03*
X1380479Y540117D03*
X1376800Y584328D03*
X1364426Y586637D03*
Y584137D03*
X1360500Y570900D03*
Y574700D03*
X1360261Y578873D03*
X1360247Y567390D03*
X1360261Y562373D03*
Y581373D03*
X1362000Y576700D03*
Y572800D03*
X1362100Y569100D03*
X1362000Y565600D03*
X1363761Y581373D03*
X1375961Y577973D03*
X1376000Y575456D03*
Y572956D03*
X1387050Y615350D03*
X1392500Y592000D03*
X1376556Y615756D03*
X1357726Y591037D03*
X1360226D03*
X1363761Y612573D03*
X1360261D03*
X1360200Y597800D03*
X1361600Y599900D03*
X1361500Y595700D03*
X1360100Y610100D03*
X1360200Y606300D03*
Y602000D03*
X1361900Y608200D03*
X1361500Y604200D03*
X1360261Y593573D03*
X1363761Y610073D03*
X1375961Y609173D03*
X1375900Y604156D03*
Y606656D03*
X1454715Y2784D03*
X1450508Y2756D03*
X1410571Y13170D03*
X1420019Y13466D03*
X1448367Y13533D03*
X1438918D03*
X1429469Y13466D03*
X1457814D03*
X1436131Y5248D03*
X1432661Y5220D03*
X1406674Y46120D03*
X1411254Y46018D03*
X1412250Y65359D03*
X1407150Y58859D03*
X1410150D03*
X1407150Y52859D03*
X1410150D03*
X1409250Y65359D03*
X1407150Y55859D03*
X1410150D03*
X1413721Y36749D03*
X1412250Y68359D03*
X1409250D03*
X1409150Y71259D03*
X1412150D03*
X1442067Y34830D03*
X1423170Y36635D03*
X1432619Y34830D03*
X1451516D03*
X1460965D03*
X1452648Y103788D03*
X1451273Y148905D03*
X1449847Y202322D03*
X1439000Y208500D03*
X1442251Y180818D03*
X1418300Y199900D03*
X1440150Y175550D03*
X1440124Y166180D03*
X1451427Y167818D03*
X1434800Y248900D03*
X1462700Y221700D03*
X1464200Y231400D03*
X1458800Y254882D03*
X1410800Y316100D03*
X1408580Y310632D03*
X1408760Y304637D03*
X1410550Y320800D03*
X1419343Y310652D03*
X1419283Y304570D03*
X1413983Y304645D03*
X1413943Y310628D03*
X1417656Y367547D03*
X1420101Y396236D03*
X1418138Y386361D03*
X1415000Y399000D03*
X1412220Y388360D03*
X1417217Y379129D03*
X1417349Y382137D03*
X1417773Y374107D03*
X1464124Y353776D03*
X1465500Y395400D03*
X1456750Y381850D03*
X1459033Y395334D03*
X1446700Y387900D03*
X1437897Y402315D03*
X1443100Y368950D03*
X1439934Y403730D03*
X1411900Y429775D03*
X1405375Y453561D03*
X1405608Y456761D03*
X1411900Y434775D03*
X1435479Y423107D03*
X1439350Y406900D03*
X1459200Y459800D03*
Y454100D03*
X1459000Y449997D03*
X1451400Y454100D03*
Y459800D03*
X1445000Y437000D03*
X1429000Y437059D03*
X1444800Y442500D03*
X1444500Y448000D03*
X1429100Y453400D03*
X1429000Y448000D03*
Y442600D03*
X1448800Y427800D03*
X1412447Y416368D03*
X1412545Y421974D03*
X1413300Y454400D03*
X1413075Y457561D03*
X1448800Y416500D03*
X1464300Y404900D03*
X1439000Y423000D03*
X1464600Y428000D03*
X1459300Y430000D03*
X1464525Y420014D03*
X1464731Y432942D03*
X1445100Y431500D03*
X1459200Y465500D03*
X1451400D03*
X1408753Y527518D03*
X1415541Y489523D03*
X1416100Y483500D03*
X1415800Y477500D03*
Y495200D03*
X1420200Y520500D03*
X1447749Y485395D03*
X1439314Y477723D03*
X1439400Y483600D03*
X1439341Y489323D03*
X1453700Y501600D03*
X1458357Y523271D03*
X1461100Y523600D03*
X1439400Y494700D03*
X1409693Y560343D03*
X1412093D03*
X1410850Y564210D03*
X1410340Y570370D03*
X1407019Y557380D03*
X1412019D03*
X1409519D03*
X1406993Y560343D03*
X1447852Y575687D03*
X1445800Y574300D03*
X1445750Y539000D03*
X1461500Y540000D03*
X1439861Y540497D03*
X1461653Y580762D03*
X1461707Y583162D03*
X1461878Y585556D03*
X1441805Y570887D03*
X1443797Y572482D03*
X1422500Y579800D03*
X1414800D03*
X1461930Y587956D03*
X1409500Y538000D03*
X1420500Y549800D03*
X1420400Y538000D03*
X1462039Y590354D03*
X1462155Y592761D03*
X1465334Y618564D03*
X1451314Y623298D03*
X1458000Y623400D03*
X1455000D03*
X1461000D03*
X1442200D03*
X1445200D03*
X1448200D03*
X1463419Y606912D03*
X1527700Y6963D03*
X1506900Y3500D03*
X1469807Y2967D03*
X1473674Y2953D03*
X1476712Y13466D03*
X1467264Y13533D03*
X1492900Y4000D03*
X1489600D03*
X1495611Y13466D03*
X1486162Y13500D03*
X1470414Y34830D03*
X1479863D03*
X1497711Y34427D03*
X1489311Y34830D03*
X1499613Y84046D03*
X1515294Y91306D03*
X1523563Y93565D03*
X1511700Y84600D03*
X1482300Y118400D03*
X1469747Y148276D03*
X1483093Y130796D03*
X1523950Y104050D03*
X1523889Y99033D03*
X1523557Y116165D03*
X1523813Y120546D03*
X1523756Y108762D03*
X1501603Y108500D03*
X1499618Y124520D03*
X1497699Y112140D03*
X1511634Y121195D03*
X1511635Y114535D03*
X1511650Y109400D03*
Y103400D03*
X1511651Y98675D03*
X1500775Y98101D03*
X1501700Y103300D03*
X1513023Y140630D03*
X1511664Y133603D03*
X1488350Y149450D03*
X1523719Y149488D03*
X1499800Y199300D03*
X1491196Y218527D03*
X1523400Y217900D03*
X1483523Y181100D03*
X1517328Y186208D03*
X1527500Y167726D03*
X1502192Y164871D03*
X1494783Y177907D03*
X1469150Y242931D03*
X1479500Y238500D03*
X1498685Y224715D03*
X1491700Y241661D03*
X1491407Y258353D03*
X1523470Y242580D03*
X1472500Y341074D03*
X1526722Y295400D03*
X1501583Y339389D03*
X1521817Y330937D03*
X1526000Y341000D03*
X1517600Y320940D03*
X1487426Y330100D03*
X1514722Y293257D03*
X1515482Y280800D03*
X1512300Y280847D03*
X1511900Y287500D03*
X1472550Y397500D03*
X1470800Y402250D03*
X1472680Y380630D03*
X1483172Y351806D03*
X1474500Y365500D03*
X1478500D03*
X1483500D03*
X1482000Y395098D03*
Y399035D03*
Y383287D03*
Y387224D03*
X1473255Y376254D03*
X1528146Y349842D03*
X1519626Y365817D03*
X1488394Y365466D03*
X1497275Y401174D03*
X1508975D03*
X1483950Y401650D03*
X1491425Y391034D03*
X1503125Y377514D03*
X1491425D03*
X1526525D03*
X1514825D03*
X1526525Y384274D03*
Y391034D03*
X1514825Y384274D03*
X1520675Y387654D03*
Y380894D03*
X1514825Y391034D03*
X1508975Y387654D03*
Y380894D03*
X1503125Y384274D03*
Y391034D03*
X1497275Y380894D03*
X1491425Y384274D03*
X1497275Y387654D03*
Y394414D03*
X1491425Y397794D03*
X1503125D03*
X1508975Y394414D03*
X1514825Y397794D03*
X1524575Y401174D03*
X1491425Y418074D03*
X1487525D03*
X1472449Y439421D03*
X1467000Y454100D03*
Y459800D03*
X1466800Y449997D03*
X1467401Y411557D03*
X1471900Y406900D03*
X1472530Y432731D03*
X1472400Y428063D03*
X1472800Y420689D03*
X1467000Y465500D03*
X1482000Y418720D03*
Y406909D03*
Y410846D03*
Y414783D03*
Y422658D03*
Y426595D03*
X1483400Y438100D03*
X1482603Y442418D03*
X1482000Y462028D03*
X1483115Y454379D03*
X1483200Y450455D03*
X1482500Y434600D03*
X1503125Y404554D03*
X1509200Y413600D03*
X1510925Y404554D03*
X1497275Y414694D03*
X1503125Y424834D03*
X1497275Y428214D03*
X1495325Y424834D03*
X1503125Y433406D03*
X1491425D03*
X1495325D03*
X1524950Y419900D03*
X1518650D03*
X1483818Y430597D03*
X1528100Y410550D03*
X1501219Y416596D03*
X1487525Y404554D03*
X1526525D03*
X1515500Y416750D03*
X1518700Y406500D03*
X1491425Y404554D03*
X1495325Y411314D03*
X1512350Y445100D03*
X1509200D03*
Y454550D03*
X1512400Y454500D03*
X1503125Y440166D03*
X1501175Y436786D03*
X1495325Y440166D03*
X1497275Y436786D03*
X1510925Y460446D03*
X1505442Y443900D03*
X1507025Y460446D03*
X1503125Y453786D03*
Y460446D03*
X1501175Y457066D03*
X1487525Y453686D03*
X1497275Y457066D03*
Y450306D03*
X1495325Y446926D03*
Y453686D03*
X1497275Y443546D03*
X1501175Y463826D03*
X1493375D03*
X1515500Y445100D03*
X1514825Y460446D03*
X1520675Y457066D03*
X1518725Y460446D03*
X1521800Y441950D03*
Y448250D03*
X1526525Y460446D03*
X1522625D03*
X1524950Y441950D03*
X1473140Y525407D03*
X1482000Y481713D03*
Y469902D03*
X1476800Y498900D03*
X1482300D03*
X1476800Y507300D03*
X1481700Y524200D03*
X1473800Y495800D03*
X1499225Y480726D03*
X1508975Y477346D03*
X1510925Y480726D03*
X1508975Y470586D03*
X1510925Y473966D03*
X1505075Y470586D03*
X1501175D03*
X1503125Y467206D03*
X1507025Y487486D03*
X1487525Y473966D03*
X1491425D03*
X1489475Y470586D03*
X1490100Y489700D03*
X1487525Y487486D03*
X1489475Y484106D03*
X1516775D03*
X1514825Y480726D03*
Y473966D03*
X1516775Y470586D03*
X1518725Y487486D03*
Y480726D03*
Y473966D03*
Y467206D03*
X1522625D03*
Y473966D03*
Y487486D03*
X1526525D03*
Y473966D03*
Y467206D03*
X1514825Y487486D03*
X1511752Y498780D03*
X1490929Y507104D03*
X1506060Y508180D03*
X1501490Y504988D03*
X1501934Y513047D03*
X1505743Y516117D03*
X1511215Y507781D03*
X1512400Y519020D03*
X1493930Y522800D03*
X1488410Y517810D03*
X1497267Y505323D03*
X1496174Y514221D03*
X1509000Y498750D03*
X1488500Y498900D03*
X1526500Y498671D03*
Y506400D03*
X1485300Y498962D03*
X1483804Y509928D03*
X1484200Y524200D03*
X1475316Y527194D03*
X1468101Y573963D03*
X1527698Y578870D03*
X1474776Y572315D03*
X1491776Y573571D03*
X1479893Y572315D03*
X1482293D03*
X1477493D03*
X1487093D03*
X1489493D03*
X1484693D03*
X1518000Y562330D03*
X1510740Y557860D03*
X1494422Y574000D03*
X1481400Y539700D03*
X1494200Y530600D03*
X1497106Y531368D03*
X1511388Y531045D03*
X1503200Y530500D03*
X1505600D03*
X1508772Y530416D03*
X1514118Y530411D03*
X1483900Y539700D03*
X1525500Y582674D03*
Y580184D03*
X1525837Y574700D03*
X1523416Y573949D03*
X1527822Y576130D03*
X1525500Y577684D03*
X1499900Y574000D03*
X1496900D03*
X1469701Y599554D03*
X1470353Y592128D03*
X1469767Y596353D03*
X1503008Y620018D03*
X1472412Y596032D03*
Y599532D03*
X1479029Y596132D03*
X1477129Y597656D03*
X1474912Y596032D03*
X1480760Y611602D03*
X1485429Y597571D03*
X1491412Y596032D03*
X1489229Y597571D03*
X1487329Y596032D03*
X1512500Y598639D03*
X1510450Y597300D03*
X1507950D03*
X1510450Y600800D03*
X1508031Y599922D03*
X1524800Y598778D03*
X1522900Y597300D03*
X1526950D03*
X1518800Y597200D03*
X1520813Y598508D03*
X1516800Y598639D03*
X1514500Y597300D03*
X1511350Y613000D03*
X1513867Y612939D03*
X1516367D03*
X1475812Y611732D03*
X1474912Y599532D03*
X1478329Y611671D03*
X1483104Y596072D03*
X1481229Y597571D03*
X1584447Y-6702D03*
X1579447D03*
X1570200Y12900D03*
X1579773Y13257D03*
X1589259Y10241D03*
X1541400Y12500D03*
X1528384Y28040D03*
X1551309Y12792D03*
X1560700Y13000D03*
X1589500Y-600D03*
X1589900Y84422D03*
X1583621Y87213D03*
X1588700Y94288D03*
X1573473Y37216D03*
X1582923D03*
X1532800Y78590D03*
X1542179Y39695D03*
X1554573Y37216D03*
X1564023D03*
X1578000Y113000D03*
X1585500Y101000D03*
X1555000Y139000D03*
X1548955Y101358D03*
X1558189Y107067D03*
X1554800Y129100D03*
Y98200D03*
X1558100D03*
X1558383Y121500D03*
X1554945Y133400D03*
X1583600Y207495D03*
X1535399Y190920D03*
X1533132Y158068D03*
X1531565Y176645D03*
X1537298Y162703D03*
X1557634Y175948D03*
X1562079Y163580D03*
X1530200Y257200D03*
X1528460Y244371D03*
X1563440Y250955D03*
X1559577Y236300D03*
X1547000Y263500D03*
Y269400D03*
X1541000Y263500D03*
Y269500D03*
X1544000Y266500D03*
X1578630Y293430D03*
X1580150Y329483D03*
X1528250Y311900D03*
X1530033Y340799D03*
X1539400Y320200D03*
X1544904Y334008D03*
X1557250Y315410D03*
X1554800Y290600D03*
X1586400Y392900D03*
X1567475Y380894D03*
Y387654D03*
X1582420Y377830D03*
X1582350Y374567D03*
X1582124Y381164D03*
X1573000Y391161D03*
X1571366Y401154D03*
X1582000Y396250D03*
X1567475Y394414D03*
X1570672Y362134D03*
X1567121Y365817D03*
X1576380Y362890D03*
X1582500Y369600D03*
X1573521Y365500D03*
X1532375Y380894D03*
Y387654D03*
Y394414D03*
X1538225Y377514D03*
Y384274D03*
X1544075Y380894D03*
Y387654D03*
X1538225Y391034D03*
Y397794D03*
X1544075Y394414D03*
X1558996Y365817D03*
X1555775Y394414D03*
X1549925Y397794D03*
X1561625D03*
X1555775Y401174D03*
X1549925Y377514D03*
X1561625D03*
Y391034D03*
Y384274D03*
X1549925Y391034D03*
Y384274D03*
X1555775Y387654D03*
Y380894D03*
X1571375Y421454D03*
X1569425Y418074D03*
X1571375Y414694D03*
X1559675Y463826D03*
X1563575Y421454D03*
X1557725Y424834D03*
X1567475Y450306D03*
X1565525Y440166D03*
X1571375Y457066D03*
X1567475D03*
X1569425Y460446D03*
X1582200Y456200D03*
X1565525Y431594D03*
X1569425D03*
Y404554D03*
X1583208Y412815D03*
X1569425Y411314D03*
X1571390Y464480D03*
X1567475Y421454D03*
X1531250Y419900D03*
Y451400D03*
Y441950D03*
X1530425Y460446D03*
X1551875Y407934D03*
Y414694D03*
X1563575Y407934D03*
X1559675Y414694D03*
X1546025Y404554D03*
X1561625Y424834D03*
X1551990Y421158D03*
X1551875Y428214D03*
X1561625Y431594D03*
X1563575Y428214D03*
X1555775Y443546D03*
Y436786D03*
X1563575Y457066D03*
X1549938Y453714D03*
X1547975Y457066D03*
X1549925Y446926D03*
X1557725D03*
X1561625Y460446D03*
X1555775Y457066D03*
X1551875D03*
X1557725Y453686D03*
X1559675Y443546D03*
Y436786D03*
X1547975Y463826D03*
X1551875D03*
X1555775D03*
X1534400Y419900D03*
X1540700D03*
X1543850Y429350D03*
Y426200D03*
X1537550Y419900D03*
X1534325Y404554D03*
X1538225D03*
X1542125D03*
X1540700Y410450D03*
X1534400Y451400D03*
Y441950D03*
X1537550D03*
X1534325Y460446D03*
X1537550Y451400D03*
X1544075Y457066D03*
X1540175D03*
X1540700Y451400D03*
Y441950D03*
X1540175Y463826D03*
X1543850Y435650D03*
X1537550D03*
X1582644Y495077D03*
X1568600Y494500D03*
X1565210Y509160D03*
X1567817Y499735D03*
X1569425Y473966D03*
X1571375Y470586D03*
X1565525Y480726D03*
X1570062Y487039D03*
X1587970Y472370D03*
X1587433Y490425D03*
X1567475Y470586D03*
X1532375D03*
X1530425Y473966D03*
X1528475Y470586D03*
Y477346D03*
X1534180Y498580D03*
X1534039Y502906D03*
X1531580Y510790D03*
X1534325Y487486D03*
X1536275Y484106D03*
X1544075Y470586D03*
X1542125Y473966D03*
X1540175Y477346D03*
X1536275Y470586D03*
X1544075Y477346D03*
X1538225Y473966D03*
X1542475Y504400D03*
X1542425Y512200D03*
X1546025Y467206D03*
X1553825Y487486D03*
Y480726D03*
X1557725D03*
X1549925Y473966D03*
X1547975Y470586D03*
X1553825Y473966D03*
Y467206D03*
X1555775Y470586D03*
X1557725Y473966D03*
X1555775Y477346D03*
Y484106D03*
X1549925Y487486D03*
X1546025Y480726D03*
X1548300Y499000D03*
X1564600Y500414D03*
X1555424Y504609D03*
X1555832Y512288D03*
X1548300Y506600D03*
X1580360Y565524D03*
X1580400Y568000D03*
X1580300Y563000D03*
Y560500D03*
X1566000Y575820D03*
X1565940Y573120D03*
X1565800Y570600D03*
X1565600Y568100D03*
Y565700D03*
X1529944Y574725D03*
X1529894Y577342D03*
X1532354Y577283D03*
X1532642Y579853D03*
X1529600Y582300D03*
X1532400D03*
X1529942Y579853D03*
X1563800Y564100D03*
X1561300Y564000D03*
X1558800Y563900D03*
X1563448Y566766D03*
X1563432Y569340D03*
X1589604Y585896D03*
X1581704D03*
X1587504Y605496D03*
Y607996D03*
X1563827Y621376D03*
X1554800Y620910D03*
X1537711Y613397D03*
X1538679Y615641D03*
X1534928Y610532D03*
X1538337Y601097D03*
X1534948Y613302D03*
X1545000Y591100D03*
X1581704Y590196D03*
X1589604D03*
X1558800Y599300D03*
X1560400Y611600D03*
X1564300Y599400D03*
X1564400Y605500D03*
X1561700Y602200D03*
X1552400Y607600D03*
X1554900Y607100D03*
X1556200Y602400D03*
X1554400Y599300D03*
X1564300Y611500D03*
X1602504Y-17346D03*
X1646200Y5300D03*
X1646400Y13400D03*
X1597700Y9000D03*
X1615000Y12000D03*
X1634200Y9700D03*
X1627500Y11700D03*
X1608123Y13302D03*
X1619100Y6500D03*
X1626400Y4600D03*
X1606700D03*
X1636500D03*
X1591270Y93940D03*
X1592200Y37700D03*
X1590464Y77962D03*
X1637700Y67400D03*
X1639623Y38100D03*
X1649073Y38200D03*
X1620050Y35550D03*
X1608500Y72688D03*
X1606730Y84230D03*
X1632000Y83000D03*
X1625451Y84288D03*
X1605184Y61044D03*
X1610450Y37300D03*
X1627380Y36652D03*
X1630121Y37609D03*
X1595943Y71522D03*
X1603138Y65890D03*
X1602840Y37382D03*
X1635900Y83000D03*
X1595335Y98135D03*
X1641600Y96500D03*
X1638500D03*
X1595522Y127278D03*
X1650300Y195251D03*
X1648400Y214100D03*
X1643887Y181841D03*
X1604401Y213500D03*
X1618500Y181680D03*
X1625524Y184531D03*
X1635100Y182800D03*
X1620036Y196186D03*
X1635112Y195181D03*
X1605250Y197250D03*
X1591174Y225017D03*
X1640871Y235210D03*
X1608489Y252095D03*
X1635503Y340146D03*
X1629503D03*
X1603307Y393224D03*
X1591912Y391052D03*
X1650624Y357884D03*
X1650480Y368215D03*
X1642126Y357894D03*
X1642114Y368142D03*
X1601060Y401010D03*
X1599100Y399100D03*
X1610828Y381387D03*
X1596151D03*
X1596168Y375135D03*
X1609761Y372584D03*
X1613474Y391105D03*
X1620447Y373926D03*
X1610642Y375135D03*
X1608020Y356500D03*
X1619889Y352841D03*
X1607443Y398649D03*
X1629503Y346146D03*
X1635503Y346046D03*
X1632503Y343146D03*
X1621010Y435870D03*
X1620500Y463727D03*
X1634500Y418500D03*
X1603650Y415469D03*
X1646540Y441240D03*
X1604200Y464387D03*
X1594880Y494880D03*
X1646700Y480300D03*
X1639394Y507798D03*
X1627032Y510226D03*
X1627068Y512626D03*
X1606200Y487100D03*
X1623814Y471400D03*
X1614000Y469500D03*
X1617700Y489700D03*
X1615200D03*
X1611506Y474768D03*
X1620500Y475000D03*
X1603500Y495300D03*
X1597178Y472226D03*
X1599900Y487100D03*
X1603802Y487205D03*
X1629530Y496374D03*
X1644800Y532800D03*
X1636848Y533794D03*
X1649900Y583500D03*
X1638674Y556178D03*
X1622040Y554827D03*
X1609829Y556599D03*
X1624293Y561747D03*
X1615030Y584260D03*
X1610080Y561367D03*
X1603060Y582920D03*
X1603120Y578020D03*
X1599170Y572780D03*
X1602000Y565700D03*
X1590004Y605496D03*
Y607996D03*
X1601504Y591526D03*
X1613721Y592325D03*
X1614700Y597000D03*
X1615862Y605507D03*
X1601489Y602812D03*
X1601270Y597200D03*
X1602150Y610720D03*
X1654800Y13518D03*
X1711863Y13276D03*
X1672427Y9700D03*
X1664200Y5400D03*
X1656600Y6300D03*
X1664823Y13287D03*
X1685500Y3000D03*
X1682985Y2901D03*
X1675800Y4100D03*
X1702421Y13231D03*
X1684902Y13472D03*
X1691541Y13226D03*
X1700710Y73292D03*
X1700300Y94703D03*
X1672000Y51500D03*
X1669350Y69962D03*
X1709600Y45800D03*
X1692573Y85833D03*
X1702513Y79885D03*
X1668009Y37000D03*
X1706500D03*
X1678000D03*
X1687500D03*
X1696795Y38260D03*
X1658559Y37890D03*
X1659038Y95111D03*
X1659000Y85500D03*
X1670250Y87873D03*
X1674455Y169991D03*
X1677605Y169986D03*
X1687950Y186150D03*
X1708250Y164950D03*
X1671556Y208379D03*
X1657498Y277300D03*
Y267100D03*
X1657949Y257240D03*
X1653091Y331618D03*
X1652991Y318741D03*
Y323941D03*
X1657500Y287800D03*
X1657600Y304500D03*
X1681192Y454286D03*
X1668000Y416200D03*
X1695658Y486945D03*
X1694410Y499830D03*
X1692120Y501410D03*
X1699900Y512300D03*
X1709400Y513000D03*
X1652500Y575600D03*
X1667277Y535221D03*
X1698600Y584800D03*
X1664113Y548380D03*
X1658466D03*
X1661880Y583900D03*
X1686036Y548251D03*
X1677300Y550200D03*
X1680007Y547917D03*
X1669121Y547923D03*
X1708140Y547538D03*
X1697839Y545759D03*
X1709183Y588700D03*
X1654100Y615790D03*
X1653970Y607340D03*
X1652700Y591300D03*
Y600850D03*
X1662580Y593200D03*
X1661200Y601300D03*
Y607300D03*
X1730550Y21160D03*
X1721559Y13500D03*
X1730768Y13313D03*
X1763100Y21500D03*
X1768807Y21512D03*
X1753903Y22116D03*
X1749941Y21163D03*
X1741000Y21200D03*
X1715259Y35602D03*
X1715100Y46100D03*
X1713550Y56000D03*
X1716900Y87900D03*
X1753059Y35300D03*
X1735150Y60650D03*
X1748500Y79500D03*
X1748854Y58533D03*
X1717600Y46100D03*
X1724758Y38600D03*
X1720600Y70200D03*
X1733910Y38233D03*
X1757054Y66059D03*
X1758100Y37000D03*
X1749364Y38971D03*
X1743500Y39300D03*
X1768450Y77376D03*
X1765900Y83700D03*
X1754703Y84053D03*
X1771459Y52695D03*
X1733900Y92200D03*
X1754600Y109200D03*
X1767250Y99500D03*
Y104500D03*
X1770850Y109500D03*
X1714189Y159550D03*
X1714528Y190189D03*
X1758650Y158650D03*
X1750189Y159550D03*
X1745689D03*
X1741189D03*
X1727689D03*
X1723189D03*
X1718689D03*
X1732189D03*
X1736689D03*
X1745777Y179574D03*
X1751975Y179374D03*
X1739377D03*
X1733178Y179574D03*
X1758375D03*
X1764673Y179374D03*
X1770973Y179574D03*
X1726700Y179400D03*
X1740900Y198800D03*
X1744000D03*
X1769100Y209700D03*
X1765950Y209600D03*
X1769016Y198872D03*
X1765866Y198772D03*
X1731260Y209600D03*
X1740709D03*
X1756000Y210000D03*
X1753400Y209900D03*
X1743900Y209700D03*
X1728616Y198872D03*
X1753311Y198700D03*
X1756600Y198800D03*
X1731216Y198872D03*
X1763554Y237712D03*
X1762795Y232106D03*
X1772244D03*
X1752554Y237712D03*
X1771451D03*
X1724944Y250324D03*
X1727444D03*
X1771243Y250100D03*
X1729944Y250324D03*
X1768516Y249983D03*
X1744603Y232489D03*
X1753347Y232106D03*
X1763300Y250100D03*
X1766100Y447900D03*
X1762992Y447938D03*
X1740963Y448476D03*
X1753543Y448100D03*
X1750393Y448037D03*
X1737795Y448100D03*
X1722000Y513000D03*
X1742900Y485000D03*
X1734000Y488100D03*
X1755000Y485000D03*
X1748600D03*
X1749396Y493969D03*
X1751868Y494045D03*
X1770325Y490255D03*
X1773500Y472100D03*
X1767300Y472700D03*
X1765325Y490255D03*
X1758500Y493800D03*
X1760900Y472800D03*
X1772459Y467005D03*
X1769309D03*
X1759860D03*
X1756710D03*
X1747262D03*
X1744112D03*
X1734663D03*
X1729200Y519000D03*
X1733830Y502650D03*
X1768900Y521124D03*
X1749090Y513790D03*
X1740400Y496300D03*
X1726600Y519000D03*
X1728700Y502600D03*
X1713600Y513000D03*
X1756417Y563840D03*
X1746000Y574000D03*
X1718000Y587723D03*
X1749000Y552863D03*
X1769000Y576378D03*
X1742381Y585530D03*
X1730814Y568814D03*
X1733000Y560000D03*
X1767455Y571695D03*
X1767000Y563500D03*
X1728245Y585244D03*
X1746052Y614796D03*
X1724092Y618700D03*
X1772158Y610960D03*
X1750739Y618718D03*
X1742509Y595869D03*
X1742381Y591530D03*
X1763500Y599100D03*
X1727843Y597142D03*
X1732443Y592342D03*
Y597142D03*
X1727743Y592342D03*
X1832449Y-8950D03*
X1785612Y10729D03*
X1782371Y26832D03*
X1804508Y11858D03*
X1798676Y11726D03*
X1830344Y13397D03*
X1828824Y3699D03*
X1816693Y13331D03*
X1819800Y35500D03*
X1790700Y34900D03*
X1799774Y34890D03*
X1808444Y37152D03*
X1800000Y80000D03*
X1827000Y87000D03*
X1834300Y41100D03*
X1788200Y93000D03*
Y89000D03*
Y85000D03*
X1818383Y133277D03*
X1788448Y98820D03*
X1788648Y101490D03*
X1807745Y104500D03*
X1803400Y114000D03*
X1796059Y104402D03*
X1801366Y151937D03*
X1811348Y143448D03*
X1800264Y143789D03*
X1800000Y132627D03*
X1820648Y155537D03*
X1816348D03*
X1777172Y179374D03*
X1778466Y198772D03*
X1783572Y179574D03*
X1802369Y179374D03*
X1808769Y179574D03*
X1815000Y179300D03*
X1789870Y179374D03*
X1796170Y179574D03*
X1795348Y172037D03*
X1797848D03*
X1792748Y171937D03*
X1821367Y179574D03*
X1827565Y179174D03*
X1833388Y179500D03*
X1791150Y209600D03*
X1794300Y209700D03*
X1794216Y198872D03*
X1791066Y198772D03*
X1819457Y198872D03*
X1828700Y198800D03*
X1820349Y209586D03*
X1828950Y209600D03*
X1832274Y209734D03*
X1816266Y198772D03*
X1804166Y198472D03*
X1807751Y209586D03*
X1803072Y209728D03*
X1806821Y198600D03*
X1815670Y209728D03*
X1781700Y209700D03*
X1778550Y209600D03*
X1781616Y198872D03*
X1816348Y163437D03*
X1818500Y159500D03*
X1820648Y163437D03*
X1782452Y237712D03*
X1820281Y250498D03*
X1809281D03*
X1801384D03*
X1790383D03*
X1791141Y232106D03*
X1828936Y249900D03*
X1819488Y232106D03*
X1810040D03*
X1800591D03*
X1781693D03*
X1775590Y448100D03*
X1778740D03*
X1828600Y450100D03*
X1825984Y448030D03*
X1816535Y448300D03*
X1813385Y447945D03*
X1804000Y447900D03*
X1800787Y447943D03*
X1791338Y448400D03*
X1788189Y448300D03*
X1779700Y472100D03*
X1784525Y491830D03*
X1781907Y467005D03*
X1785057D03*
X1779303Y497246D03*
X1832301Y467005D03*
X1835550Y466870D03*
X1789774Y476403D03*
X1801500Y471055D03*
X1795164Y476406D03*
X1789525Y491830D03*
X1801125D03*
X1796125D03*
X1817325Y481320D03*
X1806600Y471055D03*
X1812325Y481320D03*
X1806975Y491630D03*
X1830220Y479950D03*
X1824960Y473980D03*
X1824125Y491830D03*
X1822852Y467005D03*
X1819702D03*
X1819125Y491830D03*
X1807104Y467005D03*
X1810254D03*
X1811975Y491630D03*
X1797655Y467005D03*
X1794505D03*
X1810508Y515900D03*
X1804000Y498176D03*
X1834540Y519600D03*
X1796400Y498000D03*
X1781510Y546362D03*
X1786500Y562200D03*
X1783700Y579200D03*
X1828800Y546500D03*
X1828700Y540252D03*
X1828900Y552300D03*
X1834000Y534900D03*
X1811704Y554341D03*
X1807600Y552047D03*
X1806200Y549200D03*
X1786900Y552500D03*
X1801200Y529800D03*
X1806200Y582900D03*
X1810387Y571435D03*
X1794000Y568800D03*
X1793320Y557968D03*
X1828700Y569474D03*
X1836281Y589122D03*
X1828800Y575600D03*
X1828875Y563674D03*
X1828824Y557663D03*
X1810385Y568821D03*
X1807958Y565690D03*
X1812452Y538501D03*
Y533601D03*
X1807852D03*
X1807752Y538501D03*
X1779000Y598900D03*
X1787500Y597791D03*
X1825014Y593695D03*
X1811500Y603500D03*
X1808152Y591601D03*
X1812852Y596401D03*
X1808252D03*
X1812852Y591601D03*
X1893094Y-10142D03*
X1838100Y3900D03*
X1889218Y43530D03*
Y53530D03*
X1846800Y95400D03*
X1847000Y86500D03*
X1848000Y56500D03*
X1850500D03*
X1890803Y63189D03*
X1884500Y79300D03*
X1882000D03*
X1895330Y64390D03*
X1877270Y63473D03*
X1880230Y76820D03*
X1879500Y79300D03*
X1880986Y53299D03*
X1860995Y84509D03*
X1856873Y91200D03*
X1856778Y87397D03*
X1864208Y87724D03*
X1864195Y84509D03*
X1864153Y91241D03*
X1860815Y91184D03*
X1875100Y51300D03*
X1872340Y147236D03*
X1895800Y149200D03*
X1885400Y147000D03*
X1878550Y99470D03*
X1882550D03*
X1894834Y139286D03*
X1863908Y140992D03*
X1878950Y137400D03*
X1871855Y104188D03*
X1856700Y110167D03*
X1869000Y153900D03*
X1887830Y102227D03*
X1852600Y97500D03*
X1887300Y121500D03*
X1850700Y156000D03*
X1875700Y115700D03*
Y121500D03*
X1881500Y115700D03*
Y121500D03*
Y127300D03*
X1887300D03*
X1875700D03*
X1887300Y115700D03*
X1846663Y153748D03*
X1839500Y212700D03*
X1857044Y186292D03*
X1863750Y163750D03*
X1868375Y171900D03*
X1846163Y168448D03*
X1886800Y210600D03*
X1871708Y213442D03*
X1854663Y158248D03*
X1846663D03*
X1852300Y252000D03*
X1858400Y251200D03*
X1843700Y253400D03*
X1839400Y450440D03*
X1838768Y454120D03*
X1847185Y454368D03*
X1860158Y450322D03*
X1864300Y447900D03*
X1882677Y447930D03*
X1895275Y454422D03*
X1898425Y447930D03*
Y454422D03*
X1845330Y466870D03*
X1843000Y505000D03*
X1857480Y466800D03*
X1861300D03*
X1881285Y467049D03*
X1849795Y493379D03*
X1850290Y486610D03*
X1872908Y471338D03*
X1870138Y485732D03*
X1852340Y509140D03*
X1877518Y527560D03*
X1889800Y580200D03*
X1878000Y539000D03*
X1861080Y537090D03*
X1842500Y534500D03*
X1844100Y551000D03*
X1848900Y545500D03*
X1878450Y548650D03*
X1870250Y541950D03*
X1896500Y555300D03*
X1879800Y579000D03*
X1858000Y574000D03*
X1870892Y583245D03*
X1874825Y564125D03*
X1859167Y559350D03*
X1894299Y557790D03*
X1906438Y-15968D03*
X1909406Y76790D03*
X1907986Y82393D03*
X1907929Y84793D03*
X1907907Y87223D03*
X1918379Y84788D03*
X1905501Y79790D03*
X1902796Y79820D03*
X1900100Y145100D03*
X1921199Y140499D03*
X1929711Y155759D03*
X1904136Y140160D03*
X1937000Y150000D03*
X1906871Y106049D03*
X1911231Y137097D03*
X1908715Y104512D03*
X1912100Y142600D03*
X1915030Y147250D03*
X1911440Y128840D03*
X1952440Y98520D03*
X1942637Y100877D03*
X1914152Y115928D03*
X1950983Y147344D03*
X1928100Y136078D03*
X1953200Y195530D03*
X1937100Y206800D03*
X1908967Y201609D03*
X1909186Y211906D03*
X1944500Y183900D03*
X1903524Y208156D03*
X1905074Y198163D03*
X1943200Y214800D03*
X1928400Y212500D03*
X1926000Y212400D03*
X1933898Y216707D03*
X1945156Y160236D03*
X1950994Y173745D03*
X1939316Y173600D03*
X1900740Y178720D03*
X1900700Y172990D03*
Y167290D03*
X1906440Y178720D03*
X1906500Y173100D03*
X1906400Y167290D03*
X1912190Y178870D03*
X1912230Y167330D03*
Y173030D03*
X1946105Y230344D03*
X1902909Y223195D03*
X1943517Y223637D03*
X1943800Y241800D03*
X1943900Y238500D03*
X1934750Y242700D03*
Y240300D03*
X1925600Y242700D03*
X1929000Y445800D03*
X1910500Y435600D03*
X1927100Y436200D03*
X1930100D03*
X1904724Y454422D03*
X1901574Y447930D03*
X1907500Y435600D03*
X1911023Y448400D03*
X1907874Y454422D03*
Y448400D03*
X1933100Y436200D03*
X1957100Y502990D03*
X1955790Y499790D03*
X1947380Y482450D03*
X1915100Y480050D03*
X1905010Y479410D03*
X1939000Y479400D03*
X1952500Y508000D03*
X1959260Y506010D03*
X1938410Y490650D03*
X1929480Y472880D03*
X1905000Y533900D03*
X1906050Y569100D03*
X1923600Y554200D03*
X1955400Y530500D03*
X1923600Y572300D03*
X1908400Y556800D03*
X1915593Y576807D03*
X1953500Y551900D03*
X1943300Y535700D03*
X1921800Y586100D03*
X1936770Y607210D03*
X1906200Y607800D03*
X1916050Y604450D03*
X1924000Y611391D03*
X1968179Y77969D03*
X1965679D03*
Y75369D03*
X1968179D03*
X1965679Y82969D03*
Y80469D03*
X1968179D03*
X1966212Y72897D03*
X1970679Y75369D03*
Y80469D03*
Y77969D03*
X1962800Y143700D03*
X1971200Y152500D03*
X1965400Y149700D03*
X1961472Y165760D03*
X1967817Y201029D03*
X1965900Y184600D03*
X1965057Y176447D03*
X1966542Y179606D03*
X1965973Y166190D03*
X1970270Y474640D03*
X1968870Y481710D03*
X1970500Y502720D03*
X1963500Y521000D03*
X1961500Y561700D03*
Y582700D03*
X1972700Y552700D03*
G54D31*
X1887327Y532541D03*
X1929453Y511202D03*
G54D22*
X320784Y203219D03*
X330948Y201258D03*
X401377Y28022D03*
X411416D03*
X401377Y65822D03*
X411416D03*
X401377Y529022D03*
X411416D03*
X401377Y566822D03*
X411416D03*
X428149Y28022D03*
X434842Y28268D03*
X421456Y35957D03*
X434842Y65822D03*
X428149D03*
X458640Y200596D03*
X428149Y529022D03*
X434842D03*
X428149Y566822D03*
X434842D03*
X970392Y203219D03*
X980556Y201258D03*
X1050985Y28022D03*
X1061024D03*
X1077757D03*
X1084450Y28098D03*
X1050985Y65822D03*
X1071064Y35957D03*
X1061024Y65822D03*
X1084450D03*
X1077757D03*
X1050985Y529022D03*
Y566822D03*
X1061024Y529022D03*
X1084450D03*
X1077757D03*
X1067716Y547907D03*
X1071064Y574757D03*
X1061024Y566822D03*
X1084450D03*
X1077757D03*
X1108248Y200596D03*
X1111631Y198327D03*
X1451753Y276753D03*
X1454902Y279902D03*
X1445454Y270454D03*
X1448603Y273603D03*
X1454902Y305098D03*
X1448603Y311397D03*
X1458051Y301949D03*
X1464351Y295649D03*
Y289351D03*
X1458051Y283051D03*
X1489546Y270454D03*
X1486397Y273603D03*
X1483247Y276753D03*
X1470649Y295649D03*
Y289351D03*
X1480098Y305098D03*
X1476949Y301949D03*
X1486397Y311397D03*
X1489546Y314546D03*
X1483247Y308247D03*
X1476949Y283051D03*
X1606470Y93759D03*
X1638938Y109192D03*
X1638250Y125750D03*
X1651536Y121790D03*
X1638938Y118641D03*
X1645378Y128378D03*
X1638902Y112305D03*
X1648430Y150163D03*
X1638937Y131239D03*
Y143837D03*
Y137538D03*
X1638938Y153286D03*
X1616900Y153200D03*
X1629489Y150136D03*
X1616891Y146987D03*
X1616893Y140782D03*
X1635788Y137538D03*
Y143837D03*
Y131239D03*
X1616891Y134389D03*
X1629489Y137538D03*
Y143837D03*
Y131239D03*
X1620040Y106042D03*
X1623189Y118640D03*
X1629489D03*
X1610793Y109190D03*
X1607441Y118640D03*
X1616891Y124939D03*
X1596220Y109470D03*
X1613741Y115491D03*
X1602717Y102240D03*
X1620040Y162735D03*
X1627998Y172854D03*
X1601142Y172185D03*
X1674685Y134217D03*
X1693625Y133220D03*
X1680402Y128652D03*
X1678127Y117293D03*
X1673883Y124308D03*
X1654685Y146987D03*
X1654678Y137530D03*
X1657835Y134389D03*
X1671000Y103000D03*
X1709000Y127200D03*
X1691207Y139891D03*
X1667284Y137537D03*
X1657835Y124940D03*
Y150136D03*
X1667284Y121790D03*
Y128089D03*
Y150136D03*
X1664134Y140688D03*
X1668213Y172608D03*
X1729444Y123782D03*
X1726294Y101785D03*
X1742212Y117451D03*
X1717014Y108000D03*
Y139500D03*
X1739064Y108000D03*
X1742214Y101700D03*
X1745364Y114300D03*
X1755089Y150750D03*
X1752189Y136750D03*
X1752389Y132250D03*
X1754189Y124250D03*
X1757689Y123850D03*
X1752889Y146250D03*
X1745364Y145800D03*
X1731903Y133712D03*
X1720164Y97550D03*
Y111150D03*
X1723314D03*
Y117450D03*
X1720164Y120600D03*
Y133200D03*
Y126800D03*
X1751800Y141700D03*
X1742214Y98550D03*
Y126900D03*
X1745364Y120600D03*
X1742214Y111150D03*
X1739064Y114300D03*
G54D13*
X-15748Y101221D03*
Y148465D03*
Y357362D03*
Y373110D03*
Y388858D03*
Y404606D03*
X12205Y156339D03*
X-4331D03*
X17323Y101221D03*
Y116969D03*
Y132717D03*
Y148465D03*
X787Y101221D03*
Y116969D03*
Y148465D03*
X33858Y101221D03*
Y116969D03*
Y132717D03*
Y148465D03*
X28740Y109095D03*
Y156339D03*
X12205Y109095D03*
Y140591D03*
X-4331Y109095D03*
Y124843D03*
Y140591D03*
X17323Y357362D03*
Y373110D03*
Y388858D03*
Y404606D03*
X787Y357362D03*
Y373110D03*
Y388858D03*
Y404606D03*
X33858Y357362D03*
Y373110D03*
Y388858D03*
Y404606D03*
X28740Y365236D03*
Y380984D03*
Y396732D03*
X12205Y365236D03*
Y380984D03*
Y396732D03*
X-4331Y365236D03*
Y380984D03*
Y396732D03*
X12205Y412480D03*
X-4331D03*
X28740D03*
G54D40*
G01X-9569Y-9569D02*
X0Y0D01*
G01D02*
X9569Y9569D01*
G01X-9569D02*
X0Y0D01*
G01D02*
X9569Y-9569D01*
G01X1602685Y292308D02*
X1613069Y302692D01*
G01D02*
X1623453Y313076D01*
G01X1602685D02*
X1613069Y302692D01*
G01D02*
X1623453Y292308D01*
X1961890Y211043D03*
Y238405D03*
G54D41*
G01X105174Y102925D02*
X107249Y105000D01*
G01D02*
X109324Y107075D01*
G01X105174D02*
X107249Y105000D01*
G01D02*
X109324Y102925D01*
G01X1562041Y-17959D02*
X1565000Y-15000D01*
G01D02*
X1567959Y-12041D01*
G01X1562041D02*
X1565000Y-15000D01*
G01D02*
X1567959Y-17959D01*
G01X1816918Y615916D02*
X1819665Y618663D01*
G01D02*
X1822412Y621410D01*
G01X1816918D02*
X1819665Y618663D01*
G01D02*
X1822412Y615916D01*
G01X1893410Y19119D02*
X1895945Y21654D01*
G01X1893410Y24189D02*
X1895945Y21654D01*
G01X1891282Y490182D02*
X1894100Y493000D01*
G01D02*
X1896918Y495818D01*
G01X1891282D02*
X1894100Y493000D01*
G01D02*
X1896918Y490182D01*
G01X1848892Y558642D02*
X1851250Y561000D01*
G01D02*
X1853608Y563358D01*
G01X1848892D02*
X1851250Y561000D01*
G01D02*
X1853608Y558642D01*
G01X1848892Y574390D02*
X1851250Y576748D01*
G01D02*
X1853608Y579106D01*
G01X1848892D02*
X1851250Y576748D01*
G01D02*
X1853608Y574390D01*
G01X1888268Y599287D02*
X1891086Y602105D01*
G01D02*
X1893904Y604923D01*
G01X1888268D02*
X1891086Y602105D01*
G01D02*
X1893904Y599287D01*
G01X1919960Y516040D02*
X1922248Y518328D01*
G01D02*
X1924536Y520616D01*
G01X1919960D02*
X1922248Y518328D01*
G01D02*
X1924536Y516040D01*
G01X1950115Y603067D02*
X1952756Y605708D01*
G01D02*
X1955397Y608349D01*
G01X1950115D02*
X1952756Y605708D01*
G01D02*
X1955397Y603067D01*
G54D32*
X1851250Y576748D03*
Y561000D03*
G54D14*
X30500Y-42250D03*
Y-52250D03*
X12290Y264640D03*
X18450Y267010D03*
X22970Y244400D03*
X28720Y244450D03*
X17120Y244220D03*
X24200Y267060D03*
X50500Y-42250D03*
X70500D03*
X90500D03*
X110500D03*
X50500Y-52250D03*
X70500D03*
X90500D03*
X110500D03*
X130500Y-42250D03*
Y-52250D03*
X457246Y-52301D03*
Y-42301D03*
X477246Y-52301D03*
Y-42301D03*
X497246Y-52301D03*
Y-42301D03*
X517246Y-52301D03*
Y-42301D03*
X537246Y-52301D03*
Y-42301D03*
X557246Y-52301D03*
Y-42301D03*
X788984Y-52057D03*
Y-42057D03*
X808984Y-52057D03*
Y-42057D03*
X828984Y-52057D03*
Y-42057D03*
X848984Y-52057D03*
Y-42057D03*
X868984Y-52057D03*
Y-42057D03*
X888984Y-52057D03*
Y-42057D03*
X1125583Y-52285D03*
Y-42285D03*
X1145583Y-52285D03*
Y-42285D03*
X1382258Y-52257D03*
Y-42257D03*
X1402258Y-52257D03*
Y-42257D03*
X1422258Y-52257D03*
Y-42257D03*
X1442258Y-52257D03*
Y-42257D03*
G54D23*
X1392264Y23976D03*
X1513918D03*
G54D42*
G01X1887327Y508300D02*
Y511202D01*
G01D02*
Y514104D01*
G01X1883225Y511202D02*
X1887327D01*
G01D02*
X1891429D01*
G01X1887327Y529639D02*
Y532541D01*
G01D02*
Y535443D01*
G01X1881825Y532541D02*
X1887327D01*
G01D02*
X1892829D01*
G01X1929453Y508300D02*
Y511202D01*
G01D02*
Y514104D01*
G01X1923951Y511202D02*
X1929453D01*
G01D02*
X1934955D01*
G54D33*
X1952756Y-14960D03*
Y58268D03*
G54D15*
X18228Y178386D03*
X-1969D03*
X44291D03*
G54D24*
X1526871Y23968D03*
X1819665Y618663D03*
X1881595Y23968D03*
G54D43*
G01X450600Y70900D02*
X450596Y70896D01*
X448651D01*
G01X451573Y73799D02*
X451363Y73589D01*
X448599D01*
G01X450500Y68100D02*
X450490Y68090D01*
X448627D01*
G54D34*
X1949650Y220787D03*
Y228661D03*
G54D25*
X1565000Y-15000D03*
X1723503Y-5000D03*
Y-15000D03*
X1753503Y-5000D03*
Y-15000D03*
G54D16*
X3937Y204370D03*
X-3937D03*
X-11811D03*
X35433D03*
X27559D03*
X19685D03*
X3937Y227992D03*
X-3937D03*
X-11811D03*
X35433D03*
X27559D03*
X19685D03*
X3937Y313504D03*
X-3937D03*
X-11811D03*
X3937Y337126D03*
X-3937D03*
X-11811D03*
X35433D03*
X27559D03*
X19685D03*
X35433Y313504D03*
X27559D03*
X19685D03*
G54D44*
G01X548049Y-193422D02*
Y-210922D01*
G01X543027Y-193422D02*
X553071D01*
G01X565549Y-199256D02*
Y-210922D01*
G01Y-194589D02*
X565112Y-194297D01*
Y-193714D01*
X565549Y-193422D01*
X565986Y-193714D01*
Y-194297D01*
X565549Y-194589D01*
G01X583049Y-210922D02*
X581739Y-210630D01*
X580429Y-209464D01*
X579555Y-207422D01*
X579119Y-205089D01*
X579555Y-202755D01*
X580429Y-200714D01*
X581739Y-199547D01*
X583049Y-199256D01*
X584359Y-199547D01*
X585669Y-200714D01*
X586542Y-202755D01*
X586761Y-205089D01*
X586542Y-207422D01*
X585669Y-209464D01*
X584359Y-210630D01*
X583049Y-210922D01*
G01X597492Y-215297D02*
X599021Y-216464D01*
X600767Y-216755D01*
X602295Y-216464D01*
X603606Y-215006D01*
X604479Y-212964D01*
Y-199256D01*
G01Y-201589D02*
X603606Y-200422D01*
X602295Y-199547D01*
X600767Y-199256D01*
X599021Y-199839D01*
X597929Y-201005D01*
X597055Y-203047D01*
X596619Y-205089D01*
X596837Y-206839D01*
X597711Y-208881D01*
X599021Y-210339D01*
X600767Y-210922D01*
X602077Y-210630D01*
X603606Y-209464D01*
X604479Y-208298D01*
G01X621979Y-210922D02*
Y-199256D01*
G01Y-201297D02*
X621106Y-200131D01*
X619795Y-199547D01*
X618267Y-199256D01*
X616739Y-199839D01*
X615429Y-201005D01*
X614555Y-202755D01*
X614119Y-205089D01*
X614555Y-207422D01*
X615429Y-209172D01*
X616739Y-210339D01*
X618267Y-210922D01*
X619795Y-210630D01*
X621106Y-209756D01*
X621979Y-208589D01*
G01X648682Y-210922D02*
Y-193422D01*
X653922D01*
X655669Y-194297D01*
X656979Y-196339D01*
X657416Y-198672D01*
X656979Y-201005D01*
X655887Y-202755D01*
X653922Y-203631D01*
X648682D01*
G01X674479Y-210922D02*
Y-199256D01*
G01Y-201297D02*
X673606Y-200131D01*
X672295Y-199547D01*
X670767Y-199256D01*
X669239Y-199839D01*
X667929Y-201005D01*
X667055Y-202755D01*
X666619Y-205089D01*
X667055Y-207422D01*
X667929Y-209172D01*
X669239Y-210339D01*
X670767Y-210922D01*
X672295Y-210630D01*
X673606Y-209756D01*
X674479Y-208589D01*
G01X684774Y-208881D02*
X685866Y-210047D01*
X687394Y-210922D01*
X688704D01*
X690014Y-210339D01*
X690887Y-209464D01*
X691324Y-208298D01*
X691106Y-206547D01*
X690232Y-205672D01*
X686302Y-203922D01*
X685429Y-201880D01*
X685866Y-200422D01*
X686739Y-199547D01*
X688049Y-199256D01*
X689359Y-199547D01*
X690669Y-200422D01*
G01X702274Y-208881D02*
X703366Y-210047D01*
X704894Y-210922D01*
X706204D01*
X707514Y-210339D01*
X708387Y-209464D01*
X708824Y-208298D01*
X708606Y-206547D01*
X707732Y-205672D01*
X703802Y-203922D01*
X702929Y-201880D01*
X703366Y-200422D01*
X704239Y-199547D01*
X705549Y-199256D01*
X706859Y-199547D01*
X708169Y-200422D01*
G01X735746Y-210922D02*
Y-193422D01*
X740112D01*
X741859Y-194297D01*
X743169Y-195464D01*
X744261Y-197213D01*
X745134Y-199256D01*
X745352Y-202172D01*
X745134Y-205089D01*
X744261Y-207131D01*
X743169Y-208881D01*
X741859Y-210047D01*
X740112Y-210922D01*
X735746D01*
G01X752590Y-193422D02*
X758049Y-210922D01*
X763508Y-193422D01*
G01X775549D02*
Y-210922D01*
G01X770527Y-193422D02*
X780571D01*
G01X804872Y-210922D02*
Y-193422D01*
X810549Y-208005D01*
X816226Y-193422D01*
Y-210922D01*
G01X829795Y-201589D02*
X830669Y-200714D01*
X831324Y-199256D01*
X831761Y-197213D01*
X831324Y-195464D01*
X830451Y-194297D01*
X828922Y-193422D01*
X823027D01*
Y-210922D01*
X830232D01*
X831761Y-209756D01*
X832634Y-208005D01*
X833071Y-205964D01*
X832634Y-203922D01*
X831324Y-202172D01*
X829795Y-201589D01*
X823027D01*
G01X647372Y-165922D02*
Y-148422D01*
X653049Y-163005D01*
X658726Y-148422D01*
Y-165922D01*
G01X670549D02*
X669239Y-165630D01*
X667929Y-164464D01*
X667055Y-162422D01*
X666619Y-160089D01*
X667055Y-157755D01*
X667929Y-155714D01*
X669239Y-154547D01*
X670549Y-154256D01*
X671859Y-154547D01*
X673169Y-155714D01*
X674042Y-157755D01*
X674261Y-160089D01*
X674042Y-162422D01*
X673169Y-164464D01*
X671859Y-165630D01*
X670549Y-165922D01*
G01X691979Y-148422D02*
Y-165922D01*
G01Y-163298D02*
X691106Y-164756D01*
X689795Y-165630D01*
X688267Y-165922D01*
X686521Y-165339D01*
X685211Y-163881D01*
X684337Y-162131D01*
X684119Y-160089D01*
X684337Y-158047D01*
X685211Y-156297D01*
X686521Y-154839D01*
X688267Y-154256D01*
X689795Y-154547D01*
X690887Y-155131D01*
X691979Y-156297D01*
G01X702274Y-158047D02*
X709261D01*
X708606Y-156005D01*
X707514Y-154839D01*
X705986Y-154256D01*
X704457Y-154547D01*
X703147Y-155422D01*
X702274Y-157464D01*
X701837Y-159214D01*
Y-160964D01*
X702274Y-162714D01*
X703366Y-164464D01*
X704676Y-165630D01*
X706204Y-165922D01*
X707732Y-165339D01*
X709261Y-163589D01*
G01X723049Y-165922D02*
Y-148422D01*
G01X975549Y-210922D02*
Y-193422D01*
X972929Y-196922D01*
G01Y-210922D02*
X978169D01*
G01X988246Y-208298D02*
X989555Y-209756D01*
X991084Y-210630D01*
X993049Y-210922D01*
X995014Y-210339D01*
X996542Y-209172D01*
X997634Y-207131D01*
X997852Y-204797D01*
X997416Y-202464D01*
X996324Y-201005D01*
X994795Y-199839D01*
X993267Y-199547D01*
X991739Y-199839D01*
X989774Y-201005D01*
X990429Y-193422D01*
X996324D01*
G01X1010549Y-210922D02*
Y-193422D01*
X1007929Y-196922D01*
G01Y-210922D02*
X1013169D01*
G01X1023901Y-196339D02*
X1025211Y-194589D01*
X1026739Y-193714D01*
X1028486Y-193422D01*
X1030669Y-194005D01*
X1032197Y-195464D01*
X1032634Y-197213D01*
X1032416Y-198964D01*
X1031542Y-200422D01*
X1027176Y-203339D01*
X1025211Y-205380D01*
X1023901Y-208298D01*
X1023464Y-210922D01*
X1032634D01*
G01X1041401Y-203631D02*
X1042929Y-201589D01*
X1044239Y-200422D01*
X1045986Y-199839D01*
X1047514Y-200422D01*
X1048606Y-201589D01*
X1049479Y-203339D01*
X1049697Y-205380D01*
X1049479Y-207131D01*
X1048606Y-208881D01*
X1047295Y-210339D01*
X1045767Y-210922D01*
X1044021Y-210339D01*
X1042492Y-208589D01*
X1041619Y-205964D01*
X1041401Y-203047D01*
X1041837Y-199256D01*
X1042492Y-197213D01*
X1043584Y-195172D01*
X1045112Y-193714D01*
X1046641Y-193422D01*
X1048169Y-194005D01*
X1049261Y-195464D01*
G01X962432Y-165922D02*
Y-148422D01*
X967672D01*
X969419Y-149297D01*
X970729Y-151339D01*
X971166Y-153672D01*
X970729Y-156005D01*
X969637Y-157755D01*
X967672Y-158631D01*
X962432D01*
G01X989102Y-149881D02*
X987792Y-149005D01*
X986264Y-148422D01*
X984517D01*
X982552Y-149297D01*
X981024Y-150755D01*
X979932Y-152506D01*
X979059Y-155422D01*
X978840Y-158047D01*
X979277Y-160672D01*
X979932Y-162422D01*
X981242Y-164172D01*
X982771Y-165339D01*
X984299Y-165922D01*
X985827D01*
X987356Y-165339D01*
X988666Y-164464D01*
X989758Y-163298D01*
G01X1003545Y-156589D02*
X1004419Y-155714D01*
X1005074Y-154256D01*
X1005511Y-152213D01*
X1005074Y-150464D01*
X1004201Y-149297D01*
X1002672Y-148422D01*
X996777D01*
Y-165922D01*
X1003982D01*
X1005511Y-164756D01*
X1006384Y-163005D01*
X1006821Y-160964D01*
X1006384Y-158922D01*
X1005074Y-157172D01*
X1003545Y-156589D01*
X996777D01*
G01X1012749Y-171755D02*
X1025849D01*
G01X1031777Y-165922D02*
Y-148422D01*
X1041821Y-165922D01*
Y-148422D01*
G01X1054299Y-165922D02*
X1052552Y-165630D01*
X1051024Y-164464D01*
X1049714Y-162714D01*
X1048840Y-160672D01*
X1048404Y-158339D01*
Y-156005D01*
X1048840Y-153672D01*
X1049714Y-151630D01*
X1051024Y-149881D01*
X1052552Y-148714D01*
X1054299Y-148422D01*
X1056045Y-148714D01*
X1057574Y-149881D01*
X1058884Y-151630D01*
X1059758Y-153672D01*
X1060194Y-156005D01*
Y-158339D01*
X1059758Y-160672D01*
X1058884Y-162714D01*
X1057574Y-164464D01*
X1056045Y-165630D01*
X1054299Y-165922D01*
G01X1128099Y-210922D02*
Y-193422D01*
X1125479Y-196922D01*
G01Y-210922D02*
X1130719D01*
G01X1147345Y-201589D02*
X1148219Y-200714D01*
X1148874Y-199256D01*
X1149311Y-197213D01*
X1148874Y-195464D01*
X1148001Y-194297D01*
X1146472Y-193422D01*
X1140577D01*
Y-210922D01*
X1147782D01*
X1149311Y-209756D01*
X1150184Y-208005D01*
X1150621Y-205964D01*
X1150184Y-203922D01*
X1148874Y-202172D01*
X1147345Y-201589D01*
X1140577D01*
G01X1105140Y-148422D02*
X1110599Y-165922D01*
X1116058Y-148422D01*
G01X1132466Y-165922D02*
X1123732D01*
Y-148422D01*
X1132466D01*
G01X1128972Y-156880D02*
X1123732D01*
G01X1141232Y-165922D02*
Y-148422D01*
X1146691D01*
X1148437Y-149297D01*
X1149529Y-150464D01*
X1149966Y-152797D01*
X1149529Y-155131D01*
X1148219Y-156589D01*
X1146691Y-157464D01*
X1141232D01*
G01X1146691D02*
X1149966Y-165922D01*
G01X1163099Y-166505D02*
X1162662Y-166214D01*
Y-165630D01*
X1163099Y-165339D01*
X1163536Y-165630D01*
Y-166214D01*
X1163099Y-166505D01*
G01X1238682Y-193422D02*
Y-210922D01*
X1247416D01*
G01X1256401Y-196339D02*
X1257711Y-194589D01*
X1259239Y-193714D01*
X1260986Y-193422D01*
X1263169Y-194005D01*
X1264697Y-195464D01*
X1265134Y-197213D01*
X1264916Y-198964D01*
X1264042Y-200422D01*
X1259676Y-203339D01*
X1257711Y-205380D01*
X1256401Y-208298D01*
X1255964Y-210922D01*
X1265134D01*
G01X1279359Y-202172D02*
X1283726D01*
Y-207422D01*
X1282416Y-209172D01*
X1280887Y-210339D01*
X1278704Y-210922D01*
X1276521Y-210339D01*
X1274992Y-209172D01*
X1273682Y-207422D01*
X1272809Y-205380D01*
X1272372Y-203047D01*
Y-201005D01*
X1272809Y-199256D01*
X1273682Y-197213D01*
X1274992Y-195464D01*
X1276302Y-194297D01*
X1278049Y-193422D01*
X1279577D01*
X1281324Y-194005D01*
X1282634Y-195172D01*
G01X1290527Y-210922D02*
Y-193422D01*
X1300571Y-210922D01*
Y-193422D01*
G01X1308246Y-210922D02*
Y-193422D01*
X1312612D01*
X1314359Y-194297D01*
X1315669Y-195464D01*
X1316761Y-197213D01*
X1317634Y-199256D01*
X1317852Y-202172D01*
X1317634Y-205089D01*
X1316761Y-207131D01*
X1315669Y-208881D01*
X1314359Y-210047D01*
X1312612Y-210922D01*
X1308246D01*
G01X1238682Y-148422D02*
Y-165922D01*
X1247416D01*
G01X1264479D02*
Y-154256D01*
G01Y-156297D02*
X1263606Y-155131D01*
X1262295Y-154547D01*
X1260767Y-154256D01*
X1259239Y-154839D01*
X1257929Y-156005D01*
X1257055Y-157755D01*
X1256619Y-160089D01*
X1257055Y-162422D01*
X1257929Y-164172D01*
X1259239Y-165339D01*
X1260767Y-165922D01*
X1262295Y-165630D01*
X1263606Y-164756D01*
X1264479Y-163589D01*
G01X1273464Y-171172D02*
X1274774Y-171755D01*
X1276521Y-171172D01*
X1277612Y-170006D01*
X1278486Y-168547D01*
X1279795Y-163881D01*
X1282634Y-154256D01*
G01X1275647D02*
X1279795Y-163881D01*
G01X1292274Y-158047D02*
X1299261D01*
X1298606Y-156005D01*
X1297514Y-154839D01*
X1295986Y-154256D01*
X1294457Y-154547D01*
X1293147Y-155422D01*
X1292274Y-157464D01*
X1291837Y-159214D01*
Y-160964D01*
X1292274Y-162714D01*
X1293366Y-164464D01*
X1294676Y-165630D01*
X1296204Y-165922D01*
X1297732Y-165339D01*
X1299261Y-163589D01*
G01X1309992Y-165922D02*
Y-154256D01*
G01Y-156589D02*
X1311084Y-155422D01*
X1312176Y-154547D01*
X1313704Y-154256D01*
X1314795Y-154547D01*
X1316106Y-155422D01*
G01X1380796Y-165922D02*
Y-148422D01*
X1385162D01*
X1386909Y-149297D01*
X1388219Y-150464D01*
X1389311Y-152213D01*
X1390184Y-154256D01*
X1390402Y-157172D01*
X1390184Y-160089D01*
X1389311Y-162131D01*
X1388219Y-163881D01*
X1386909Y-165047D01*
X1385162Y-165922D01*
X1380796D01*
G01X1399824Y-158047D02*
X1406811D01*
X1406156Y-156005D01*
X1405064Y-154839D01*
X1403536Y-154256D01*
X1402007Y-154547D01*
X1400697Y-155422D01*
X1399824Y-157464D01*
X1399387Y-159214D01*
Y-160964D01*
X1399824Y-162714D01*
X1400916Y-164464D01*
X1402226Y-165630D01*
X1403754Y-165922D01*
X1405282Y-165339D01*
X1406811Y-163589D01*
G01X1417324Y-163881D02*
X1418416Y-165047D01*
X1419944Y-165922D01*
X1421254D01*
X1422564Y-165339D01*
X1423437Y-164464D01*
X1423874Y-163298D01*
X1423656Y-161547D01*
X1422782Y-160672D01*
X1418852Y-158922D01*
X1417979Y-156880D01*
X1418416Y-155422D01*
X1419289Y-154547D01*
X1420599Y-154256D01*
X1421909Y-154547D01*
X1423219Y-155422D01*
G01X1438099Y-154256D02*
Y-165922D01*
G01Y-149589D02*
X1437662Y-149297D01*
Y-148714D01*
X1438099Y-148422D01*
X1438536Y-148714D01*
Y-149297D01*
X1438099Y-149589D01*
G01X1452542Y-170297D02*
X1454071Y-171464D01*
X1455817Y-171755D01*
X1457345Y-171464D01*
X1458656Y-170006D01*
X1459529Y-167964D01*
Y-154256D01*
G01Y-156589D02*
X1458656Y-155422D01*
X1457345Y-154547D01*
X1455817Y-154256D01*
X1454071Y-154839D01*
X1452979Y-156005D01*
X1452105Y-158047D01*
X1451669Y-160089D01*
X1451887Y-161839D01*
X1452761Y-163881D01*
X1454071Y-165339D01*
X1455817Y-165922D01*
X1457127Y-165630D01*
X1458656Y-164464D01*
X1459529Y-163298D01*
G01X1469387Y-165922D02*
Y-154256D01*
G01Y-157172D02*
X1470261Y-155714D01*
X1471571Y-154547D01*
X1473317Y-154256D01*
X1474845Y-154547D01*
X1476156Y-155714D01*
X1476811Y-157755D01*
Y-165922D01*
G01X1487324Y-158047D02*
X1494311D01*
X1493656Y-156005D01*
X1492564Y-154839D01*
X1491036Y-154256D01*
X1489507Y-154547D01*
X1488197Y-155422D01*
X1487324Y-157464D01*
X1486887Y-159214D01*
Y-160964D01*
X1487324Y-162714D01*
X1488416Y-164464D01*
X1489726Y-165630D01*
X1491254Y-165922D01*
X1492782Y-165339D01*
X1494311Y-163589D01*
G01X1505042Y-165922D02*
Y-154256D01*
G01Y-156589D02*
X1506134Y-155422D01*
X1507226Y-154547D01*
X1508754Y-154256D01*
X1509845Y-154547D01*
X1511156Y-155422D01*
G01X1426729Y-193422D02*
X1431969D01*
G01X1429349D02*
Y-210922D01*
G01X1426729D02*
X1431969D01*
G01X1441390Y-193422D02*
X1446849Y-210922D01*
X1452308Y-193422D01*
G01X1464349Y-210922D02*
Y-203047D01*
X1459982Y-193422D01*
G01X1468716D02*
X1464349Y-203047D01*
G01X1551799Y-193422D02*
X1550052Y-194005D01*
X1548742Y-195464D01*
X1547869Y-197213D01*
X1547214Y-199547D01*
X1546996Y-202172D01*
X1547214Y-204797D01*
X1547869Y-207131D01*
X1548742Y-208881D01*
X1550052Y-210339D01*
X1551799Y-210922D01*
X1553545Y-210339D01*
X1554856Y-208881D01*
X1555729Y-207131D01*
X1556384Y-204797D01*
X1556602Y-202172D01*
X1556384Y-199547D01*
X1555729Y-197213D01*
X1554856Y-195464D01*
X1553545Y-194005D01*
X1551799Y-193422D01*
G01X1565151Y-196339D02*
X1566461Y-194589D01*
X1567989Y-193714D01*
X1569736Y-193422D01*
X1571919Y-194005D01*
X1573447Y-195464D01*
X1573884Y-197213D01*
X1573666Y-198964D01*
X1572792Y-200422D01*
X1568426Y-203339D01*
X1566461Y-205380D01*
X1565151Y-208298D01*
X1564714Y-210922D01*
X1573884D01*
G01X1582869Y-211505D02*
X1590729Y-193422D01*
G01X1604299Y-210922D02*
Y-193422D01*
X1601679Y-196922D01*
G01Y-210922D02*
X1606919D01*
G01X1621799Y-193422D02*
X1620052Y-194005D01*
X1618742Y-195464D01*
X1617869Y-197213D01*
X1617214Y-199547D01*
X1616996Y-202172D01*
X1617214Y-204797D01*
X1617869Y-207131D01*
X1618742Y-208881D01*
X1620052Y-210339D01*
X1621799Y-210922D01*
X1623545Y-210339D01*
X1624856Y-208881D01*
X1625729Y-207131D01*
X1626384Y-204797D01*
X1626602Y-202172D01*
X1626384Y-199547D01*
X1625729Y-197213D01*
X1624856Y-195464D01*
X1623545Y-194005D01*
X1621799Y-193422D01*
G01X1635369Y-211505D02*
X1643229Y-193422D01*
G01X1652651Y-196339D02*
X1653961Y-194589D01*
X1655489Y-193714D01*
X1657236Y-193422D01*
X1659419Y-194005D01*
X1660947Y-195464D01*
X1661384Y-197213D01*
X1661166Y-198964D01*
X1660292Y-200422D01*
X1655926Y-203339D01*
X1653961Y-205380D01*
X1652651Y-208298D01*
X1652214Y-210922D01*
X1661384D01*
G01X1674299Y-193422D02*
X1672552Y-194005D01*
X1671242Y-195464D01*
X1670369Y-197213D01*
X1669714Y-199547D01*
X1669496Y-202172D01*
X1669714Y-204797D01*
X1670369Y-207131D01*
X1671242Y-208881D01*
X1672552Y-210339D01*
X1674299Y-210922D01*
X1676045Y-210339D01*
X1677356Y-208881D01*
X1678229Y-207131D01*
X1678884Y-204797D01*
X1679102Y-202172D01*
X1678884Y-199547D01*
X1678229Y-197213D01*
X1677356Y-195464D01*
X1676045Y-194005D01*
X1674299Y-193422D01*
G01X1691799Y-210922D02*
Y-193422D01*
X1689179Y-196922D01*
G01Y-210922D02*
X1694419D01*
G01X1708862D02*
X1709299Y-207131D01*
X1709954Y-203922D01*
X1710827Y-201005D01*
X1711919Y-197797D01*
X1713666Y-193422D01*
X1704932D01*
G01X1599496Y-165922D02*
Y-148422D01*
X1603862D01*
X1605609Y-149297D01*
X1606919Y-150464D01*
X1608011Y-152213D01*
X1608884Y-154256D01*
X1609102Y-157172D01*
X1608884Y-160089D01*
X1608011Y-162131D01*
X1606919Y-163881D01*
X1605609Y-165047D01*
X1603862Y-165922D01*
X1599496D01*
G01X1625729D02*
Y-154256D01*
G01Y-156297D02*
X1624856Y-155131D01*
X1623545Y-154547D01*
X1622017Y-154256D01*
X1620489Y-154839D01*
X1619179Y-156005D01*
X1618305Y-157755D01*
X1617869Y-160089D01*
X1618305Y-162422D01*
X1619179Y-164172D01*
X1620489Y-165339D01*
X1622017Y-165922D01*
X1623545Y-165630D01*
X1624856Y-164756D01*
X1625729Y-163589D01*
G01X1639299Y-148422D02*
Y-165922D01*
G01X1636242Y-154256D02*
X1642356D01*
G01X1653524Y-158047D02*
X1660511D01*
X1659856Y-156005D01*
X1658764Y-154839D01*
X1657236Y-154256D01*
X1655707Y-154547D01*
X1654397Y-155422D01*
X1653524Y-157464D01*
X1653087Y-159214D01*
Y-160964D01*
X1653524Y-162714D01*
X1654616Y-164464D01*
X1655926Y-165630D01*
X1657454Y-165922D01*
X1658982Y-165339D01*
X1660511Y-163589D01*
G36*
G01X1956463Y209274D02*
G02X1954500Y205493I-1963J-1381D01*
G01X1950000D01*
G02X1947600Y207893I0J2400D01*
G01Y210293D01*
G02X1952400I2400J0D01*
G01X1954500D01*
G02X1954986Y210243I-1J-2400D01*
G03X1956463Y209274I1904J1292D01*
G37*
G54D26*
X1647327Y-315D03*
G54D17*
X15512Y434094D03*
X119980Y145531D03*
G54D45*
G01X1969500Y95000D02*
Y100000D01*
G54D27*
X1613069Y302692D03*
G54D36*
X1952250Y240355D03*
G54D18*
X42724Y644684D03*
Y644656D03*
Y654684D03*
Y654656D03*
X67724Y644684D03*
Y644656D03*
Y654684D03*
Y654656D03*
X221656Y644656D03*
X196656D03*
X231446Y644756D03*
Y644784D03*
X221656Y644684D03*
X196656D03*
X221656Y654656D03*
X196656D03*
X231446Y654756D03*
Y654784D03*
X221656Y654684D03*
X196656D03*
X256446Y644756D03*
Y644784D03*
Y654756D03*
Y654784D03*
X409240Y644564D03*
X384240D03*
X418914Y644486D03*
Y644514D03*
X409240Y644536D03*
X384240D03*
X409240Y654564D03*
X384240D03*
X418914Y654486D03*
Y654514D03*
X409240Y654536D03*
X384240D03*
X443914Y644486D03*
Y644514D03*
Y654486D03*
Y654514D03*
X596707Y644293D03*
X571707D03*
X596708Y644266D03*
X571708D03*
X596707Y654293D03*
X571707D03*
X596708Y654266D03*
X571708D03*
X606462Y644245D03*
X631462D03*
X606462Y644217D03*
X631462D03*
X606462Y654245D03*
X631462D03*
X606462Y654217D03*
X631462D03*
X912351Y644245D03*
X887351D03*
X912351Y644273D03*
X887351D03*
X912351Y654245D03*
X887351D03*
X912351Y654273D03*
X887351D03*
X922116Y644206D03*
X947116D03*
X922116Y644234D03*
X947116D03*
X922116Y654206D03*
X947116D03*
X922116Y654234D03*
X947116D03*
X1200877Y644262D03*
Y644234D03*
Y654262D03*
Y654234D03*
X1225877Y644262D03*
X1235614Y644236D03*
X1260614D03*
X1235614Y644264D03*
X1260614D03*
X1225877Y644234D03*
Y654262D03*
X1235614Y654236D03*
X1260614D03*
X1235614Y654264D03*
X1260614D03*
X1225877Y654234D03*
X1514375Y644292D03*
Y644264D03*
Y654292D03*
Y654264D03*
X1539375Y644292D03*
Y644264D03*
Y654292D03*
Y654264D03*
G54D46*
G01X1611200Y117100D02*
X1609700D01*
G01X1612100Y111600D02*
Y113200D01*
G01X1616200Y117100D02*
X1617500D01*
G01X1615400Y117900D02*
Y119500D01*
G01X1616200Y113900D02*
X1617600D01*
G01X1615400Y113000D02*
Y111500D01*
G54D19*
X107249Y105000D03*
G54D37*
X1922248Y518328D03*
G54D28*
X1643803Y585591D03*
X1640850Y582835D03*
X1631992D03*
X1623134D03*
X1640850Y567874D03*
X1631992D03*
X1623134D03*
X1646756Y595039D03*
X1623134Y612756D03*
X1640850Y597795D03*
X1631992D03*
X1623134D03*
X1640850Y612756D03*
X1631992D03*
X1691047Y585591D03*
X1688094Y582835D03*
X1679236D03*
X1670378D03*
X1688094Y567874D03*
X1679236D03*
X1670378D03*
X1694000Y595039D03*
X1688094Y612756D03*
X1679236D03*
X1670378D03*
X1688094Y597795D03*
X1679236D03*
X1670378D03*
G54D38*
X1952756Y605708D03*
G54D29*
X1895945Y21654D03*
G54D39*
X1969883Y207007D03*
Y242441D03*
M02*
